G04 ================== begin FILE IDENTIFICATION RECORD ==================*
G04 Layout Name:  E:/<user>/9332_F0TG_MB_C/brd/0417/9332_F0TG_MB_C_V02_0417_0820.brd*
G04 Film Name:    gnd5*
G04 File Format:  Gerber RS274X*
G04 File Origin:  Cadence Allegro 17.2-S081*
G04 Origin Date:  Wed Apr 19 14:50:10 2023*
G04 *
G04 Layer:  DRAWING FORMAT/TITLE_BLOCK_A*
G04 Layer:  PIN/SPECIAL_DRILL*
G04 Layer:  VIA CLASS/GND5*
G04 Layer:  PIN/GND5*
G04 Layer:  MANUFACTURING/PHOTOPLOT_OUTLINE*
G04 Layer:  ETCH/GND5*
G04 Layer:  DRAWING FORMAT/TITLE_BLOCK*
G04 Layer:  DRAWING FORMAT/TITLE_DATA_GND5*
G04 *
G04 Offset:    (0.00 0.00)*
G04 Mirror:    No*
G04 Mode:      Negative*
G04 Rotation:  0*
G04 FullContactRelief:  No*
G04 UndefLineWidth:     6.00*
G04 ================== end FILE IDENTIFICATION RECORD ====================*
%FSLAX25Y25*MOIN*%
%IR0*IPPOS*OFA0.00000B0.00000*MIA0B0*SFA1.00000B1.00000*%
%ADD14C,.03*%
%ADD41C,.06*%
%ADD30C,.024*%
%ADD68C,.052*%
%ADD25C,.061*%
%AMMACRO54*
4,1,36,0.0,.01,
-.001736,.009848,
-.00342,.009397,
-.005,.00866,
-.006428,.00766,
-.00766,.006428,
-.00866,.005,
-.009397,.00342,
-.009848,.001736,
-.01,0.0,
-.009848,-.001736,
-.009397,-.00342,
-.00866,-.005,
-.00766,-.006428,
-.006428,-.00766,
-.005,-.00866,
-.00342,-.009397,
-.001736,-.009848,
0.0,-.01,
.001736,-.009848,
.00342,-.009397,
.005,-.00866,
.006428,-.00766,
.00766,-.006428,
.00866,-.005,
.009397,-.00342,
.009848,-.001736,
.01,0.0,
.009848,.001736,
.009397,.00342,
.00866,.005,
.00766,.006428,
.006428,.00766,
.005,.00866,
.00342,.009397,
.001736,.009848,
0.0,.01,
0.0*
%
%ADD54MACRO54*%
%ADD43C,.071*%
%ADD23C,.026*%
%ADD64C,.064*%
%AMMACRO28*
4,1,36,.0025,0.0,
.002462,.000434,
.002349,.000855,
.002165,.00125,
.001915,.001607,
.001607,.001915,
.00125,.002165,
.000855,.002349,
.000434,.002462,
0.0,.0025,
-.000434,.002462,
-.000855,.002349,
-.00125,.002165,
-.001607,.001915,
-.001915,.001607,
-.002165,.00125,
-.002349,.000855,
-.002462,.000434,
-.0025,0.0,
-.002462,-.000434,
-.002349,-.000855,
-.002165,-.00125,
-.001915,-.001607,
-.001607,-.001915,
-.00125,-.002165,
-.000855,-.002349,
-.000434,-.002462,
0.0,-.0025,
.000434,-.002462,
.000855,-.002349,
.00125,-.002165,
.001607,-.001915,
.001915,-.001607,
.002165,-.00125,
.002349,-.000855,
.002462,-.000434,
.0025,0.0,
135.*
%
%ADD28MACRO28*%
%ADD24C,.028*%
%AMMACRO19*
4,1,36,.0025,0.0,
.002462,.000434,
.002349,.000855,
.002165,.00125,
.001915,.001607,
.001607,.001915,
.00125,.002165,
.000855,.002349,
.000434,.002462,
0.0,.0025,
-.000434,.002462,
-.000855,.002349,
-.00125,.002165,
-.001607,.001915,
-.001915,.001607,
-.002165,.00125,
-.002349,.000855,
-.002462,.000434,
-.0025,0.0,
-.002462,-.000434,
-.002349,-.000855,
-.002165,-.00125,
-.001915,-.001607,
-.001607,-.001915,
-.00125,-.002165,
-.000855,-.002349,
-.000434,-.002462,
0.0,-.0025,
.000434,-.002462,
.000855,-.002349,
.00125,-.002165,
.001607,-.001915,
.001915,-.001607,
.002165,-.00125,
.002349,-.000855,
.002462,-.000434,
.0025,0.0,
180.*
%
%ADD19MACRO19*%
%AMMACRO17*
4,1,36,.0025,0.0,
.002462,.000434,
.002349,.000855,
.002165,.00125,
.001915,.001607,
.001607,.001915,
.00125,.002165,
.000855,.002349,
.000434,.002462,
0.0,.0025,
-.000434,.002462,
-.000855,.002349,
-.00125,.002165,
-.001607,.001915,
-.001915,.001607,
-.002165,.00125,
-.002349,.000855,
-.002462,.000434,
-.0025,0.0,
-.002462,-.000434,
-.002349,-.000855,
-.002165,-.00125,
-.001915,-.001607,
-.001607,-.001915,
-.00125,-.002165,
-.000855,-.002349,
-.000434,-.002462,
0.0,-.0025,
.000434,-.002462,
.000855,-.002349,
.00125,-.002165,
.001607,-.001915,
.001915,-.001607,
.002165,-.00125,
.002349,-.000855,
.002462,-.000434,
.0025,0.0,
225.*
%
%ADD17MACRO17*%
%AMMACRO10*
4,1,36,.0025,0.0,
.002462,.000434,
.002349,.000855,
.002165,.00125,
.001915,.001607,
.001607,.001915,
.00125,.002165,
.000855,.002349,
.000434,.002462,
0.0,.0025,
-.000434,.002462,
-.000855,.002349,
-.00125,.002165,
-.001607,.001915,
-.001915,.001607,
-.002165,.00125,
-.002349,.000855,
-.002462,.000434,
-.0025,0.0,
-.002462,-.000434,
-.002349,-.000855,
-.002165,-.00125,
-.001915,-.001607,
-.001607,-.001915,
-.00125,-.002165,
-.000855,-.002349,
-.000434,-.002462,
0.0,-.0025,
.000434,-.002462,
.000855,-.002349,
.00125,-.002165,
.001607,-.001915,
.001915,-.001607,
.002165,-.00125,
.002349,-.000855,
.002462,-.000434,
.0025,0.0,
270.*
%
%ADD10MACRO10*%
%AMMACRO83*
4,1,36,.003,0.0,
.002954,.000521,
.002819,.001026,
.002598,.0015,
.002298,.001928,
.001928,.002298,
.0015,.002598,
.001026,.002819,
.000521,.002954,
0.0,.003,
-.000521,.002954,
-.001026,.002819,
-.0015,.002598,
-.001928,.002298,
-.002298,.001928,
-.002598,.0015,
-.002819,.001026,
-.002954,.000521,
-.003,0.0,
-.002954,-.000521,
-.002819,-.001026,
-.002598,-.0015,
-.002298,-.001928,
-.001928,-.002298,
-.0015,-.002598,
-.001026,-.002819,
-.000521,-.002954,
0.0,-.003,
.000521,-.002954,
.001026,-.002819,
.0015,-.002598,
.001928,-.002298,
.002298,-.001928,
.002598,-.0015,
.002819,-.001026,
.002954,-.000521,
.003,0.0,
270.*
%
%ADD83MACRO83*%
%AMMACRO44*
4,1,36,-.0025,0.0,
-.002462,.000434,
-.002349,.000855,
-.002165,.00125,
-.001915,.001607,
-.001607,.001915,
-.00125,.002165,
-.000855,.002349,
-.000434,.002462,
0.0,.0025,
.000434,.002462,
.000855,.002349,
.00125,.002165,
.001607,.001915,
.001915,.001607,
.002165,.00125,
.002349,.000855,
.002462,.000434,
.0025,0.0,
.002462,-.000434,
.002349,-.000855,
.002165,-.00125,
.001915,-.001607,
.001607,-.001915,
.00125,-.002165,
.000855,-.002349,
.000434,-.002462,
0.0,-.0025,
-.000434,-.002462,
-.000855,-.002349,
-.00125,-.002165,
-.001607,-.001915,
-.001915,-.001607,
-.002165,-.00125,
-.002349,-.000855,
-.002462,-.000434,
-.0025,0.0,
180.*
%
%ADD44MACRO44*%
%AMMACRO32*
4,1,36,.003,0.0,
.002954,.000521,
.002819,.001026,
.002598,.0015,
.002298,.001928,
.001928,.002298,
.0015,.002598,
.001026,.002819,
.000521,.002954,
0.0,.003,
-.000521,.002954,
-.001026,.002819,
-.0015,.002598,
-.001928,.002298,
-.002298,.001928,
-.002598,.0015,
-.002819,.001026,
-.002954,.000521,
-.003,0.0,
-.002954,-.000521,
-.002819,-.001026,
-.002598,-.0015,
-.002298,-.001928,
-.001928,-.002298,
-.0015,-.002598,
-.001026,-.002819,
-.000521,-.002954,
0.0,-.003,
.000521,-.002954,
.001026,-.002819,
.0015,-.002598,
.001928,-.002298,
.002298,-.001928,
.002598,-.0015,
.002819,-.001026,
.002954,-.000521,
.003,0.0,
180.*
%
%ADD32MACRO32*%
%ADD22C,.074*%
%ADD20C,.0263*%
%AMMACRO82*
4,1,36,-.003,0.0,
-.002954,.000521,
-.002819,.001026,
-.002598,.0015,
-.002298,.001928,
-.001928,.002298,
-.0015,.002598,
-.001026,.002819,
-.000521,.002954,
0.0,.003,
.000521,.002954,
.001026,.002819,
.0015,.002598,
.001928,.002298,
.002298,.001928,
.002598,.0015,
.002819,.001026,
.002954,.000521,
.003,0.0,
.002954,-.000521,
.002819,-.001026,
.002598,-.0015,
.002298,-.001928,
.001928,-.002298,
.0015,-.002598,
.001026,-.002819,
.000521,-.002954,
0.0,-.003,
-.000521,-.002954,
-.001026,-.002819,
-.0015,-.002598,
-.001928,-.002298,
-.002298,-.001928,
-.002598,-.0015,
-.002819,-.001026,
-.002954,-.000521,
-.003,0.0,
270.*
%
%ADD82MACRO82*%
%ADD81C,.0435*%
%ADD67C,.075*%
%ADD62C,.06015*%
%ADD48C,.066*%
%ADD51C,.076*%
%ADD50C,.095*%
%ADD34C,.03047*%
%ADD31C,.0248*%
%ADD75C,.087*%
%ADD35C,.03417*%
%AMMACRO13*
4,1,18,.09673,.06845,
.107147,.050613,
.114308,.031238,
.117996,.010914,
.118098,-.009741,
.114613,-.030101,
.107644,-.049546,
.097406,-.067485,
.09673,-.06845,
.10175,-.07347,
.112962,-.054685,
.120742,-.034239,
.124853,-.012752,
.125171,.009122,
.121685,.030719,
.114502,.051383,
.10384,.070486,
.10175,.07347,
.09673,.06845,
0.0*
4,1,18,.06845,-.09673,
.050613,-.107147,
.031238,-.114308,
.010914,-.117996,
-.009741,-.118098,
-.030101,-.114613,
-.049546,-.107644,
-.067485,-.097406,
-.06845,-.09673,
-.07347,-.10175,
-.054685,-.112962,
-.034239,-.120742,
-.012752,-.124853,
.009122,-.125171,
.030719,-.121685,
.051383,-.114502,
.070486,-.10384,
.07347,-.10175,
.06845,-.09673,
0.0*
4,1,18,-.09673,-.06845,
-.107147,-.050613,
-.114308,-.031238,
-.117996,-.010914,
-.118098,.009741,
-.114613,.030101,
-.107644,.049546,
-.097406,.067485,
-.09673,.06845,
-.10175,.07347,
-.112962,.054685,
-.120742,.034239,
-.124853,.012752,
-.125171,-.009122,
-.121685,-.030719,
-.114502,-.051383,
-.10384,-.070486,
-.10175,-.07347,
-.09673,-.06845,
0.0*
4,1,18,-.06845,.09673,
-.050613,.107147,
-.031238,.114308,
-.010914,.117996,
.009741,.118098,
.030101,.114613,
.049546,.107644,
.067485,.097406,
.06845,.09673,
.07347,.10175,
.054685,.112962,
.034239,.120742,
.012752,.124853,
-.009122,.125171,
-.030719,.121685,
-.051383,.114502,
-.070486,.10384,
-.07347,.10175,
-.06845,.09673,
0.0*
%
%ADD13MACRO13*%
%AMMACRO37*
4,1,16,.0711,.04282,
.077455,.029823,
.081457,.01592,
.082984,.001533,
.08199,-.0129,
.078504,-.026942,
.072633,-.040164,
.0711,-.04282,
.07619,-.04791,
.083352,-.033952,
.087981,-.018962,
.089937,-.003396,
.089161,.012273,
.085675,.027569,
.079586,.042027,
.07619,.04791,
.0711,.04282,
0.0*
4,1,16,.04282,-.0711,
.029823,-.077455,
.01592,-.081457,
.001533,-.082984,
-.0129,-.08199,
-.026942,-.078504,
-.040164,-.072633,
-.04282,-.0711,
-.04791,-.07619,
-.033952,-.083352,
-.018962,-.087981,
-.003396,-.089937,
.012273,-.089161,
.027569,-.085675,
.042027,-.079586,
.04791,-.07619,
.04282,-.0711,
0.0*
4,1,16,-.0711,-.04282,
-.077455,-.029823,
-.081457,-.01592,
-.082984,-.001533,
-.08199,.0129,
-.078504,.026942,
-.072633,.040164,
-.0711,.04282,
-.07619,.04791,
-.083352,.033952,
-.087981,.018962,
-.089937,.003396,
-.089161,-.012273,
-.085675,-.027569,
-.079586,-.042027,
-.07619,-.04791,
-.0711,-.04282,
0.0*
4,1,16,-.04282,.0711,
-.029823,.077455,
-.01592,.081457,
-.001533,.082984,
.0129,.08199,
.026942,.078504,
.040164,.072633,
.04282,.0711,
.04791,.07619,
.033952,.083352,
.018962,.087981,
.003396,.089937,
-.012273,.089161,
-.027569,.085675,
-.042027,.079586,
-.04791,.07619,
-.04282,.0711,
0.0*
%
%ADD37MACRO37*%
%AMMACRO65*
4,1,16,.02584,.01524,
.028094,.010521,
.029494,.005483,
.029998,.000278,
.029591,-.004935,
.028284,-.009999,
.026118,-.014758,
.02584,-.01524,
.03092,-.02032,
.033979,-.014642,
.036005,-.008519,
.036938,-.002138,
.036748,.004309,
.035441,.010625,
.033058,.016618,
.03092,.02032,
.02584,.01524,
90.*
4,1,16,.01524,-.02584,
.010521,-.028094,
.005483,-.029494,
.000278,-.029998,
-.004935,-.029591,
-.009999,-.028284,
-.014758,-.026118,
-.01524,-.02584,
-.02032,-.03092,
-.014642,-.033979,
-.008519,-.036005,
-.002138,-.036938,
.004309,-.036748,
.010625,-.035441,
.016618,-.033058,
.02032,-.03092,
.01524,-.02584,
90.*
4,1,16,-.02584,-.01524,
-.028094,-.010521,
-.029494,-.005483,
-.029998,-.000278,
-.029591,.004935,
-.028284,.009999,
-.026118,.014758,
-.02584,.01524,
-.03092,.02032,
-.033979,.014642,
-.036005,.008519,
-.036938,.002138,
-.036748,-.004309,
-.035441,-.010625,
-.033058,-.016618,
-.03092,-.02032,
-.02584,-.01524,
90.*
4,1,16,-.01524,.02584,
-.010521,.028094,
-.005483,.029494,
-.000278,.029998,
.004935,.029591,
.009999,.028284,
.014758,.026118,
.01524,.02584,
.02032,.03092,
.014642,.033979,
.008519,.036005,
.002138,.036938,
-.004309,.036748,
-.010625,.035441,
-.016618,.033058,
-.02032,.03092,
-.01524,.02584,
90.*
%
%ADD65MACRO65*%
%AMMACRO47*
4,1,15,.02438,.01377,
.026401,.009327,
.027619,.004601,
.027999,-.000265,
.027527,-.005123,
.02622,-.009825,
.02438,-.01377,
.02948,-.01887,
.032309,-.013464,
.034156,-.007649,
.034965,-.001602,
.034712,.004494,
.033405,.010454,
.031082,.016095,
.02948,.01887,
.02438,.01377,
90.*
4,1,15,.01377,-.02438,
.009327,-.026401,
.004601,-.027619,
-.000265,-.027999,
-.005123,-.027527,
-.009825,-.02622,
-.01377,-.02438,
-.01887,-.02948,
-.013464,-.032309,
-.007649,-.034156,
-.001602,-.034965,
.004494,-.034712,
.010454,-.033405,
.016095,-.031082,
.01887,-.02948,
.01377,-.02438,
90.*
4,1,15,-.02438,-.01377,
-.026401,-.009327,
-.027619,-.004601,
-.027999,.000265,
-.027527,.005123,
-.02622,.009825,
-.02438,.01377,
-.02948,.01887,
-.032309,.013464,
-.034156,.007649,
-.034965,.001602,
-.034712,-.004494,
-.033405,-.010454,
-.031082,-.016095,
-.02948,-.01887,
-.02438,-.01377,
90.*
4,1,15,-.01377,.02438,
-.009327,.026401,
-.004601,.027619,
.000265,.027999,
.005123,.027527,
.009825,.02622,
.01377,.02438,
.01887,.02948,
.013464,.032309,
.007649,.034156,
.001602,.034965,
-.004494,.034712,
-.010454,.033405,
-.016095,.031082,
-.01887,.02948,
-.01377,.02438,
90.*
%
%ADD47MACRO47*%
%AMMACRO16*
4,1,16,.07001,.04172,
.076191,.028929,
.080057,.015259,
.08149,.001126,
.080448,-.013042,
.076961,-.026814,
.071136,-.03977,
.07001,-.04172,
.0751,-.04682,
.082089,-.033068,
.086584,-.018311,
.088449,-.002997,
.087625,.012407,
.08414,.027435,
.078097,.041629,
.0751,.04682,
.07001,.04172,
0.0*
4,1,16,.04172,-.07001,
.028929,-.076191,
.015259,-.080057,
.001126,-.08149,
-.013042,-.080448,
-.026814,-.076961,
-.03977,-.071136,
-.04172,-.07001,
-.04682,-.0751,
-.033068,-.082089,
-.018311,-.086584,
-.002997,-.088449,
.012407,-.087625,
.027435,-.08414,
.041629,-.078097,
.04682,-.0751,
.04172,-.07001,
0.0*
4,1,16,-.07001,-.04172,
-.076191,-.028929,
-.080057,-.015259,
-.08149,-.001126,
-.080448,.013042,
-.076961,.026814,
-.071136,.03977,
-.07001,.04172,
-.0751,.04682,
-.082089,.033068,
-.086584,.018311,
-.088449,.002997,
-.087625,-.012407,
-.08414,-.027435,
-.078097,-.041629,
-.0751,-.04682,
-.07001,-.04172,
0.0*
4,1,16,-.04172,.07001,
-.028929,.076191,
-.015259,.080057,
-.001126,.08149,
.013042,.080448,
.026814,.076961,
.03977,.071136,
.04172,.07001,
.04682,.0751,
.033068,.082089,
.018311,.086584,
.002997,.088449,
-.012407,.087625,
-.027435,.08414,
-.041629,.078097,
-.04682,.0751,
-.04172,.07001,
0.0*
%
%ADD16MACRO16*%
%AMMACRO66*
4,1,15,.02142,.01082,
.022973,.006936,
.023829,.002841,
.02396,-.00134,
.023364,-.00548,
.022057,-.009454,
.02142,-.01082,
.02657,-.01597,
.02894,-.011114,
.03043,-.005919,
.030995,-.000545,
.030619,.004845,
.029313,.010088,
.027115,.015025,
.02657,.01597,
.02142,.01082,
0.0*
4,1,15,.01082,-.02142,
.006936,-.022973,
.002841,-.023829,
-.00134,-.02396,
-.00548,-.023364,
-.009454,-.022057,
-.01082,-.02142,
-.01597,-.02657,
-.011114,-.02894,
-.005919,-.03043,
-.000545,-.030995,
.004845,-.030619,
.010088,-.029313,
.015025,-.027115,
.01597,-.02657,
.01082,-.02142,
0.0*
4,1,15,-.02142,-.01082,
-.022973,-.006936,
-.023829,-.002841,
-.02396,.00134,
-.023364,.00548,
-.022057,.009454,
-.02142,.01082,
-.02657,.01597,
-.02894,.011114,
-.03043,.005919,
-.030995,.000545,
-.030619,-.004845,
-.029313,-.010088,
-.027115,-.015025,
-.02657,-.01597,
-.02142,-.01082,
0.0*
4,1,15,-.01082,.02142,
-.006936,.022973,
-.002841,.023829,
.00134,.02396,
.00548,.023364,
.009454,.022057,
.01082,.02142,
.01597,.02657,
.011114,.02894,
.005919,.03043,
.000545,.030995,
-.004845,.030619,
-.010088,.029313,
-.015025,.027115,
-.01597,.02657,
-.01082,.02142,
0.0*
%
%ADD66MACRO66*%
%AMMACRO52*
4,1,15,.02475,.01414,
.026829,.009627,
.028094,.004822,
.028504,-.000129,
.028049,-.005077,
.026741,-.009871,
.02475,-.01414,
.02984,-.01923,
.032726,-.013756,
.034617,-.007864,
.035457,-.001734,
.03522,.00445,
.033912,.010498,
.031574,.016227,
.02984,.01923,
.02475,.01414,
0.0*
4,1,15,.01414,-.02475,
.009627,-.026829,
.004822,-.028094,
-.000129,-.028504,
-.005077,-.028049,
-.009871,-.026741,
-.01414,-.02475,
-.01923,-.02984,
-.013756,-.032726,
-.007864,-.034617,
-.001734,-.035457,
.00445,-.03522,
.010498,-.033912,
.016227,-.031574,
.01923,-.02984,
.01414,-.02475,
0.0*
4,1,15,-.02475,-.01414,
-.026829,-.009627,
-.028094,-.004822,
-.028504,.000129,
-.028049,.005077,
-.026741,.009871,
-.02475,.01414,
-.02984,.01923,
-.032726,.013756,
-.034617,.007864,
-.035457,.001734,
-.03522,-.00445,
-.033912,-.010498,
-.031574,-.016227,
-.02984,-.01923,
-.02475,-.01414,
0.0*
4,1,15,-.01414,.02475,
-.009627,.026829,
-.004822,.028094,
.000129,.028504,
.005077,.028049,
.009871,.026741,
.01414,.02475,
.01923,.02984,
.013756,.032726,
.007864,.034617,
.001734,.035457,
-.00445,.03522,
-.010498,.033912,
-.016227,.031574,
-.01923,.02984,
-.01414,.02475,
0.0*
%
%ADD52MACRO52*%
%ADD69C,.03968*%
%AMMACRO78*
4,1,15,.03682,.01914,
.039584,.012455,
.041146,.005393,
.041457,-.001834,
.040509,-.009005,
.03833,-.015903,
.03682,-.01914,
.04197,-.0243,
.045552,-.016643,
.04775,-.00848,
.048497,-.000059,
.047771,.008363,
.045593,.016531,
.042029,.024197,
.04197,.0243,
.03682,.01914,
0.0*
4,1,15,.01914,-.03682,
.012455,-.039584,
.005393,-.041146,
-.001834,-.041457,
-.009005,-.040509,
-.015903,-.03833,
-.01914,-.03682,
-.0243,-.04197,
-.016643,-.045552,
-.00848,-.04775,
-.000059,-.048497,
.008363,-.047771,
.016531,-.045593,
.024197,-.042029,
.0243,-.04197,
.01914,-.03682,
0.0*
4,1,15,-.03682,-.01914,
-.039584,-.012455,
-.041146,-.005393,
-.041457,.001834,
-.040509,.009005,
-.03833,.015903,
-.03682,.01914,
-.04197,.0243,
-.045552,.016643,
-.04775,.00848,
-.048497,.000059,
-.047771,-.008363,
-.045593,-.016531,
-.042029,-.024197,
-.04197,-.0243,
-.03682,-.01914,
0.0*
4,1,15,-.01914,.03682,
-.012455,.039584,
-.005393,.041146,
.001834,.041457,
.009005,.040509,
.015903,.03833,
.01914,.03682,
.0243,.04197,
.016643,.045552,
.00848,.04775,
.000059,.048497,
-.008363,.047771,
-.016531,.045593,
-.024197,.042029,
-.0243,.04197,
-.01914,.03682,
0.0*
%
%ADD78MACRO78*%
%AMMACRO74*
4,1,36,.0025,0.0,
.002462,.000434,
.002349,.000855,
.002165,.00125,
.001915,.001607,
.001607,.001915,
.00125,.002165,
.000855,.002349,
.000434,.002462,
0.0,.0025,
-.000434,.002462,
-.000855,.002349,
-.00125,.002165,
-.001607,.001915,
-.001915,.001607,
-.002165,.00125,
-.002349,.000855,
-.002462,.000434,
-.0025,0.0,
-.002462,-.000434,
-.002349,-.000855,
-.002165,-.00125,
-.001915,-.001607,
-.001607,-.001915,
-.00125,-.002165,
-.000855,-.002349,
-.000434,-.002462,
0.0,-.0025,
.000434,-.002462,
.000855,-.002349,
.00125,-.002165,
.001607,-.001915,
.001915,-.001607,
.002165,-.00125,
.002349,-.000855,
.002462,-.000434,
.0025,0.0,
134.996*
%
%ADD74MACRO74*%
%AMMACRO76*
4,1,15,-.03682,.01914,
-.039584,.012455,
-.041146,.005393,
-.041457,-.001834,
-.040509,-.009005,
-.03833,-.015903,
-.03682,-.01914,
-.04197,-.0243,
-.045552,-.016643,
-.04775,-.00848,
-.048497,-.000059,
-.047771,.008363,
-.045593,.016531,
-.042029,.024197,
-.04197,.0243,
-.03682,.01914,
0.0*
4,1,15,-.01914,-.03682,
-.012455,-.039584,
-.005393,-.041146,
.001834,-.041457,
.009005,-.040509,
.015903,-.03833,
.01914,-.03682,
.0243,-.04197,
.016643,-.045552,
.00848,-.04775,
.000059,-.048497,
-.008363,-.047771,
-.016531,-.045593,
-.024197,-.042029,
-.0243,-.04197,
-.01914,-.03682,
0.0*
4,1,15,.03682,-.01914,
.039584,-.012455,
.041146,-.005393,
.041457,.001834,
.040509,.009005,
.03833,.015903,
.03682,.01914,
.04197,.0243,
.045552,.016643,
.04775,.00848,
.048497,.000059,
.047771,-.008363,
.045593,-.016531,
.042029,-.024197,
.04197,-.0243,
.03682,-.01914,
0.0*
4,1,15,.01914,.03682,
.012455,.039584,
.005393,.041146,
-.001834,.041457,
-.009005,.040509,
-.015903,.03833,
-.01914,.03682,
-.0243,.04197,
-.016643,.045552,
-.00848,.04775,
-.000059,.048497,
.008363,.047771,
.016531,.045593,
.024197,.042029,
.0243,.04197,
.01914,.03682,
0.0*
%
%ADD76MACRO76*%
%AMMACRO39*
4,1,36,.003,0.0,
.002954,.000521,
.002819,.001026,
.002598,.0015,
.002298,.001928,
.001928,.002298,
.0015,.002598,
.001026,.002819,
.000521,.002954,
0.0,.003,
-.000521,.002954,
-.001026,.002819,
-.0015,.002598,
-.001928,.002298,
-.002298,.001928,
-.002598,.0015,
-.002819,.001026,
-.002954,.000521,
-.003,0.0,
-.002954,-.000521,
-.002819,-.001026,
-.002598,-.0015,
-.002298,-.001928,
-.001928,-.002298,
-.0015,-.002598,
-.001026,-.002819,
-.000521,-.002954,
0.0,-.003,
.000521,-.002954,
.001026,-.002819,
.0015,-.002598,
.001928,-.002298,
.002298,-.001928,
.002598,-.0015,
.002819,-.001026,
.002954,-.000521,
.003,0.0,
179.996*
%
%ADD39MACRO39*%
%ADD60O,.285X.23*%
%ADD73C,.142*%
%AMMACRO61*
4,1,36,0.0,.01,
-.001736,.009848,
-.00342,.009397,
-.005,.00866,
-.006428,.00766,
-.00766,.006428,
-.00866,.005,
-.009397,.00342,
-.009848,.001736,
-.01,0.0,
-.009848,-.001736,
-.009397,-.00342,
-.00866,-.005,
-.00766,-.006428,
-.006428,-.00766,
-.005,-.00866,
-.00342,-.009397,
-.001736,-.009848,
0.0,-.01,
.001736,-.009848,
.00342,-.009397,
.005,-.00866,
.006428,-.00766,
.00766,-.006428,
.00866,-.005,
.009397,-.00342,
.009848,-.001736,
.01,0.0,
.009848,.001736,
.009397,.00342,
.00866,.005,
.00766,.006428,
.006428,.00766,
.005,.00866,
.00342,.009397,
.001736,.009848,
0.0,.01,
180.*
%
%ADD61MACRO61*%
%ADD36O,.219X.156*%
%ADD11C,.125*%
%ADD27C,.424*%
%ADD18C,.155*%
%ADD53C,.291*%
%ADD55C,.247*%
%ADD46C,.256*%
%AMMACRO33*
4,1,36,0.0,.0085,
.001476,.008371,
.002907,.007987,
.00425,.007361,
.005464,.006511,
.006511,.005464,
.007361,.00425,
.007987,.002907,
.008371,.001476,
.0085,0.0,
.008371,-.001476,
.007987,-.002907,
.007361,-.00425,
.006511,-.005464,
.005464,-.006511,
.00425,-.007361,
.002907,-.007987,
.001476,-.008371,
0.0,-.0085,
-.001476,-.008371,
-.002907,-.007987,
-.00425,-.007361,
-.005464,-.006511,
-.006511,-.005464,
-.007361,-.00425,
-.007987,-.002907,
-.008371,-.001476,
-.0085,0.0,
-.008371,.001476,
-.007987,.002907,
-.007361,.00425,
-.006511,.005464,
-.005464,.006511,
-.00425,.007361,
-.002907,.007987,
-.001476,.008371,
0.0,.0085,
180.*
%
%ADD33MACRO33*%
%AMMACRO59*
4,1,20,-.0075,-.05555,
-.0075,-.06273,
-.013677,-.060878,
-.019439,-.057981,
-.024611,-.054127,
-.029034,-.049434,
-.032576,-.044045,
-.035127,-.038122,
-.036612,-.031846,
-.037,-.0265,
-.037,-.0075,
-.03,-.0075,
-.03,-.0265,
-.029544,-.03171,
-.028191,-.036762,
-.02598,-.041502,
-.022981,-.045786,
-.019282,-.049484,
-.014998,-.052484,
-.010258,-.054694,
-.0075,-.05555,
90.*
4,1,20,.0075,-.06273,
.0075,-.05555,
.01243,-.053806,
.016983,-.051232,
.02102,-.047906,
.024418,-.043931,
.027073,-.039425,
.028906,-.034527,
.029861,-.029385,
.03,-.0265,
.03,-.0075,
.037,-.0075,
.037,-.0265,
.036438,-.032925,
.034769,-.039154,
.032043,-.044999,
.028344,-.050282,
.023784,-.054842,
.018501,-.058541,
.012656,-.061266,
.0075,-.06273,
90.*
4,1,20,-.0075,.06273,
-.0075,.05555,
-.01243,.053806,
-.016983,.051232,
-.02102,.047906,
-.024418,.043931,
-.027073,.039425,
-.028906,.034527,
-.029861,.029385,
-.03,.0265,
-.03,.0075,
-.037,.0075,
-.037,.0265,
-.036438,.032925,
-.034769,.039154,
-.032043,.044999,
-.028344,.050282,
-.023784,.054842,
-.018501,.058541,
-.012656,.061266,
-.0075,.06273,
90.*
4,1,20,.0075,.05555,
.0075,.06273,
.013677,.060878,
.019439,.057981,
.024611,.054127,
.029034,.049434,
.032576,.044045,
.035127,.038122,
.036612,.031846,
.037,.0265,
.037,.0075,
.03,.0075,
.03,.0265,
.029544,.03171,
.028191,.036762,
.02598,.041502,
.022981,.045786,
.019282,.049484,
.014998,.052484,
.010258,.054694,
.0075,.05555,
90.*
%
%ADD59MACRO59*%
%AMMACRO15*
4,1,36,.0025,0.0,
.002462,.000434,
.002349,.000855,
.002165,.00125,
.001915,.001607,
.001607,.001915,
.00125,.002165,
.000855,.002349,
.000434,.002462,
0.0,.0025,
-.000434,.002462,
-.000855,.002349,
-.00125,.002165,
-.001607,.001915,
-.001915,.001607,
-.002165,.00125,
-.002349,.000855,
-.002462,.000434,
-.0025,0.0,
-.002462,-.000434,
-.002349,-.000855,
-.002165,-.00125,
-.001915,-.001607,
-.001607,-.001915,
-.00125,-.002165,
-.000855,-.002349,
-.000434,-.002462,
0.0,-.0025,
.000434,-.002462,
.000855,-.002349,
.00125,-.002165,
.001607,-.001915,
.001915,-.001607,
.002165,-.00125,
.002349,-.000855,
.002462,-.000434,
.0025,0.0,
90.*
%
%ADD15MACRO15*%
%AMMACRO56*
4,1,36,0.0,.019,
-.003299,.018711,
-.006498,.017854,
-.0095,.016454,
-.012213,.014555,
-.014555,.012213,
-.016454,.0095,
-.017854,.006498,
-.018711,.003299,
-.019,0.0,
-.018711,-.003299,
-.017854,-.006498,
-.016454,-.0095,
-.014555,-.012213,
-.012213,-.014555,
-.0095,-.016454,
-.006498,-.017854,
-.003299,-.018711,
0.0,-.019,
.003299,-.018711,
.006498,-.017854,
.0095,-.016454,
.012213,-.014555,
.014555,-.012213,
.016454,-.0095,
.017854,-.006498,
.018711,-.003299,
.019,0.0,
.018711,.003299,
.017854,.006498,
.016454,.0095,
.014555,.012213,
.012213,.014555,
.0095,.016454,
.006498,.017854,
.003299,.018711,
0.0,.019,
270.*
%
%ADD56MACRO56*%
%AMMACRO40*
4,1,36,.003,0.0,
.002954,.000521,
.002819,.001026,
.002598,.0015,
.002298,.001928,
.001928,.002298,
.0015,.002598,
.001026,.002819,
.000521,.002954,
0.0,.003,
-.000521,.002954,
-.001026,.002819,
-.0015,.002598,
-.001928,.002298,
-.002298,.001928,
-.002598,.0015,
-.002819,.001026,
-.002954,.000521,
-.003,0.0,
-.002954,-.000521,
-.002819,-.001026,
-.002598,-.0015,
-.002298,-.001928,
-.001928,-.002298,
-.0015,-.002598,
-.001026,-.002819,
-.000521,-.002954,
0.0,-.003,
.000521,-.002954,
.001026,-.002819,
.0015,-.002598,
.001928,-.002298,
.002298,-.001928,
.002598,-.0015,
.002819,-.001026,
.002954,-.000521,
.003,0.0,
90.*
%
%ADD40MACRO40*%
%AMMACRO12*
4,1,36,.0025,0.0,
.002462,.000434,
.002349,.000855,
.002165,.00125,
.001915,.001607,
.001607,.001915,
.00125,.002165,
.000855,.002349,
.000434,.002462,
0.0,.0025,
-.000434,.002462,
-.000855,.002349,
-.00125,.002165,
-.001607,.001915,
-.001915,.001607,
-.002165,.00125,
-.002349,.000855,
-.002462,.000434,
-.0025,0.0,
-.002462,-.000434,
-.002349,-.000855,
-.002165,-.00125,
-.001915,-.001607,
-.001607,-.001915,
-.00125,-.002165,
-.000855,-.002349,
-.000434,-.002462,
0.0,-.0025,
.000434,-.002462,
.000855,-.002349,
.00125,-.002165,
.001607,-.001915,
.001915,-.001607,
.002165,-.00125,
.002349,-.000855,
.002462,-.000434,
.0025,0.0,
0.0*
%
%ADD12MACRO12*%
%AMMACRO80*
4,1,36,-.003,0.0,
-.002954,.000521,
-.002819,.001026,
-.002598,.0015,
-.002298,.001928,
-.001928,.002298,
-.0015,.002598,
-.001026,.002819,
-.000521,.002954,
0.0,.003,
.000521,.002954,
.001026,.002819,
.0015,.002598,
.001928,.002298,
.002298,.001928,
.002598,.0015,
.002819,.001026,
.002954,.000521,
.003,0.0,
.002954,-.000521,
.002819,-.001026,
.002598,-.0015,
.002298,-.001928,
.001928,-.002298,
.0015,-.002598,
.001026,-.002819,
.000521,-.002954,
0.0,-.003,
-.000521,-.002954,
-.001026,-.002819,
-.0015,-.002598,
-.001928,-.002298,
-.002298,-.001928,
-.002598,-.0015,
-.002819,-.001026,
-.002954,-.000521,
-.003,0.0,
90.*
%
%ADD80MACRO80*%
%AMMACRO45*
4,1,36,-.0025,0.0,
-.002462,.000434,
-.002349,.000855,
-.002165,.00125,
-.001915,.001607,
-.001607,.001915,
-.00125,.002165,
-.000855,.002349,
-.000434,.002462,
0.0,.0025,
.000434,.002462,
.000855,.002349,
.00125,.002165,
.001607,.001915,
.001915,.001607,
.002165,.00125,
.002349,.000855,
.002462,.000434,
.0025,0.0,
.002462,-.000434,
.002349,-.000855,
.002165,-.00125,
.001915,-.001607,
.001607,-.001915,
.00125,-.002165,
.000855,-.002349,
.000434,-.002462,
0.0,-.0025,
-.000434,-.002462,
-.000855,-.002349,
-.00125,-.002165,
-.001607,-.001915,
-.001915,-.001607,
-.002165,-.00125,
-.002349,-.000855,
-.002462,-.000434,
-.0025,0.0,
0.0*
%
%ADD45MACRO45*%
%ADD38C,.188*%
%AMMACRO29*
4,1,36,.003,0.0,
.002954,.000521,
.002819,.001026,
.002598,.0015,
.002298,.001928,
.001928,.002298,
.0015,.002598,
.001026,.002819,
.000521,.002954,
0.0,.003,
-.000521,.002954,
-.001026,.002819,
-.0015,.002598,
-.001928,.002298,
-.002298,.001928,
-.002598,.0015,
-.002819,.001026,
-.002954,.000521,
-.003,0.0,
-.002954,-.000521,
-.002819,-.001026,
-.002598,-.0015,
-.002298,-.001928,
-.001928,-.002298,
-.0015,-.002598,
-.001026,-.002819,
-.000521,-.002954,
0.0,-.003,
.000521,-.002954,
.001026,-.002819,
.0015,-.002598,
.001928,-.002298,
.002298,-.001928,
.002598,-.0015,
.002819,-.001026,
.002954,-.000521,
.003,0.0,
0.0*
%
%ADD29MACRO29*%
%AMMACRO21*
4,1,16,.02584,.01524,
.028094,.010521,
.029494,.005483,
.029998,.000278,
.029591,-.004935,
.028284,-.009999,
.026118,-.014758,
.02584,-.01524,
.03092,-.02032,
.033979,-.014642,
.036005,-.008519,
.036938,-.002138,
.036748,.004309,
.035441,.010625,
.033058,.016618,
.03092,.02032,
.02584,.01524,
180.*
4,1,16,.01524,-.02584,
.010521,-.028094,
.005483,-.029494,
.000278,-.029998,
-.004935,-.029591,
-.009999,-.028284,
-.014758,-.026118,
-.01524,-.02584,
-.02032,-.03092,
-.014642,-.033979,
-.008519,-.036005,
-.002138,-.036938,
.004309,-.036748,
.010625,-.035441,
.016618,-.033058,
.02032,-.03092,
.01524,-.02584,
180.*
4,1,16,-.02584,-.01524,
-.028094,-.010521,
-.029494,-.005483,
-.029998,-.000278,
-.029591,.004935,
-.028284,.009999,
-.026118,.014758,
-.02584,.01524,
-.03092,.02032,
-.033979,.014642,
-.036005,.008519,
-.036938,.002138,
-.036748,-.004309,
-.035441,-.010625,
-.033058,-.016618,
-.03092,-.02032,
-.02584,-.01524,
180.*
4,1,16,-.01524,.02584,
-.010521,.028094,
-.005483,.029494,
-.000278,.029998,
.004935,.029591,
.009999,.028284,
.014758,.026118,
.01524,.02584,
.02032,.03092,
.014642,.033979,
.008519,.036005,
.002138,.036938,
-.004309,.036748,
-.010625,.035441,
-.016618,.033058,
-.02032,.03092,
-.01524,.02584,
180.*
%
%ADD21MACRO21*%
%AMMACRO63*
4,1,15,.02438,.01377,
.026401,.009327,
.027619,.004601,
.027999,-.000265,
.027527,-.005123,
.02622,-.009825,
.02438,-.01377,
.02948,-.01887,
.032309,-.013464,
.034156,-.007649,
.034965,-.001602,
.034712,.004494,
.033405,.010454,
.031082,.016095,
.02948,.01887,
.02438,.01377,
270.*
4,1,15,.01377,-.02438,
.009327,-.026401,
.004601,-.027619,
-.000265,-.027999,
-.005123,-.027527,
-.009825,-.02622,
-.01377,-.02438,
-.01887,-.02948,
-.013464,-.032309,
-.007649,-.034156,
-.001602,-.034965,
.004494,-.034712,
.010454,-.033405,
.016095,-.031082,
.01887,-.02948,
.01377,-.02438,
270.*
4,1,15,-.02438,-.01377,
-.026401,-.009327,
-.027619,-.004601,
-.027999,.000265,
-.027527,.005123,
-.02622,.009825,
-.02438,.01377,
-.02948,.01887,
-.032309,.013464,
-.034156,.007649,
-.034965,.001602,
-.034712,-.004494,
-.033405,-.010454,
-.031082,-.016095,
-.02948,-.01887,
-.02438,-.01377,
270.*
4,1,15,-.01377,.02438,
-.009327,.026401,
-.004601,.027619,
.000265,.027999,
.005123,.027527,
.009825,.02622,
.01377,.02438,
.01887,.02948,
.013464,.032309,
.007649,.034156,
.001602,.034965,
-.004494,.034712,
-.010454,.033405,
-.016095,.031082,
-.01887,.02948,
-.01377,.02438,
270.*
%
%ADD63MACRO63*%
%AMMACRO42*
4,1,15,.02438,.01377,
.026401,.009327,
.027619,.004601,
.027999,-.000265,
.027527,-.005123,
.02622,-.009825,
.02438,-.01377,
.02948,-.01887,
.032309,-.013464,
.034156,-.007649,
.034965,-.001602,
.034712,.004494,
.033405,.010454,
.031082,.016095,
.02948,.01887,
.02438,.01377,
180.*
4,1,15,.01377,-.02438,
.009327,-.026401,
.004601,-.027619,
-.000265,-.027999,
-.005123,-.027527,
-.009825,-.02622,
-.01377,-.02438,
-.01887,-.02948,
-.013464,-.032309,
-.007649,-.034156,
-.001602,-.034965,
.004494,-.034712,
.010454,-.033405,
.016095,-.031082,
.01887,-.02948,
.01377,-.02438,
180.*
4,1,15,-.02438,-.01377,
-.026401,-.009327,
-.027619,-.004601,
-.027999,.000265,
-.027527,.005123,
-.02622,.009825,
-.02438,.01377,
-.02948,.01887,
-.032309,.013464,
-.034156,.007649,
-.034965,.001602,
-.034712,-.004494,
-.033405,-.010454,
-.031082,-.016095,
-.02948,-.01887,
-.02438,-.01377,
180.*
4,1,15,-.01377,.02438,
-.009327,.026401,
-.004601,.027619,
.000265,.027999,
.005123,.027527,
.009825,.02622,
.01377,.02438,
.01887,.02948,
.013464,.032309,
.007649,.034156,
.001602,.034965,
-.004494,.034712,
-.010454,.033405,
-.016095,.031082,
-.01887,.02948,
-.01377,.02438,
180.*
%
%ADD42MACRO42*%
%AMMACRO26*
4,1,20,-.039,.0245,
-.038408,.031272,
-.036648,.037838,
-.033775,.043999,
-.029876,.049567,
-.02507,.054374,
-.019501,.058273,
-.01334,.061146,
-.0075,.06277,
-.0075,.05561,
-.012788,.053835,
-.017688,.051168,
-.02205,.047691,
-.025742,.04351,
-.028652,.038751,
-.030691,.033558,
-.031798,.028091,
-.032,.0245,
-.032,.0075,
-.039,.0075,
-.039,.0245,
90.*
4,1,20,-.039,-.0075,
-.032,-.0075,
-.032,-.0245,
-.031514,-.030057,
-.03007,-.035445,
-.027713,-.040501,
-.024513,-.04507,
-.020569,-.049015,
-.015999,-.052214,
-.010944,-.054572,
-.0075,-.05561,
-.0075,-.06277,
-.014032,-.060887,
-.020137,-.057898,
-.025631,-.053894,
-.030345,-.048997,
-.034138,-.043356,
-.036894,-.037142,
-.038529,-.030544,
-.039,-.0245,
-.039,-.0075,
90.*
4,1,20,.0075,.06277,
.014032,.060887,
.020137,.057898,
.025631,.053894,
.030345,.048997,
.034138,.043356,
.036894,.037142,
.038529,.030544,
.039,.0245,
.039,.0075,
.032,.0075,
.032,.0245,
.031514,.030057,
.03007,.035445,
.027713,.040501,
.024513,.04507,
.020569,.049015,
.015999,.052214,
.010944,.054572,
.0075,.05561,
.0075,.06277,
90.*
4,1,20,.0075,-.05561,
.012788,-.053835,
.017688,-.051168,
.02205,-.047691,
.025742,-.04351,
.028652,-.038751,
.030691,-.033558,
.031798,-.028091,
.032,-.0245,
.032,-.0075,
.039,-.0075,
.039,-.0245,
.038408,-.031272,
.036648,-.037838,
.033775,-.043999,
.029876,-.049567,
.02507,-.054374,
.019501,-.058273,
.01334,-.061146,
.0075,-.06277,
.0075,-.05561,
90.*
%
%ADD26MACRO26*%
%AMMACRO72*
4,1,15,.02475,.01414,
.026829,.009627,
.028094,.004822,
.028504,-.000129,
.028049,-.005077,
.026741,-.009871,
.02475,-.01414,
.02984,-.01923,
.032726,-.013756,
.034617,-.007864,
.035457,-.001734,
.03522,.00445,
.033912,.010498,
.031574,.016227,
.02984,.01923,
.02475,.01414,
270.*
4,1,15,.01414,-.02475,
.009627,-.026829,
.004822,-.028094,
-.000129,-.028504,
-.005077,-.028049,
-.009871,-.026741,
-.01414,-.02475,
-.01923,-.02984,
-.013756,-.032726,
-.007864,-.034617,
-.001734,-.035457,
.00445,-.03522,
.010498,-.033912,
.016227,-.031574,
.01923,-.02984,
.01414,-.02475,
270.*
4,1,15,-.02475,-.01414,
-.026829,-.009627,
-.028094,-.004822,
-.028504,.000129,
-.028049,.005077,
-.026741,.009871,
-.02475,.01414,
-.02984,.01923,
-.032726,.013756,
-.034617,.007864,
-.035457,.001734,
-.03522,-.00445,
-.033912,-.010498,
-.031574,-.016227,
-.02984,-.01923,
-.02475,-.01414,
270.*
4,1,15,-.01414,.02475,
-.009627,.026829,
-.004822,.028094,
.000129,.028504,
.005077,.028049,
.009871,.026741,
.01414,.02475,
.01923,.02984,
.013756,.032726,
.007864,.034617,
.001734,.035457,
-.00445,.03522,
-.010498,.033912,
-.016227,.031574,
-.01923,.02984,
-.01414,.02475,
270.*
%
%ADD72MACRO72*%
%AMMACRO71*
4,1,15,.02142,.01082,
.022973,.006936,
.023829,.002841,
.02396,-.00134,
.023364,-.00548,
.022057,-.009454,
.02142,-.01082,
.02657,-.01597,
.02894,-.011114,
.03043,-.005919,
.030995,-.000545,
.030619,.004845,
.029313,.010088,
.027115,.015025,
.02657,.01597,
.02142,.01082,
180.*
4,1,15,.01082,-.02142,
.006936,-.022973,
.002841,-.023829,
-.00134,-.02396,
-.00548,-.023364,
-.009454,-.022057,
-.01082,-.02142,
-.01597,-.02657,
-.011114,-.02894,
-.005919,-.03043,
-.000545,-.030995,
.004845,-.030619,
.010088,-.029313,
.015025,-.027115,
.01597,-.02657,
.01082,-.02142,
180.*
4,1,15,-.02142,-.01082,
-.022973,-.006936,
-.023829,-.002841,
-.02396,.00134,
-.023364,.00548,
-.022057,.009454,
-.02142,.01082,
-.02657,.01597,
-.02894,.011114,
-.03043,.005919,
-.030995,.000545,
-.030619,-.004845,
-.029313,-.010088,
-.027115,-.015025,
-.02657,-.01597,
-.02142,-.01082,
180.*
4,1,15,-.01082,.02142,
-.006936,.022973,
-.002841,.023829,
.00134,.02396,
.00548,.023364,
.009454,.022057,
.01082,.02142,
.01597,.02657,
.011114,.02894,
.005919,.03043,
.000545,.030995,
-.004845,.030619,
-.010088,.029313,
-.015025,.027115,
-.01597,.02657,
-.01082,.02142,
180.*
%
%ADD71MACRO71*%
%AMMACRO70*
4,1,15,.02475,.01414,
.026829,.009627,
.028094,.004822,
.028504,-.000129,
.028049,-.005077,
.026741,-.009871,
.02475,-.01414,
.02984,-.01923,
.032726,-.013756,
.034617,-.007864,
.035457,-.001734,
.03522,.00445,
.033912,.010498,
.031574,.016227,
.02984,.01923,
.02475,.01414,
180.*
4,1,15,.01414,-.02475,
.009627,-.026829,
.004822,-.028094,
-.000129,-.028504,
-.005077,-.028049,
-.009871,-.026741,
-.01414,-.02475,
-.01923,-.02984,
-.013756,-.032726,
-.007864,-.034617,
-.001734,-.035457,
.00445,-.03522,
.010498,-.033912,
.016227,-.031574,
.01923,-.02984,
.01414,-.02475,
180.*
4,1,15,-.02475,-.01414,
-.026829,-.009627,
-.028094,-.004822,
-.028504,.000129,
-.028049,.005077,
-.026741,.009871,
-.02475,.01414,
-.02984,.01923,
-.032726,.013756,
-.034617,.007864,
-.035457,.001734,
-.03522,-.00445,
-.033912,-.010498,
-.031574,-.016227,
-.02984,-.01923,
-.02475,-.01414,
180.*
4,1,15,-.01414,.02475,
-.009627,.026829,
-.004822,.028094,
.000129,.028504,
.005077,.028049,
.009871,.026741,
.01414,.02475,
.01923,.02984,
.013756,.032726,
.007864,.034617,
.001734,.035457,
-.00445,.03522,
-.010498,.033912,
-.016227,.031574,
-.01923,.02984,
-.01414,.02475,
180.*
%
%ADD70MACRO70*%
%AMMACRO57*
4,1,18,.07103,.05689,
.07983,.043691,
.086204,.029165,
.089959,.013753,
.09098,-.002077,
.089237,-.017844,
.084783,-.033069,
.077753,-.047289,
.07103,-.05689,
.07601,-.06186,
.085597,-.047721,
.092583,-.032132,
.096757,-.015567,
.09799,.001471,
.096246,.018464,
.091577,.034897,
.084126,.050269,
.07601,.06186,
.07103,.05689,
270.*
4,1,18,.05689,-.07103,
.043691,-.07983,
.029165,-.086204,
.013753,-.089959,
-.002077,-.09098,
-.017844,-.089237,
-.033069,-.084783,
-.047289,-.077753,
-.05689,-.07103,
-.06186,-.07601,
-.047721,-.085597,
-.032132,-.092583,
-.015567,-.096757,
.001471,-.09799,
.018464,-.096246,
.034897,-.091577,
.050269,-.084126,
.06186,-.07601,
.05689,-.07103,
270.*
4,1,18,-.07103,-.05689,
-.07983,-.043691,
-.086204,-.029165,
-.089959,-.013753,
-.09098,.002077,
-.089237,.017844,
-.084783,.033069,
-.077753,.047289,
-.07103,.05689,
-.07601,.06186,
-.085597,.047721,
-.092583,.032132,
-.096757,.015567,
-.09799,-.001471,
-.096246,-.018464,
-.091577,-.034897,
-.084126,-.050269,
-.07601,-.06186,
-.07103,-.05689,
270.*
4,1,18,-.05689,.07103,
-.043691,.07983,
-.029165,.086204,
-.013753,.089959,
.002077,.09098,
.017844,.089237,
.033069,.084783,
.047289,.077753,
.05689,.07103,
.06186,.07601,
.047721,.085597,
.032132,.092583,
.015567,.096757,
-.001471,.09799,
-.018464,.096246,
-.034897,.091577,
-.050269,.084126,
-.06186,.07601,
-.05689,.07103,
270.*
%
%ADD57MACRO57*%
%AMMACRO49*
4,1,16,.02657,.01597,
.02894,.011114,
.03043,.005919,
.030995,.000545,
.030619,-.004845,
.029313,-.010088,
.027115,-.015025,
.02657,-.01597,
.03164,-.02104,
.034813,-.015226,
.036928,-.00895,
.037921,-.002401,
.037762,.00422,
.036455,.010713,
.034041,.016881,
.03164,.02104,
.02657,.01597,
180.*
4,1,16,.01597,-.02657,
.011114,-.02894,
.005919,-.03043,
.000545,-.030995,
-.004845,-.030619,
-.010088,-.029313,
-.015025,-.027115,
-.01597,-.02657,
-.02104,-.03164,
-.015226,-.034813,
-.00895,-.036928,
-.002401,-.037921,
.00422,-.037762,
.010713,-.036455,
.016881,-.034041,
.02104,-.03164,
.01597,-.02657,
180.*
4,1,16,-.02657,-.01597,
-.02894,-.011114,
-.03043,-.005919,
-.030995,-.000545,
-.030619,.004845,
-.029313,.010088,
-.027115,.015025,
-.02657,.01597,
-.03164,.02104,
-.034813,.015226,
-.036928,.00895,
-.037921,.002401,
-.037762,-.00422,
-.036455,-.010713,
-.034041,-.016881,
-.03164,-.02104,
-.02657,-.01597,
180.*
4,1,16,-.01597,.02657,
-.011114,.02894,
-.005919,.03043,
-.000545,.030995,
.004845,.030619,
.010088,.029313,
.015025,.027115,
.01597,.02657,
.02104,.03164,
.015226,.034813,
.00895,.036928,
.002401,.037921,
-.00422,.037762,
-.010713,.036455,
-.016881,.034041,
-.02104,.03164,
-.01597,.02657,
180.*
%
%ADD49MACRO49*%
%AMMACRO58*
4,1,15,.04124,.02356,
.044705,.016041,
.046811,.008034,
.047495,-.000216,
.046736,-.008461,
.044557,-.016448,
.04124,-.02356,
.04635,-.02867,
.050624,-.020186,
.05336,-.011088,
.054475,-.001654,
.053935,.007831,
.051756,.017077,
.048004,.025805,
.04635,.02867,
.04124,.02356,
0.0*
4,1,15,.02356,-.04124,
.016041,-.044705,
.008034,-.046811,
-.000216,-.047495,
-.008461,-.046736,
-.016448,-.044557,
-.02356,-.04124,
-.02867,-.04635,
-.020186,-.050624,
-.011088,-.05336,
-.001654,-.054475,
.007831,-.053935,
.017077,-.051756,
.025805,-.048004,
.02867,-.04635,
.02356,-.04124,
0.0*
4,1,15,-.04124,-.02356,
-.044705,-.016041,
-.046811,-.008034,
-.047495,.000216,
-.046736,.008461,
-.044557,.016448,
-.04124,.02356,
-.04635,.02867,
-.050624,.020186,
-.05336,.011088,
-.054475,.001654,
-.053935,-.007831,
-.051756,-.017077,
-.048004,-.025805,
-.04635,-.02867,
-.04124,-.02356,
0.0*
4,1,15,-.02356,.04124,
-.016041,.044705,
-.008034,.046811,
.000216,.047495,
.008461,.046736,
.016448,.044557,
.02356,.04124,
.02867,.04635,
.020186,.050624,
.011088,.05336,
.001654,.054475,
-.007831,.053935,
-.017077,.051756,
-.025805,.048004,
-.02867,.04635,
-.02356,.04124,
0.0*
%
%ADD58MACRO58*%
%AMMACRO79*
4,1,15,.03682,.01914,
.039584,.012455,
.041146,.005393,
.041457,-.001834,
.040509,-.009005,
.03833,-.015903,
.03682,-.01914,
.04197,-.0243,
.045552,-.016643,
.04775,-.00848,
.048497,-.000059,
.047771,.008363,
.045593,.016531,
.042029,.024197,
.04197,.0243,
.03682,.01914,
180.*
4,1,15,.01914,-.03682,
.012455,-.039584,
.005393,-.041146,
-.001834,-.041457,
-.009005,-.040509,
-.015903,-.03833,
-.01914,-.03682,
-.0243,-.04197,
-.016643,-.045552,
-.00848,-.04775,
-.000059,-.048497,
.008363,-.047771,
.016531,-.045593,
.024197,-.042029,
.0243,-.04197,
.01914,-.03682,
180.*
4,1,15,-.03682,-.01914,
-.039584,-.012455,
-.041146,-.005393,
-.041457,.001834,
-.040509,.009005,
-.03833,.015903,
-.03682,.01914,
-.04197,.0243,
-.045552,.016643,
-.04775,.00848,
-.048497,.000059,
-.047771,-.008363,
-.045593,-.016531,
-.042029,-.024197,
-.04197,-.0243,
-.03682,-.01914,
180.*
4,1,15,-.01914,.03682,
-.012455,.039584,
-.005393,.041146,
.001834,.041457,
.009005,.040509,
.015903,.03833,
.01914,.03682,
.0243,.04197,
.016643,.045552,
.00848,.04775,
.000059,.048497,
-.008363,.047771,
-.016531,.045593,
-.024197,.042029,
-.0243,.04197,
-.01914,.03682,
180.*
%
%ADD79MACRO79*%
%AMMACRO77*
4,1,15,-.03682,.01914,
-.039584,.012455,
-.041146,.005393,
-.041457,-.001834,
-.040509,-.009005,
-.03833,-.015903,
-.03682,-.01914,
-.04197,-.0243,
-.045552,-.016643,
-.04775,-.00848,
-.048497,-.000059,
-.047771,.008363,
-.045593,.016531,
-.042029,.024197,
-.04197,.0243,
-.03682,.01914,
180.*
4,1,15,-.01914,-.03682,
-.012455,-.039584,
-.005393,-.041146,
.001834,-.041457,
.009005,-.040509,
.015903,-.03833,
.01914,-.03682,
.0243,-.04197,
.016643,-.045552,
.00848,-.04775,
.000059,-.048497,
-.008363,-.047771,
-.016531,-.045593,
-.024197,-.042029,
-.0243,-.04197,
-.01914,-.03682,
180.*
4,1,15,.03682,-.01914,
.039584,-.012455,
.041146,-.005393,
.041457,.001834,
.040509,.009005,
.03833,.015903,
.03682,.01914,
.04197,.0243,
.045552,.016643,
.04775,.00848,
.048497,.000059,
.047771,-.008363,
.045593,-.016531,
.042029,-.024197,
.04197,-.0243,
.03682,-.01914,
180.*
4,1,15,.01914,.03682,
.012455,.039584,
.005393,.041146,
-.001834,.041457,
-.009005,.040509,
-.015903,.03833,
-.01914,.03682,
-.0243,.04197,
-.016643,.045552,
-.00848,.04775,
-.000059,.048497,
.008363,.047771,
.016531,.045593,
.024197,.042029,
.0243,.04197,
.01914,.03682,
180.*
%
%ADD77MACRO77*%
%ADD84C,.006*%
%ADD89C,.024*%
%ADD110C,.07005*%
%ADD92C,.07006*%
%ADD88C,.07306*%
%ADD90C,.07624*%
%ADD91C,.07608*%
%ADD99C,.07808*%
%ADD97C,.09708*%
%ADD112C,.311*%
%ADD107O,.03004X.07004*%
%ADD102C,.11006*%
%ADD93O,.03004X.06404*%
%ADD111C,.31502*%
%ADD94O,.03006X.06406*%
%ADD113C,.16206*%
%ADD95O,.03004X.06904*%
%ADD103C,.43406*%
%ADD86O,.03404X.06804*%
%ADD85C,.16506*%
%ADD101O,.03006X.06906*%
%ADD98C,.25806*%
%ADD96O,.2363X.2993*%
%ADD87O,.03406X.06806*%
%ADD108C,.19823*%
%ADD106C,.19806*%
%ADD104C,.19807*%
%ADD105C,.19809*%
%ADD109C,.19786*%
%ADD100O,.43374X.77626*%
G75*
%LPD*%
G75*
G36*
G01X-476840Y-884638D02*
X5911000D01*
Y2768362D01*
X-476840D01*
Y-884638D01*
G37*
%LPC*%
G75*
G36*
G01X1007087Y132327D02*
G02X1009020Y130394I0J-1933D01*
G01Y46378D01*
G03X1018898Y36500I9878J0D01*
G01X1510244D01*
G02X1516114Y30630I0J-5870D01*
G01Y-1575D01*
G03X1525992Y-11453I9878J0D01*
G01X1796071D01*
G03X1805949Y-1575I0J9878D01*
G01Y30630D01*
G02X1811819Y36500I5870J0D01*
G01X1849606D01*
G02X1855476Y30630I0J-5870D01*
G01Y-40945D01*
G02X1849606Y-46815I-5870J0D01*
G01X7874D01*
G02X2004Y-40945I0J5870D01*
G01Y30630D01*
G02X7874Y36500I5870J0D01*
G01X35835D01*
G02X41705Y30630I0J-5870D01*
G01Y-1575D01*
G03X51583Y-11453I9878J0D01*
G01X321661D01*
G03X331539Y-1575I0J9878D01*
G01Y30630D01*
G02X337409Y36500I5870J0D01*
G01X480717D01*
G02X486587Y30630I0J-5870D01*
G01Y19212D01*
G03X496465Y9334I9878J0D01*
G01X766543D01*
G03X776421Y19212I0J9878D01*
G01Y30630D01*
G02X782291Y36500I5870J0D01*
G01X879134D01*
G03X889012Y46378I0J9878D01*
G01Y130394D01*
G02X890945Y132327I1933J0D01*
G01X1007087D01*
G37*
G36*
G01X1092027Y1738114D02*
X1824016D01*
G02X1829886Y1732244I0J-5870D01*
G01Y1612316D01*
G03X1832779Y1605332I9878J1D01*
G01X1839978Y1598133D01*
G02X1841697Y1593984I-4150J-4150D01*
G01Y326095D01*
G03X1844590Y319111I9878J1D01*
G01X1853757Y309944D01*
G02X1855476Y305795I-4150J-4150D01*
G01Y54252D01*
G02X1849606Y48382I-5870J0D01*
G01X1803945D01*
G03X1794067Y38504I0J-9878D01*
G01Y2204D01*
G02X1793867Y2004I-200J0D01*
G01X1528196D01*
G02X1527996Y2204I0J200D01*
G01Y38504D01*
G03X1518118Y48382I-9878J0D01*
G01X1026772D01*
G02X1020902Y54252I0J5870D01*
G01Y134331D01*
G03X1011024Y144209I-9878J0D01*
G01X887008D01*
G03X877130Y134331I0J-9878D01*
G01Y54252D01*
G02X871260Y48382I-5870J0D01*
G01X774417D01*
G03X764539Y38504I0J-9878D01*
G01Y22991D01*
G02X764339Y22791I-200J0D01*
G01X498669D01*
G02X498469Y22991I0J200D01*
G01Y38504D01*
G03X488591Y48382I-9878J0D01*
G01X329535D01*
G03X319657Y38504I0J-9878D01*
G01Y2204D01*
G02X319457Y2004I-200J0D01*
G01X53787D01*
G02X53587Y2204I0J200D01*
G01Y38504D01*
G03X43709Y48382I-9878J0D01*
G01X7874D01*
G02X2004Y54252I0J5870D01*
G01Y305795D01*
G02X3723Y309944I5869J-1D01*
G01X6985Y313206D01*
G03X9878Y320190I-6985J6985D01*
G01Y1588078D01*
G02X11597Y1592228I5870J-1D01*
G01X24701Y1605332D01*
G03X27595Y1612317I-6985J6986D01*
G01Y1732244D01*
G02X33465Y1738114I5870J0D01*
G01X765532D01*
G02X765732Y1737914I0J-200D01*
G01Y1736890D01*
G03X769705Y1732917I3973J0D01*
G01X1087854D01*
G03X1091827Y1736890I0J3973D01*
G01Y1737914D01*
G02X1092027Y1738114I200J0D01*
G37*
G36*
G01X1873228Y1820942D02*
X2093700D01*
G02X2099570Y1815072I0J-5870D01*
G01Y1791450D01*
G02X2093700Y1785580I-5870J0D01*
G01X2031574D01*
G03X2021696Y1775702I0J-9878D01*
G01Y1229954D01*
G03X2031574Y1220076I9878J0D01*
G01X2093700D01*
G02X2099570Y1214206I0J-5870D01*
G01Y-40945D01*
G02X2093700Y-46815I-5870J0D01*
G01X1873228D01*
G02X1867358Y-40945I0J5870D01*
G01Y305795D01*
G03X1862159Y318346I-17750J0D01*
G01X1855299Y325206D01*
G02X1853579Y329357I4150J4151D01*
G01Y1593984D01*
G03X1848380Y1606535I-17750J0D01*
G01X1843487Y1611428D01*
G02X1841768Y1615578I4151J4150D01*
G01Y1732244D01*
G02X1847638Y1738114I5870J0D01*
G01X1857480D01*
G03X1867358Y1747992I0J9878D01*
G01Y1815072D01*
G02X1873228Y1820942I5870J0D01*
G37*
%LPD*%
G75*
G36*
G01X81970Y18038D02*
G02Y21044I0J1503D01*
G01X85370D01*
G02Y18038I0J-1503D01*
G01X81970D01*
G37*
G36*
G01X96143D02*
G02Y21044I0J1503D01*
G01X99543D01*
G02Y18038I0J-1503D01*
G01X96143D01*
G37*
G36*
G01X110316D02*
G02Y21044I0J1503D01*
G01X113716D01*
G02Y18038I0J-1503D01*
G01X110316D01*
G37*
G36*
G01X124490D02*
G02Y21044I0J1503D01*
G01X127890D01*
G02Y18038I0J-1503D01*
G01X124490D01*
G37*
G36*
G01X160356D02*
G02Y21044I0J1503D01*
G01X163756D01*
G02Y18038I0J-1503D01*
G01X160356D01*
G37*
G36*
G01X174529D02*
G02Y21044I0J1503D01*
G01X177929D01*
G02Y18038I0J-1503D01*
G01X174529D01*
G37*
G36*
G01X204490D02*
G02Y21044I0J1503D01*
G01X207890D01*
G02Y18038I0J-1503D01*
G01X204490D01*
G37*
G36*
G01X218663D02*
G02Y21044I0J1503D01*
G01X222063D01*
G02Y18038I0J-1503D01*
G01X218663D01*
G37*
G36*
G01X1556379D02*
G02Y21044I0J1503D01*
G01X1559779D01*
G02Y18038I0J-1503D01*
G01X1556379D01*
G37*
G36*
G01X1570552D02*
G02Y21044I0J1503D01*
G01X1573952D01*
G02Y18038I0J-1503D01*
G01X1570552D01*
G37*
G36*
G01X1584725D02*
G02Y21044I0J1503D01*
G01X1588125D01*
G02Y18038I0J-1503D01*
G01X1584725D01*
G37*
G36*
G01X1598899D02*
G02Y21044I0J1503D01*
G01X1602299D01*
G02Y18038I0J-1503D01*
G01X1598899D01*
G37*
G36*
G01X1634765D02*
G02Y21044I0J1503D01*
G01X1638165D01*
G02Y18038I0J-1503D01*
G01X1634765D01*
G37*
G36*
G01X1648938D02*
G02Y21044I0J1503D01*
G01X1652338D01*
G02Y18038I0J-1503D01*
G01X1648938D01*
G37*
G36*
G01X1678899D02*
G02Y21044I0J1503D01*
G01X1682299D01*
G02Y18038I0J-1503D01*
G01X1678899D01*
G37*
G36*
G01X1693072D02*
G02Y21044I0J1503D01*
G01X1696472D01*
G02Y18038I0J-1503D01*
G01X1693072D01*
G37*
G36*
G01X280828Y24432D02*
G02Y27438I0J1503D01*
G01X284228D01*
G02Y24432I0J-1503D01*
G01X280828D01*
G37*
G36*
G01X74865Y24974D02*
G02Y27980I0J1503D01*
G01X78265D01*
G02Y24974I0J-1503D01*
G01X74865D01*
G37*
G36*
G01X89038D02*
G02Y27980I0J1503D01*
G01X92438D01*
G02Y24974I0J-1503D01*
G01X89038D01*
G37*
G36*
G01X103211D02*
G02Y27980I0J1503D01*
G01X106611D01*
G02Y24974I0J-1503D01*
G01X103211D01*
G37*
G36*
G01X117385D02*
G02Y27980I0J1503D01*
G01X120785D01*
G02Y24974I0J-1503D01*
G01X117385D01*
G37*
G36*
G01X153251D02*
G02Y27980I0J1503D01*
G01X156651D01*
G02Y24974I0J-1503D01*
G01X153251D01*
G37*
G36*
G01X167424D02*
G02Y27980I0J1503D01*
G01X170824D01*
G02Y24974I0J-1503D01*
G01X167424D01*
G37*
G36*
G01X197385D02*
G02Y27980I0J1503D01*
G01X200785D01*
G02Y24974I0J-1503D01*
G01X197385D01*
G37*
G36*
G01X211558D02*
G02Y27980I0J1503D01*
G01X214958D01*
G02Y24974I0J-1503D01*
G01X211558D01*
G37*
G36*
G01X225731D02*
G02Y27980I0J1503D01*
G01X229131D01*
G02Y24974I0J-1503D01*
G01X225731D01*
G37*
G36*
G01X1549274D02*
G02Y27980I0J1503D01*
G01X1552674D01*
G02Y24974I0J-1503D01*
G01X1549274D01*
G37*
G36*
G01X1563447D02*
G02Y27980I0J1503D01*
G01X1566847D01*
G02Y24974I0J-1503D01*
G01X1563447D01*
G37*
G36*
G01X1577620D02*
G02Y27980I0J1503D01*
G01X1581020D01*
G02Y24974I0J-1503D01*
G01X1577620D01*
G37*
G36*
G01X1591794D02*
G02Y27980I0J1503D01*
G01X1595194D01*
G02Y24974I0J-1503D01*
G01X1591794D01*
G37*
G36*
G01X1627660D02*
G02Y27980I0J1503D01*
G01X1631060D01*
G02Y24974I0J-1503D01*
G01X1627660D01*
G37*
G36*
G01X1641833D02*
G02Y27980I0J1503D01*
G01X1645233D01*
G02Y24974I0J-1503D01*
G01X1641833D01*
G37*
G36*
G01X1671794D02*
G02Y27980I0J1503D01*
G01X1675194D01*
G02Y24974I0J-1503D01*
G01X1671794D01*
G37*
G36*
G01X1685967D02*
G02Y27980I0J1503D01*
G01X1689367D01*
G02Y24974I0J-1503D01*
G01X1685967D01*
G37*
G36*
G01X1755238D02*
G02Y27980I0J1503D01*
G01X1758638D01*
G02Y24974I0J-1503D01*
G01X1755238D01*
G37*
G36*
G01X1700183Y25002D02*
G02Y28008I0J1503D01*
G01X1703583D01*
G02Y25002I0J-1503D01*
G01X1700183D01*
G37*
G36*
G01X519765Y38826D02*
G02Y41830I0J1502D01*
G01X523165D01*
G02Y38826I0J-1502D01*
G01X519765D01*
G37*
G36*
G01X670613Y40962D02*
G02Y43966I0J1502D01*
G01X674013D01*
G02Y40962I0J-1502D01*
G01X670613D01*
G37*
G36*
G01X512658Y45110D02*
G02Y48116I0J1503D01*
G01X516058D01*
G02Y45110I0J-1503D01*
G01X512658D01*
G37*
G36*
G01X533918Y45564D02*
G02Y48570I0J1503D01*
G01X537318D01*
G02Y45564I0J-1503D01*
G01X533918D01*
G37*
G36*
G01X225727Y49146D02*
G02Y52152I0J1503D01*
G01X229127D01*
G02Y49146I0J-1503D01*
G01X225727D01*
G37*
G36*
G01X280826D02*
G02Y52152I0J1503D01*
G01X284226D01*
G02Y49146I0J-1503D01*
G01X280826D01*
G37*
G36*
G01X1700136D02*
G02Y52152I0J1503D01*
G01X1703536D01*
G02Y49146I0J-1503D01*
G01X1700136D01*
G37*
G36*
G01X1755235D02*
G02Y52152I0J1503D01*
G01X1758635D01*
G02Y49146I0J-1503D01*
G01X1755235D01*
G37*
G36*
G01X262198Y54862D02*
G03X262334I68J188D01*
G02X263516Y55068I1184J-3297D01*
G02X266921Y52387I0J-3503D01*
G03X267021Y52257I195J46D01*
G02X268868Y49171I-1655J-3086D01*
G02X265365Y45668I-3503J0D01*
G02X263864Y46006I0J3503D01*
G03X263672Y45995I-86J-181D01*
G02X261816Y45462I-1857J2970D01*
G02X260634Y45668I2J3503D01*
G03X260498I-68J-188D01*
G02X259316Y45462I-1184J3297D01*
G02X257661Y45878I1J3503D01*
G03X257471I-95J-176D01*
G02X255816Y45462I-1656J3087D01*
G02X254161Y45878I1J3503D01*
G03X253971I-95J-176D01*
G02X252316Y45462I-1656J3087D01*
G02X250661Y45878I1J3503D01*
G03X250471I-95J-176D01*
G02X248816Y45462I-1656J3087D01*
G02X245314Y48965I1J3503D01*
G02X246959Y51935I3504J0D01*
G03X247051Y52075I-106J170D01*
G02X250516Y55068I3465J-509D01*
G02X252171Y54652I-1J-3503D01*
G03X252361I95J176D01*
G02X254016Y55068I1656J-3087D01*
G02X255671Y54652I-1J-3503D01*
G03X255861I95J176D01*
G02X257516Y55068I1656J-3087D01*
G02X259171Y54652I-1J-3503D01*
G03X259361I95J176D01*
G02X261016Y55068I1656J-3087D01*
G02X262198Y54862I-2J-3503D01*
G37*
G36*
G01X757202Y54804D02*
G02X758621Y55104I1418J-3202D01*
G02X762124Y51602I1J-3502D01*
G02X760383Y48575I-3502J0D01*
G01X760382Y48574D01*
G03X760284Y48421I101J-173D01*
G01X760252Y48099D01*
G03X760319Y47929I199J-20D01*
G02X754928Y47567I-2516J-2851D01*
G01X754962Y47606D01*
X754984Y47707D01*
X754852Y48131D01*
X754778Y48202D01*
X754728Y48215D01*
G02X752118Y51602I893J3387D01*
G02X755621Y55104I3503J-1D01*
G01X755623D01*
G02X757040Y54804I-1J-3502D01*
G03X757202I81J183D01*
G37*
G36*
G01X1728848Y55655D02*
X1728849Y55656D01*
G02X1729836Y56026I987J-1131D01*
G02X1731332Y54658I0J-1502D01*
G03X1731443Y54496I199J18D01*
G02X1733398Y51354I-1547J-3142D01*
G02X1733316Y50602I-3503J1D01*
G03X1733334Y50465I195J-44D01*
G02X1733744Y48822I-3093J-1644D01*
G02X1733586Y47785I-3503J3D01*
G01X1733567Y47725D01*
X1733604Y47607D01*
X1733950Y47338D01*
G03X1734177Y47325I123J158D01*
G02X1736004Y47840I1828J-2987D01*
G01X1736006D01*
G02X1739508Y44338I0J-3502D01*
G01Y44335D01*
G02X1739303Y43155I-3502J1D01*
G03Y43021I188J-67D01*
G02X1739508Y41841I-3297J-1181D01*
G01Y41838D01*
G02X1732504I-3502J0D01*
G01Y41841D01*
G02X1732709Y43021I3502J-1D01*
G03Y43155I-188J67D01*
G02X1732504Y44335I3297J1181D01*
G01Y44338D01*
G02X1732661Y45375I3503J0D01*
G01X1732680Y45435D01*
X1732643Y45553D01*
X1732297Y45822D01*
G03X1732070Y45835I-123J-158D01*
G02X1730241Y45320I-1828J2987D01*
G02X1728585Y45735I-2J3502D01*
G03X1728397I-94J-176D01*
G02X1726741Y45320I-1654J3087D01*
G02X1725085Y45735I-2J3502D01*
G03X1724897I-94J-176D01*
G02X1723241Y45320I-1654J3087D01*
G02X1719738Y48822I-1J3502D01*
G02X1721117Y51607I3503J0D01*
G03X1721195Y51749I-121J159D01*
G02X1724685Y54956I3490J-295D01*
G02X1725575Y54842I4J-3502D01*
G03X1725722Y54860I51J193D01*
G01X1725828Y54918D01*
G03X1725920Y55026I-96J175D01*
G02X1727336Y56026I1416J-503D01*
G02X1728323Y55656I0J-1501D01*
G01X1728324D01*
Y55655D01*
G03X1728454Y55607I130J152D01*
G01X1728718D01*
G03X1728848Y55655I0J200D01*
G37*
G36*
G01X1734796Y54421D02*
G02X1734590Y55603I3297J1184D01*
G02X1741596I3503J0D01*
G02X1741390Y54421I-3503J2D01*
G03Y54285I188J-68D01*
G02X1741596Y53103I-3297J-1184D01*
G02X1734590I-3503J0D01*
G02X1734796Y54285I3503J-2D01*
G03Y54421I-188J68D01*
G37*
G36*
G01X1770792Y63032D02*
Y63033D01*
G02X1777796I3502J0D01*
G01Y63032D01*
G02X1777516Y61661I-3502J1D01*
G03Y61505I184J-78D01*
G02X1777796Y60133I-3222J-1372D01*
G01Y60129D01*
G02X1777507Y58738I-3502J2D01*
G03Y58579I183J-79D01*
G02X1777794Y57191I-3216J-1389D01*
G02X1770788I-3503J0D01*
G02X1771078Y58586I3503J-1D01*
G03X1771079Y58745I-183J81D01*
G02X1770792Y60133I3215J1388D01*
G02X1771072Y61505I3502J0D01*
G03Y61661I-184J78D01*
G02X1770792Y63032I3222J1372D01*
G37*
G36*
G01X763221Y68634D02*
G02X766724Y65132I1J-3502D01*
G02X766134Y63188I-3503J2D01*
G03X766107Y63026I167J-111D01*
G02X766224Y62132I-3386J-898D01*
G02X762721Y58630I-3503J1D01*
G01X762718D01*
G02X761538Y58835I1J3502D01*
G03X761404I-67J-188D01*
G02X760221Y58630I-1181J3297D01*
G02X759038Y58835I-2J3502D01*
G03X758904I-67J-188D01*
G02X757721Y58630I-1181J3297D01*
G02X754218Y62132I-1J3502D01*
G02X754424Y63314I3503J-2D01*
G03Y63450I-188J68D01*
G02X754218Y64632I3297J1184D01*
G02X757721Y68134I3503J-1D01*
G01X757724D01*
G02X758904Y67929I-1J-3502D01*
G03X759038I67J188D01*
G02X760221Y68134I1181J-3297D01*
G02X761115Y68018I0J-3502D01*
G03X761277Y68045I51J194D01*
G02X763221Y68634I1944J-2913D01*
G37*
G36*
G01X304943Y68370D02*
G03X305084Y68377I61J190D01*
G02X306468Y68662I1384J-3217D01*
G01X306470D01*
G02Y61658I0J-3502D01*
G01X306466D01*
G02X305379Y61832I3J3502D01*
G03X305238Y61825I-61J-190D01*
G02X303854Y61540I-1384J3217D01*
G01X303852D01*
G02Y68544I0J3502D01*
G01X303856D01*
G02X304943Y68370I-3J-3502D01*
G37*
G36*
G01X61157Y67838D02*
G02Y70842I0J1502D01*
G01X64557D01*
G02Y67838I0J-1502D01*
G01X61157D01*
G37*
G36*
G01X83157D02*
G02Y70842I0J1502D01*
G01X86557D01*
G02Y67838I0J-1502D01*
G01X83157D01*
G37*
G36*
G01X105157D02*
G02Y70842I0J1502D01*
G01X108557D01*
G02Y67838I0J-1502D01*
G01X105157D01*
G37*
G36*
G01X172361D02*
G02Y70842I0J1502D01*
G01X175761D01*
G02Y67838I0J-1502D01*
G01X172361D01*
G37*
G36*
G01X194361D02*
G02Y70842I0J1502D01*
G01X197761D01*
G02Y67838I0J-1502D01*
G01X194361D01*
G37*
G36*
G01X1535566D02*
G02Y70842I0J1502D01*
G01X1538966D01*
G02Y67838I0J-1502D01*
G01X1535566D01*
G37*
G36*
G01X1557566D02*
G02Y70842I0J1502D01*
G01X1560966D01*
G02Y67838I0J-1502D01*
G01X1557566D01*
G37*
G36*
G01X1579566D02*
G02Y70842I0J1502D01*
G01X1582966D01*
G02Y67838I0J-1502D01*
G01X1579566D01*
G37*
G36*
G01X1646770D02*
G02Y70842I0J1502D01*
G01X1650170D01*
G02Y67838I0J-1502D01*
G01X1646770D01*
G37*
G36*
G01X1668770D02*
G02Y70842I0J1502D01*
G01X1672170D01*
G02Y67838I0J-1502D01*
G01X1668770D01*
G37*
G36*
G01X127153Y67840D02*
G02Y70846I0J1503D01*
G01X130553D01*
G02Y67840I0J-1503D01*
G01X127153D01*
G37*
G36*
G01X149153D02*
G02Y70846I0J1503D01*
G01X152553D01*
G02Y67840I0J-1503D01*
G01X149153D01*
G37*
G36*
G01X216491D02*
G02Y70846I0J1503D01*
G01X219891D01*
G02Y67840I0J-1503D01*
G01X216491D01*
G37*
G36*
G01X1601562D02*
G02Y70846I0J1503D01*
G01X1604962D01*
G02Y67840I0J-1503D01*
G01X1601562D01*
G37*
G36*
G01X1623562D02*
G02Y70846I0J1503D01*
G01X1626962D01*
G02Y67840I0J-1503D01*
G01X1623562D01*
G37*
G36*
G01X1690900D02*
G02Y70846I0J1503D01*
G01X1694300D01*
G02Y67840I0J-1503D01*
G01X1690900D01*
G37*
G36*
G01X1221518Y67427D02*
G02X1225540Y71450I4023J0D01*
G01X1225541D01*
G02Y63504I0J-3973D01*
G01X1225441D01*
G02X1221518Y67427I0J3923D01*
G37*
G36*
G01X519743Y69934D02*
G02Y72938I0J1502D01*
G01X523143D01*
G02Y69934I0J-1502D01*
G01X519743D01*
G37*
G36*
G01X541003D02*
G02Y72938I0J1502D01*
G01X544403D01*
G02Y69934I0J-1502D01*
G01X541003D01*
G37*
G36*
G01X555176D02*
G02Y72938I0J1502D01*
G01X558576D01*
G02Y69934I0J-1502D01*
G01X555176D01*
G37*
G36*
G01X311430Y70434D02*
G02X311150Y71806I3223J1372D01*
G02X318156I3503J0D01*
G02X317876Y70434I-3503J0D01*
G03Y70278I184J-78D01*
G02X318156Y68906I-3223J-1372D01*
G02X311150I-3503J0D01*
G02X311430Y70278I3503J0D01*
G03Y70434I-184J78D01*
G37*
G36*
G01X1776242Y72972D02*
Y72973D01*
G02X1783246I3502J0D01*
G01Y72972D01*
G02X1782966Y71601I-3502J1D01*
G03Y71445I184J-78D01*
G02X1783246Y70074I-3222J-1372D01*
G01Y70073D01*
G02X1776242I-3502J0D01*
G01Y70074D01*
G02X1776522Y71445I3502J-1D01*
G03Y71601I-184J78D01*
G02X1776242Y72972I3222J1372D01*
G37*
G36*
G01X94157Y73838D02*
G02Y76842I0J1502D01*
G01X97557D01*
G02Y73838I0J-1502D01*
G01X94157D01*
G37*
G36*
G01X116157D02*
G02Y76842I0J1502D01*
G01X119557D01*
G02Y73838I0J-1502D01*
G01X116157D01*
G37*
G36*
G01X138157D02*
G02Y76842I0J1502D01*
G01X141557D01*
G02Y73838I0J-1502D01*
G01X138157D01*
G37*
G36*
G01X161361D02*
G02Y76842I0J1502D01*
G01X164761D01*
G02Y73838I0J-1502D01*
G01X161361D01*
G37*
G36*
G01X205495D02*
G02Y76842I0J1502D01*
G01X208895D01*
G02Y73838I0J-1502D01*
G01X205495D01*
G37*
G36*
G01X227495D02*
G02Y76842I0J1502D01*
G01X230895D01*
G02Y73838I0J-1502D01*
G01X227495D01*
G37*
G36*
G01X1568566D02*
G02Y76842I0J1502D01*
G01X1571966D01*
G02Y73838I0J-1502D01*
G01X1568566D01*
G37*
G36*
G01X1590566D02*
G02Y76842I0J1502D01*
G01X1593966D01*
G02Y73838I0J-1502D01*
G01X1590566D01*
G37*
G36*
G01X1612566D02*
G02Y76842I0J1502D01*
G01X1615966D01*
G02Y73838I0J-1502D01*
G01X1612566D01*
G37*
G36*
G01X1635770D02*
G02Y76842I0J1502D01*
G01X1639170D01*
G02Y73838I0J-1502D01*
G01X1635770D01*
G37*
G36*
G01X1679904D02*
G02Y76842I0J1502D01*
G01X1683304D01*
G02Y73838I0J-1502D01*
G01X1679904D01*
G37*
G36*
G01X1701904D02*
G02Y76842I0J1502D01*
G01X1705304D01*
G02Y73838I0J-1502D01*
G01X1701904D01*
G37*
G36*
G01X72153Y73840D02*
G02Y76846I0J1503D01*
G01X75553D01*
G02Y73840I0J-1503D01*
G01X72153D01*
G37*
G36*
G01X183357D02*
G02Y76846I0J1503D01*
G01X186757D01*
G02Y73840I0J-1503D01*
G01X183357D01*
G37*
G36*
G01X1546562D02*
G02Y76846I0J1503D01*
G01X1549962D01*
G02Y73840I0J-1503D01*
G01X1546562D01*
G37*
G36*
G01X1657766D02*
G02Y76846I0J1503D01*
G01X1661166D01*
G02Y73840I0J-1503D01*
G01X1657766D01*
G37*
G36*
G01X547821Y77870D02*
G02Y80874I0J1502D01*
G01X551721D01*
G02Y77870I0J-1502D01*
G01X547821D01*
G37*
G36*
G01X259596Y78847D02*
G02X259390Y80029I3297J1184D01*
G02X266396I3503J0D01*
G02X266190Y78847I-3503J2D01*
G03Y78711I188J-68D01*
G02X266396Y77529I-3297J-1184D01*
G02X265926Y75777I-3503J1D01*
G03X265941Y75554I173J-100D01*
G02X266353Y74883I-2760J-2157D01*
G01Y74881D01*
G03X266515Y74768I181J86D01*
G01X266858Y74735D01*
G03X267037Y74814I19J199D01*
G01X267038Y74815D01*
G02X269860Y76244I2823J-2074D01*
G02Y69238I0J-3503D01*
G02X266689Y71254I0J3503D01*
G01Y71256D01*
G03X266527Y71369I-181J-86D01*
G01X266184Y71402D01*
G03X266005Y71323I-19J-199D01*
G01X266004Y71322D01*
G02X263182Y69894I-2822J2074D01*
G02X259680Y73396I0J3502D01*
G01Y73397D01*
G02X260149Y75148I3502J0D01*
G03X260134Y75371I-173J100D01*
G02X259390Y77529I2758J2158D01*
G02X259596Y78711I3503J-2D01*
G03Y78847I-188J68D01*
G37*
G36*
G01X1454786Y76366D02*
G02Y84312I0J3973D01*
G01X1454886D01*
G02X1458808Y80389I-1J-3923D01*
G02X1454786Y76366I-4022J-1D01*
G37*
G36*
G01X1738824Y84928D02*
G03X1739040Y84981I68J188D01*
G02X1741621Y86116I2581J-2367D01*
G02X1745124Y82613I0J-3503D01*
G02X1744918Y81431I-3503J2D01*
G03Y81295I188J-68D01*
G02X1745124Y80113I-3297J-1184D01*
G02X1744708Y78458I-3503J1D01*
G03Y78268I176J-95D01*
G02X1745124Y76613I-3087J-1656D01*
G02X1744918Y75431I-3503J2D01*
G03Y75295I188J-68D01*
G02X1745124Y74113I-3297J-1184D01*
G02X1741621Y70610I-3503J0D01*
G02X1740414Y70825I1J3503D01*
G03X1740198Y70772I-68J-188D01*
G02X1737617Y69638I-2580J2368D01*
G02X1734114Y73140I-1J3502D01*
G02X1734320Y74322I3503J-2D01*
G03Y74458I-188J68D01*
G02X1734114Y75640I3297J1184D01*
G02X1734530Y77295I3503J-1D01*
G03Y77485I-176J95D01*
G02X1734114Y79140I3087J1656D01*
G02X1734320Y80322I3503J-2D01*
G03Y80458I-188J68D01*
G02X1734114Y81640I3297J1184D01*
G02X1737617Y85142I3503J-1D01*
G01X1737620D01*
G02X1738824Y84928I-1J-3502D01*
G37*
G36*
G01X695374Y87282D02*
G03X695481Y87389I-77J184D01*
G02X698711Y89538I3230J-1353D01*
G02X702214Y86035I0J-3503D01*
G02X700174Y82852I-3503J0D01*
G03X700067Y82610I84J-182D01*
G02X700230Y81556I-3339J-1056D01*
G01Y81552D01*
G02X699726Y79743I-3501J1D01*
G03X699707Y79578I171J-103D01*
G02X699874Y78512I-3336J-1069D01*
G02X692868I-3503J0D01*
G02X693373Y80321I3502J-3D01*
G03X693392Y80486I-171J103D01*
G02X693226Y81552I3336J1065D01*
G02X693431Y82735I3502J2D01*
G03Y82869I-188J67D01*
G02X693226Y84049I3297J1181D01*
G01Y84052D01*
G02X695374Y87282I3503J0D01*
G37*
G36*
G01X84927Y82714D02*
X89655Y89777D01*
G02X89821Y89866I166J-110D01*
G02X90021Y89666I0J-200D01*
G02X89987Y89555I-200J1D01*
G01X85481Y82824D01*
G03X85536Y82547I167J-111D01*
G01X85599Y82505D01*
X86722Y81752D01*
X87260Y81392D01*
G03X87537Y81447I111J166D01*
G01X92043Y88178D01*
G02X92209Y88267I166J-110D01*
G02X92409Y88067I0J-200D01*
G02X92375Y87956I-200J1D01*
G01X87647Y80893D01*
G02X87481Y80804I-166J110D01*
G02X87370Y80838I1J200D01*
G01X84982Y82437D01*
G02X84893Y82603I110J166D01*
G02X84927Y82714I200J-1D01*
G37*
G36*
G01X139302Y82300D02*
X142905Y89998D01*
G02X143086Y90113I181J-85D01*
G02X143286Y89913I0J-200D01*
G02X143267Y89828I-200J0D01*
G01X139834Y82492D01*
G03X139930Y82226I181J-85D01*
G01X140374Y82019D01*
X140669Y81881D01*
X140870Y81787D01*
X141809Y81348D01*
G03X142075Y81444I85J181D01*
G01X145508Y88780D01*
G02X145689Y88895I181J-85D01*
G02X145889Y88695I0J-200D01*
G02X145870Y88610I-200J0D01*
G01X142267Y80912D01*
G02X142086Y80797I-181J85D01*
G02X142001Y80816I0J200D01*
G01X139398Y82034D01*
G02X139283Y82215I85J181D01*
G02X139302Y82300I200J0D01*
G37*
G36*
G01X452102Y87208D02*
G02Y90214I0J1503D01*
G01X455502D01*
G02Y87208I0J-1503D01*
G01X452102D01*
G37*
G36*
G01X219426Y82450D02*
Y90550D01*
G02X219826I200J0D01*
G01Y82050D01*
G02X219626Y81850I-200J0D01*
G01X216756D01*
G02X216556Y82050I0J200D01*
G01Y90550D01*
G02X216956I200J0D01*
G01Y82450D01*
G03X217156Y82250I200J0D01*
G01X219226D01*
G03X219426Y82450I0J200D01*
G37*
G36*
G01X173646Y83714D02*
X176203Y91820D01*
G02X176394Y91960I191J-60D01*
G02X176594Y91760I0J-200D01*
G01Y91759D01*
G02X176585Y91700I-200J0D01*
G01X174148Y83976D01*
G03X174279Y83725I191J-60D01*
G01X175268Y83413D01*
X176256Y83101D01*
G03X176507Y83232I60J191D01*
G01X178944Y90956D01*
G02X179135Y91096I191J-60D01*
G02X179335Y90896I0J-200D01*
G01Y90895D01*
G02X179326Y90836I-200J0D01*
G01X176769Y82730D01*
G02X176578Y82590I-191J60D01*
G01X176577D01*
G02X176518Y82599I0J200D01*
G01X173777Y83463D01*
G02X173637Y83654I60J191D01*
G01Y83655D01*
G02X173646Y83714I200J0D01*
G37*
G36*
G01X107820Y84535D02*
X112116Y91869D01*
G02X112289Y91968I173J-102D01*
G02X112489Y91768I0J-200D01*
G01Y91767D01*
G02X112462Y91667I-200J0D01*
G01X108368Y84679D01*
G03X108440Y84405I173J-101D01*
G01X110228Y83357D01*
G03X110502Y83429I101J173D01*
G01X114596Y90417D01*
G02X114769Y90516I173J-102D01*
G02X114969Y90316I0J-200D01*
G01Y90315D01*
G02X114942Y90215I-200J0D01*
G01X110646Y82881D01*
G02X110473Y82782I-173J102D01*
G01X110472D01*
G02X110372Y82809I0J200D01*
G01X107892Y84261D01*
G02X107793Y84434I102J173D01*
G01Y84435D01*
G02X107820Y84535I200J0D01*
G37*
G36*
G01X537148Y89555D02*
G02X539273Y91680I1062J1062D01*
G01X541678Y89276D01*
G02X542118Y88214I-1063J-1063D01*
G01Y88213D01*
G02X540615Y86710I-1503J0D01*
G01X540614D01*
G02X539552Y87150I1J1503D01*
G01X537148Y89555D01*
G37*
G36*
G01X195284Y83786D02*
X197047Y92102D01*
G02X197243Y92261I196J-41D01*
G02X197443Y92061I0J-200D01*
G02X197439Y92020I-200J-1D01*
G01X195758Y84096D01*
G03X195913Y83859I196J-41D01*
G01X197941Y83428D01*
G03X198178Y83583I41J196D01*
G01X199858Y91506D01*
G02X200054Y91665I196J-41D01*
G02X200254Y91465I0J-200D01*
G02X200250Y91424I-200J-1D01*
G01X198487Y83108D01*
G02X198291Y82949I-196J41D01*
G02X198250Y82953I-1J200D01*
G01X195439Y83549D01*
G02X195280Y83745I41J196D01*
G02X195284Y83786I200J1D01*
G37*
G36*
G01X230430Y84970D02*
Y93070D01*
G02X230830I200J0D01*
G01Y84570D01*
G02X230630Y84370I-200J0D01*
G01X227760D01*
G02X227560Y84570I0J200D01*
G01Y93070D01*
G02X227960I200J0D01*
G01Y84970D01*
G03X228160Y84770I200J0D01*
G01X230230D01*
G03X230430Y84970I0J200D01*
G37*
G36*
G01X66146Y86843D02*
X71221Y93661D01*
G02X71381Y93742I161J-119D01*
G02X71581Y93542I0J-200D01*
G02X71541Y93423I-200J1D01*
G01X66705Y86925D01*
G03X66746Y86646I161J-119D01*
G01X68410Y85407D01*
G03X68689Y85448I119J161D01*
G01X73526Y91945D01*
G02X73686Y92026I161J-119D01*
G02X73886Y91826I0J-200D01*
G02X73846Y91707I-200J1D01*
G01X68771Y84889D01*
G02X68611Y84808I-161J119D01*
G02X68492Y84848I1J200D01*
G01X66187Y86564D01*
G02X66106Y86724I119J161D01*
G02X66146Y86843I200J-1D01*
G37*
G36*
G01X445014Y93182D02*
G02Y96186I0J1502D01*
G01X448414D01*
G02Y93182I0J-1502D01*
G01X445014D01*
G37*
G36*
G01X746532Y92887D02*
Y92888D01*
G02X753536I3502J0D01*
G01Y92887D01*
G02X753256Y91516I-3502J1D01*
G03Y91360I184J-78D01*
G02X753536Y89989I-3222J-1372D01*
G01Y89988D01*
G02X746532I-3502J0D01*
G01Y89989D01*
G02X746812Y91360I3502J-1D01*
G03Y91516I-184J78D01*
G02X746532Y92887I3222J1372D01*
G37*
G36*
G01X459056Y93598D02*
G02Y96604I0J1503D01*
G01X462456D01*
G02Y93598I0J-1503D01*
G01X459056D01*
G37*
G36*
G01X514240Y95644D02*
G02Y98648I0J1502D01*
G01X517640D01*
G02Y95644I0J-1502D01*
G01X514240D01*
G37*
G36*
G01X101309Y91451D02*
X105819Y98656D01*
G02X105989Y98750I170J-107D01*
G02X106189Y98550I0J-200D01*
G01Y98549D01*
G02X106159Y98444I-200J0D01*
G01X101861Y91578D01*
G03X101925Y91302I170J-106D01*
G01X102396Y91007D01*
X102408Y90999D01*
X103682Y90202D01*
G03X103958Y90266I106J170D01*
G01X108255Y97131D01*
G02X108425Y97225I170J-107D01*
G02X108625Y97025I0J-200D01*
G01Y97024D01*
G02X108595Y96919I-200J0D01*
G01X104085Y89714D01*
G02X103915Y89620I-170J107D01*
G01X103914D01*
G02X103809Y89650I0J200D01*
G01X101373Y91175D01*
G02X101279Y91345I107J170D01*
G01Y91346D01*
G02X101309Y91451I200J0D01*
G37*
G36*
G01X122493Y91647D02*
X126540Y99122D01*
G02X126716Y99227I176J-95D01*
G02X126916Y99027I0J-200D01*
G02X126892Y98932I-200J0D01*
G01X123035Y91809D01*
G03X123115Y91539I176J-95D01*
G01X123342Y91415D01*
X124939Y90549D01*
G03X125210Y90630I95J176D01*
G01X129067Y97753D01*
G02X129243Y97858I176J-95D01*
G02X129443Y97658I0J-200D01*
G02X129419Y97563I-200J0D01*
G01X125372Y90088D01*
G02X125196Y89983I-176J95D01*
G02X125101Y90007I0J200D01*
G01X122574Y91376D01*
G02X122469Y91552I95J176D01*
G02X122493Y91647I200J0D01*
G37*
G36*
G01X80880Y92433D02*
X85793Y99370D01*
G02X85956Y99454I163J-116D01*
G02X86156Y99254I0J-200D01*
G02X86119Y99138I-200J0D01*
G01X81438Y92528D01*
G03X81485Y92249I163J-116D01*
G01X83177Y91051D01*
G03X83456Y91098I116J163D01*
G01X88138Y97709D01*
G02X88301Y97793I163J-116D01*
G02X88501Y97593I0J-200D01*
G02X88464Y97477I-200J0D01*
G01X83551Y90540D01*
G02X83388Y90456I-163J116D01*
G02X83272Y90493I0J200D01*
G01X80927Y92154D01*
G02X80843Y92317I116J163D01*
G02X80880Y92433I200J0D01*
G37*
G36*
G01X207077Y94893D02*
X208408Y103289D01*
G02X208606Y103458I198J-31D01*
G02X208806Y103259I0J-200D01*
G01Y103257D01*
G02X208804Y103227I-200J-2D01*
G01X207535Y95226D01*
G03X207702Y94997I198J-31D01*
G01X209750Y94672D01*
G03X209979Y94839I31J198D01*
G01X211247Y102839D01*
G02X211445Y103008I198J-31D01*
G02X211645Y102809I0J-200D01*
G01Y102807D01*
G02X211643Y102777I-200J-2D01*
G01X210312Y94381D01*
G02X210115Y94212I-198J31D01*
G01X210113D01*
G02X210083Y94214I-2J200D01*
G01X207244Y94664D01*
G02X207075Y94861I31J198D01*
G01Y94863D01*
G02X207077Y94893I200J2D01*
G37*
G36*
G01X266571Y103752D02*
G03X266761I95J176D01*
G02X268416Y104168I1656J-3087D01*
G02X271908Y100934I0J-3502D01*
G03X271989Y100788I200J15D01*
G02X272651Y100153I-2073J-2823D01*
G03X272851Y100083I156J125D01*
G02X273616Y100168I767J-3418D01*
G02Y93162I0J-3503D01*
G02X270881Y94477I0J3502D01*
G03X270681Y94547I-156J-125D01*
G02X269916Y94462I-767J3418D01*
G02X268261Y94878I1J3503D01*
G03X268071I-95J-176D01*
G02X266416Y94462I-1656J3087D01*
G02X264761Y94878I1J3503D01*
G03X264571I-95J-176D01*
G02X262916Y94462I-1656J3087D01*
G02X259424Y97696I0J3502D01*
G03X259343Y97842I-200J-15D01*
G02X257914Y100665I2073J2823D01*
G02X261416Y104168I3502J1D01*
G02X263071Y103752I-1J-3503D01*
G03X263261I95J176D01*
G02X264916Y104168I1656J-3087D01*
G02X266571Y103752I-1J-3503D01*
G37*
G36*
G01X187789Y96285D02*
X189965Y104502D01*
G02X190158Y104651I193J-50D01*
G02X190358Y104452I0J-200D01*
G01Y104451D01*
G02X190351Y104400I-200J1D01*
G01X188278Y96569D01*
G03X188420Y96325I193J-51D01*
G01X190425Y95794D01*
G03X190669Y95936I51J193D01*
G01X192743Y103767D01*
G02X192936Y103916I193J-50D01*
G02X193136Y103717I0J-200D01*
G01Y103716D01*
G02X193129Y103665I-200J1D01*
G01X190953Y95448D01*
G02X190761Y95299I-193J50D01*
G01X190760D01*
G02X190709Y95306I1J200D01*
G01X187931Y96041D01*
G02X187782Y96233I50J193D01*
G01Y96234D01*
G02X187789Y96285I200J-1D01*
G37*
G36*
G01X135975Y97425D02*
X139796Y105017D01*
G02X139975Y105127I179J-91D01*
G02X140175Y104927I0J-200D01*
G01Y104926D01*
G02X140154Y104837I-200J0D01*
G01X136513Y97603D01*
G03X136602Y97334I179J-90D01*
G01X138453Y96402D01*
G03X138722Y96491I90J179D01*
G01X142363Y103725D01*
G02X142542Y103835I179J-91D01*
G02X142742Y103635I0J-200D01*
G01Y103634D01*
G02X142721Y103545I-200J0D01*
G01X138900Y95953D01*
G02X138721Y95843I-179J91D01*
G01X138720D01*
G02X138631Y95864I0J200D01*
G01X136064Y97156D01*
G02X135954Y97335I91J179D01*
G01Y97336D01*
G02X135975Y97425I200J0D01*
G37*
G36*
G01X1741886Y105380D02*
G03X1742076I95J176D01*
G02X1743731Y105796I1656J-3087D01*
G02X1747049Y103414I0J-3502D01*
G03X1747141Y103303I190J64D01*
G02X1748844Y101047I-1706J-3059D01*
G03X1749019Y100894I195J46D01*
G02X1752188Y97408I-333J-3486D01*
G02X1748686Y93906I-3502J0D01*
G02X1745277Y96605I0J3502D01*
G03X1745102Y96758I-195J-46D01*
G02X1743779Y97157I330J3487D01*
G03X1743591I-94J-176D01*
G02X1741935Y96742I-1654J3087D01*
G02X1740279Y97157I-2J3502D01*
G03X1740091I-94J-176D01*
G02X1738437Y96742I-1654J3087D01*
G01X1738435D01*
G02X1735117Y99123I0J3502D01*
G03X1735025Y99234I-190J-64D01*
G02X1733228Y102293I1705J3059D01*
G02X1736731Y105796I3503J0D01*
G02X1738386Y105380I-1J-3503D01*
G03X1738576I95J176D01*
G02X1740231Y105796I1656J-3087D01*
G02X1741886Y105380I-1J-3503D01*
G37*
G36*
G01X696065Y107949D02*
G02X697721Y108364I1654J-3087D01*
G02X699377Y107949I2J-3502D01*
G03X699565I94J176D01*
G02X701219Y108364I1654J-3087D01*
G01X701221D01*
G02X704713Y105131I0J-3502D01*
G03X704794Y104985I200J15D01*
G02X705722Y103968I-2073J-2823D01*
G03X705938Y103876I171J103D01*
G02X706716Y103964I780J-3414D01*
G01X706721D01*
G02Y96960I0J-3502D01*
G02X703720Y98656I0J3503D01*
G03X703504Y98748I-171J-103D01*
G02X702721Y98660I-780J3414D01*
G02X701065Y99075I-2J3502D01*
G03X700877I-94J-176D01*
G02X699221Y98660I-1654J3087D01*
G02X697565Y99075I-2J3502D01*
G03X697377I-94J-176D01*
G02X695723Y98660I-1654J3087D01*
G01X695721D01*
G02X692229Y101893I0J3502D01*
G03X692148Y102039I-200J-15D01*
G02X690718Y104862I2071J2823D01*
G02X694221Y108364I3503J-1D01*
G01X694223D01*
G02X695877Y107949I0J-3502D01*
G03X696065I94J176D01*
G37*
G36*
G01X552105Y110700D02*
G02Y113706I0J1503D01*
G01X555505D01*
G02Y110700I0J-1503D01*
G01X552105D01*
G37*
G36*
G01X173110Y111944D02*
X176022Y119929D01*
G02X176210Y120060I188J-69D01*
G02X176410Y119860I0J-200D01*
G01Y119859D01*
G02X176398Y119791I-200J0D01*
G01X173623Y112182D01*
G03X173742Y111925I188J-69D01*
G01X175691Y111215D01*
G03X175948Y111334I69J188D01*
G01X178722Y118944D01*
G02X178910Y119075I188J-69D01*
G02X179110Y118875I0J-200D01*
G01Y118874D01*
G02X179098Y118806I-200J0D01*
G01X176186Y110821D01*
G02X175998Y110690I-188J69D01*
G01X175997D01*
G02X175929Y110702I0J200D01*
G01X173229Y111687D01*
G02X173098Y111875I69J188D01*
G01Y111876D01*
G02X173110Y111944I200J0D01*
G37*
G36*
G01X791363Y124244D02*
G03X791499I68J188D01*
G02X792681Y124450I1184J-3297D01*
G02Y117444I0J-3503D01*
G02X792393Y117456I2J3503D01*
G03X792191Y117331I-16J-199D01*
G02X788941Y115134I-3250J1305D01*
G02X787759Y115340I2J3503D01*
G03X787623I-68J-188D01*
G02X786441Y115134I-1184J3297D01*
G02X785259Y115340I2J3503D01*
G03X785123I-68J-188D01*
G02X783941Y115134I-1184J3297D01*
G02X782759Y115340I2J3503D01*
G03X782623I-68J-188D01*
G02X781441Y115134I-1184J3297D01*
G02Y122140I0J3503D01*
G02X781729Y122128I-2J-3503D01*
G03X781931Y122253I16J199D01*
G02X785181Y124450I3250J-1305D01*
G02X786363Y124244I-2J-3503D01*
G03X786499I68J188D01*
G02X787681Y124450I1184J-3297D01*
G02X788863Y124244I-2J-3503D01*
G03X788999I68J188D01*
G02X790181Y124450I1184J-3297D01*
G02X791363Y124244I-2J-3503D01*
G37*
G36*
G01X472895Y128518D02*
G02Y131522I0J1502D01*
G01X476295D01*
G02Y128518I0J-1502D01*
G01X472895D01*
G37*
G36*
G01X47255Y123148D02*
X51557Y127748D01*
G02X69964Y110535I9203J-8607D01*
G01X65662Y105934D01*
G02X47255Y123148I-9203J8607D01*
G37*
G36*
G01X490380Y129940D02*
G02Y132944I0J1502D01*
G01X493780D01*
G02Y129940I0J-1502D01*
G01X490380D01*
G37*
G36*
G01X169524Y127832D02*
X172844Y135657D01*
G02X173028Y135779I184J-78D01*
G02X173228Y135579I0J-200D01*
G02X173212Y135501I-200J0D01*
G01X170048Y128044D01*
G03X170154Y127782I184J-78D01*
G01X172064Y126971D01*
G03X172326Y127077I78J184D01*
G01X175490Y134534D01*
G02X175674Y134656I184J-78D01*
G02X175874Y134456I0J-200D01*
G02X175858Y134378I-200J0D01*
G01X172538Y126553D01*
G02X172354Y126431I-184J78D01*
G02X172276Y126447I0J200D01*
G01X169630Y127570D01*
G02X169508Y127754I78J184D01*
G02X169524Y127832I200J0D01*
G37*
G36*
G01X482380Y140440D02*
G02Y143444I0J1502D01*
G01X485780D01*
G02Y140440I0J-1502D01*
G01X482380D01*
G37*
G36*
G01X779327Y150364D02*
G03X779471Y150499I-47J194D01*
G02X782819Y152974I3348J-1027D01*
G02X786322Y149471I0J-3503D01*
G02X783651Y146068I-3503J0D01*
G03X783507Y145933I47J-194D01*
G02X780159Y143458I-3348J1027D01*
G02X776656Y146961I0J3503D01*
G02X779327Y150364I3503J0D01*
G37*
G36*
G01X975691Y157718D02*
G02Y164722I0J3502D01*
G01X975693D01*
G02X978131Y163733I-1J-3502D01*
G01X978159Y163705D01*
X978231Y163676D01*
X978548Y163675D01*
G03X978686Y163730I0J200D01*
G01X978687Y163731D01*
G02X981112Y164706I2425J-2528D01*
G02Y157702I0J-3502D01*
G01X981110D01*
G02X978672Y158691I1J3502D01*
G01X978644Y158719D01*
X978572Y158748D01*
X978255Y158749D01*
G03X978117Y158694I0J-200D01*
G01X978116Y158693D01*
G02X975691Y157718I-2425J2528D01*
G37*
G36*
G01X959376Y169081D02*
G02X959170Y170263I3297J1184D01*
G02X966176I3503J0D01*
G02X965970Y169081I-3503J2D01*
G03Y168945I188J-68D01*
G02X966176Y167763I-3297J-1184D01*
G02X959170I-3503J0D01*
G02X959376Y168945I3503J-2D01*
G03Y169081I-188J68D01*
G37*
G36*
G01X946854Y179703D02*
G03X946999Y179709I65J189D01*
G02X948401Y180002I1402J-3210D01*
G02X951904Y176499I0J-3503D01*
G02X949342Y173125I-3503J0D01*
G03X949197Y172957I54J-193D01*
G02X945721Y169886I-3476J432D01*
G02X944539Y170092I2J3503D01*
G03X944403I-68J-188D01*
G02X943221Y169886I-1184J3297D01*
G02X942039Y170092I2J3503D01*
G03X941903I-68J-188D01*
G02X940721Y169886I-1184J3297D01*
G02X939510Y170103I3J3503D01*
G03X939372I-69J-188D01*
G02X938161Y169886I-1214J3286D01*
G02X937002Y170084I2J3503D01*
G03X936861Y170081I-67J-189D01*
G02X935551Y169826I-1312J3248D01*
G02X932048Y173329I0J3503D01*
G02X932313Y174663I3503J-2D01*
G03X932315Y174810I-185J76D01*
G02X932088Y176049I3276J1240D01*
G02X935591Y179552I3503J0D01*
G01X935592D01*
G02X936376Y179463I-1J-3503D01*
G03X936515Y179481I45J195D01*
G02X938161Y179892I1646J-3091D01*
G02X939372Y179675I-3J-3503D01*
G03X939510I69J188D01*
G02X940721Y179892I1214J-3286D01*
G02X941903Y179686I-2J-3503D01*
G03X942039I68J188D01*
G02X943221Y179892I1184J-3297D01*
G02X944403Y179686I-2J-3503D01*
G03X944539I68J188D01*
G02X945721Y179892I1184J-3297D01*
G02X946854Y179703I-2J-3503D01*
G37*
G36*
G01X365287Y173422D02*
G02Y197050I0J11814D01*
G01X371587D01*
G02Y173422I0J-11814D01*
G01X365287D01*
G37*
G36*
G01X247177Y172636D02*
G02Y197836I0J12600D01*
G01X253476D01*
G02Y172636I0J-12600D01*
G01X247177D01*
G37*
G36*
G01X987564Y209093D02*
G03X987721Y209152I15J199D01*
G02X990221Y210202I2501J-2453D01*
G02X993724Y206699I0J-3503D01*
G02X993308Y205044I-3503J1D01*
G03Y204854I176J-95D01*
G02X993724Y203199I-3087J-1656D01*
G02X993308Y201544I-3503J1D01*
G03Y201354I176J-95D01*
G02X993724Y199699I-3087J-1656D01*
G02X990221Y196196I-3503J0D01*
G02X989978Y196205I8J3503D01*
G03X989821Y196146I-15J-199D01*
G02X989542Y195890I-2504J2449D01*
G03X989471Y195701I126J-155D01*
G02X989524Y195099I-3450J-607D01*
G02X982518I-3503J0D01*
G02X983800Y197808I3503J0D01*
G03X983871Y197997I-126J155D01*
G02X983818Y198598I3450J607D01*
G01Y198600D01*
G02X983819Y198660I3503J-28D01*
G02X982055Y199171I59J3502D01*
G03X981837Y199165I-104J-170D01*
G02X979849Y198546I-1988J2884D01*
G02X977910Y199132I1J3503D01*
G03X977688I-111J-166D01*
G02X975749Y198546I-1940J2917D01*
G02X972359Y201167I0J3503D01*
G03X972153Y201317I-194J-50D01*
G02X971943Y201310I-222J3496D01*
G02X970051Y201866I2J3503D01*
G03X969835I-108J-169D01*
G02X967943Y201310I-1894J2947D01*
G02X964686Y203525I0J3502D01*
G03X964536Y203648I-186J-74D01*
G02X963305Y205125I271J1477D01*
G02X964807Y206627I1502J0D01*
G01X964833D01*
G03X965004Y206718I3J200D01*
G02X967943Y208316I2939J-1904D01*
G02X969835Y207760I-2J-3503D01*
G03X970051I108J169D01*
G02X971943Y208316I1894J-2947D01*
G02X974028Y207627I-1J-3503D01*
G01X974059Y207604D01*
X974131Y207584D01*
X974478Y207624D01*
X974544Y207658D01*
X974569Y207687D01*
G02X977221Y208902I2652J-2287D01*
G02X980718Y205584I0J-3502D01*
G03X980860Y205403I200J11D01*
G02X981673Y205040I-1010J-3354D01*
G03X981891Y205046I104J170D01*
G02X983641Y205656I1987J-2884D01*
G03X983827Y205842I-14J200D01*
G02X987321Y209102I3494J-242D01*
G02X987564Y209093I-8J-3503D01*
G37*
G36*
G01X860942Y329356D02*
G02Y332360I0J1502D01*
G01X864342D01*
G02Y329356I0J-1502D01*
G01X860942D01*
G37*
G36*
G01X920139Y309612D02*
G02X937341I8601J12042D01*
G01X920139D01*
G37*
G36*
G01X857187Y340708D02*
G02Y343712I0J1502D01*
G01X860587D01*
G02Y340708I0J-1502D01*
G01X857187D01*
G37*
G36*
G01X45960Y427304D02*
G02Y430308I0J1502D01*
G01X49360D01*
G02Y427304I0J-1502D01*
G01X45960D01*
G37*
G36*
G01X60921Y429304D02*
G02Y432308I0J1502D01*
G01X64821D01*
G02Y429304I0J-1502D01*
G01X60921D01*
G37*
G36*
G01X45812Y450100D02*
G02Y453104I0J1502D01*
G01X49212D01*
G02Y450100I0J-1502D01*
G01X45812D01*
G37*
G36*
G01X644414Y569666D02*
G02Y572672I0J1503D01*
G01X648314D01*
G02Y569666I0J-1503D01*
G01X644414D01*
G37*
G36*
G01X646358Y588814D02*
G02Y591818I0J1502D01*
G01X650258D01*
G02Y588814I0J-1502D01*
G01X646358D01*
G37*
G36*
G01X634794Y589002D02*
G02Y592006I0J1502D01*
G01X638694D01*
G02Y589002I0J-1502D01*
G01X634794D01*
G37*
G36*
G01X469014Y604311D02*
G03X469148I67J188D01*
G02X470331Y604516I1181J-3297D01*
G02X473834Y601014I1J-3502D01*
G02X473628Y599832I-3503J2D01*
G03Y599696I188J-68D01*
G02X473834Y598514I-3297J-1184D01*
G02X470331Y595012I-3503J1D01*
G01X470328D01*
G02X469148Y595217I1J3502D01*
G03X469014I-67J-188D01*
G02X467831Y595012I-1181J3297D01*
G02X466648Y595217I-2J3502D01*
G03X466514I-67J-188D01*
G02X465331Y595012I-1181J3297D01*
G02X464148Y595217I-2J3502D01*
G03X464014I-67J-188D01*
G02X462831Y595012I-1181J3297D01*
G02X461592Y595238I-1J3502D01*
G03X461450I-71J-187D01*
G02X460211Y595012I-1238J3276D01*
G02X459028Y595217I-2J3502D01*
G03X458894I-67J-188D01*
G02X457711Y595012I-1181J3297D01*
G02X454208Y598514I-1J3502D01*
G02X454414Y599696I3503J-2D01*
G03Y599832I-188J68D01*
G02X454208Y601014I3297J1184D01*
G02X457711Y604516I3503J-1D01*
G01X457714D01*
G02X458894Y604311I-1J-3502D01*
G03X459028I67J188D01*
G02X460211Y604516I1181J-3297D01*
G02X461450Y604290I1J-3502D01*
G03X461592I71J187D01*
G02X462831Y604516I1238J-3276D01*
G02X464014Y604311I2J-3502D01*
G03X464148I67J188D01*
G02X465331Y604516I1181J-3297D01*
G02X466514Y604311I2J-3502D01*
G03X466648I67J188D01*
G02X467831Y604516I1181J-3297D01*
G02X469014Y604311I2J-3502D01*
G37*
G36*
G01X509510Y613939D02*
Y613940D01*
G02X516514I3502J0D01*
G01Y613939D01*
G02X516234Y612568I-3502J1D01*
G03X516235Y612412I185J-77D01*
G02X516372Y612030I-3223J-1372D01*
G03X516544Y611887I192J56D01*
G02X517354Y611708I-338J-3451D01*
G03X517486I66J189D01*
G02X518635Y611904I1149J-3272D01*
G02Y604968I0J-3468D01*
G02X517486Y605164I0J3468D01*
G03X517354I-66J-189D01*
G02X516205Y604968I-1149J3272D01*
G02X515056Y605164I0J3468D01*
G03X514924I-66J-189D01*
G02X514513Y605048I-1146J3273D01*
G02X514514Y605003I-3501J-100D01*
G01Y604999D01*
G02X514234Y603629I-3503J2D01*
G03Y603473I184J-78D01*
G02X514514Y602101I-3223J-1372D01*
G02X511011Y598598I-3503J0D01*
G02X508840Y599353I1J3503D01*
G03X508609Y599365I-124J-157D01*
G02X506745Y598828I-1864J2967D01*
G02X503242Y602331I0J3503D01*
G02X503522Y603703I3503J0D01*
G03Y603859I-184J78D01*
G02X503242Y605231I3223J1372D01*
G02X503522Y606603I3503J0D01*
G03Y606759I-184J78D01*
G02X503242Y608131I3223J1372D01*
G02X506745Y611634I3503J0D01*
G02X508871Y610914I-1J-3503D01*
G01X508916Y610880D01*
X509025Y610868D01*
X509449Y611065D01*
X509511Y611157D01*
X509514Y611212D01*
G02X509790Y612412I3498J-173D01*
G03Y612568I-184J78D01*
G02X509510Y613939I3222J1372D01*
G37*
G36*
G01X1525960Y621415D02*
G03X1526094I67J188D01*
G02X1527277Y621620I1181J-3297D01*
G02X1530780Y618118I1J-3502D01*
G02X1530574Y616936I-3503J2D01*
G03Y616800I188J-68D01*
G02X1530780Y615618I-3297J-1184D01*
G02X1530569Y614421I-3503J0D01*
G03Y614285I188J-68D01*
G02X1530780Y613088I-3292J-1197D01*
G02X1530574Y611906I-3503J2D01*
G03Y611770I188J-68D01*
G02X1530780Y610588I-3297J-1184D01*
G02X1530556Y609358I-3503J2D01*
G03Y609218I188J-70D01*
G02X1530780Y607988I-3279J-1232D01*
G02X1530574Y606806I-3503J2D01*
G03Y606670I188J-68D01*
G02X1530780Y605488I-3297J-1184D01*
G02X1527277Y601986I-3503J1D01*
G01X1527274D01*
G02X1526094Y602191I1J3502D01*
G03X1525960I-67J-188D01*
G02X1524777Y601986I-1181J3297D01*
G02X1521274Y605488I-1J3502D01*
G02X1521480Y606670I3503J-2D01*
G03Y606806I-188J68D01*
G02X1521274Y607988I3297J1184D01*
G02X1521498Y609218I3503J-2D01*
G03Y609358I-188J70D01*
G02X1521274Y610588I3279J1232D01*
G02X1521480Y611770I3503J-2D01*
G03Y611906I-188J68D01*
G02X1521274Y613088I3297J1184D01*
G02X1521485Y614285I3503J0D01*
G03Y614421I-188J68D01*
G02X1521274Y615618I3292J1197D01*
G02X1521480Y616800I3503J-2D01*
G03Y616936I-188J68D01*
G02X1521274Y618118I3297J1184D01*
G02X1524777Y621620I3503J-1D01*
G01X1524780D01*
G02X1525960Y621415I-1J-3502D01*
G37*
G36*
G01X1357462Y632413D02*
Y632414D01*
G02X1364466I3502J0D01*
G01Y632413D01*
G02X1364186Y631042I-3502J1D01*
G03X1364187Y630886I185J-77D01*
G02X1364411Y630133I-3224J-1369D01*
G03X1364567Y629973I197J36D01*
G02X1365006Y629851I-707J-3395D01*
G03X1365138I66J189D01*
G02X1366283Y630046I1146J-3272D01*
G01X1366287D01*
G02Y623112I0J-3467D01*
G01X1366283D01*
G02X1365138Y623307I1J3467D01*
G03X1365006I-66J-189D01*
G02X1363857Y623112I-1146J3272D01*
G02X1362708Y623307I-3J3467D01*
G03X1362576I-66J-189D01*
G02X1362165Y623191I-1146J3273D01*
G02X1362166Y623146I-3501J-100D01*
G01Y623142D01*
G02X1361886Y621772I-3503J2D01*
G03Y621616I184J-78D01*
G02X1362166Y620244I-3223J-1372D01*
G02X1358663Y616742I-3503J1D01*
G01X1358662D01*
G02X1356492Y617496I1J3502D01*
G03X1356261Y617508I-124J-157D01*
G02X1354397Y616972I-1862J2967D01*
G02X1350894Y620474I-1J3502D01*
G02X1351174Y621846I3503J0D01*
G03Y622002I-184J78D01*
G02X1350894Y623374I3223J1372D01*
G02X1351174Y624746I3503J0D01*
G03Y624902I-184J78D01*
G02X1350894Y626274I3223J1372D01*
G02X1354397Y629776I3503J-1D01*
G02X1357197Y628378I0J-3503D01*
G03X1357316Y628302I160J120D01*
G02X1357363Y628292I-705J-3431D01*
G01X1357522Y628461D01*
G03X1357570Y628647I-146J137D01*
G02X1357462Y629514I3394J863D01*
G02X1357742Y630886I3502J0D01*
G03Y631042I-184J78D01*
G02X1357462Y632413I3222J1372D01*
G37*
G36*
G01X1701661Y643052D02*
G02Y646056I0J1502D01*
G01X1705561D01*
G02Y643052I0J-1502D01*
G01X1701661D01*
G37*
G36*
G01X1620462Y642739D02*
Y642741D01*
G02X1627466I3502J0D01*
G01Y642739D01*
G02X1627166Y641322I-3502J1D01*
G03Y641160I183J-81D01*
G02X1627387Y640480I-3203J-1417D01*
G03X1627543Y640326I196J42D01*
G02X1628006Y640199I-684J-3400D01*
G03X1628138I66J189D01*
G02X1629283Y640394I1146J-3272D01*
G01X1629287D01*
G02Y633460I0J-3467D01*
G01X1629283D01*
G02X1628138Y633655I1J3467D01*
G03X1628006I-66J-189D01*
G02X1626857Y633460I-1146J3272D01*
G02X1625708Y633655I-3J3467D01*
G03X1625576I-66J-189D01*
G02X1625165Y633539I-1146J3273D01*
G02X1625166Y633494I-3501J-100D01*
G01Y633490D01*
G02X1624886Y632120I-3503J2D01*
G03Y631964I184J-78D01*
G02X1625166Y630592I-3223J-1372D01*
G02X1621663Y627090I-3503J1D01*
G01X1621662D01*
G02X1619492Y627844I1J3502D01*
G03X1619261Y627856I-124J-157D01*
G02X1617397Y627320I-1862J2967D01*
G02X1613894Y630822I-1J3502D01*
G02X1614174Y632194I3503J0D01*
G03Y632350I-184J78D01*
G02X1613894Y633722I3223J1372D01*
G02X1614174Y635094I3503J0D01*
G03Y635250I-184J78D01*
G02X1613894Y636622I3223J1372D01*
G02X1617397Y640124I3503J-1D01*
G01X1617398D01*
G02X1620198Y638726I0J-3504D01*
G03X1620316Y638650I160J119D01*
G02X1620330Y638647I-727J-3426D01*
G01X1620490Y638813D01*
G03X1620542Y638994I-143J139D01*
G02X1620462Y639741I3422J744D01*
G02X1620762Y641160I3502J1D01*
G03Y641322I-183J81D01*
G02X1620462Y642739I3202J1418D01*
G37*
G36*
G01X353915Y649354D02*
G02X355195Y649596I1279J-3260D01*
G02X358698Y646094I1J-3502D01*
G02X358517Y644986I-3502J3D01*
G03X358522Y644848I190J-62D01*
G02X358778Y643534I-3247J-1315D01*
G02X358572Y642352I-3503J2D01*
G03Y642216I188J-68D01*
G02X358778Y641034I-3297J-1184D01*
G02X355275Y637532I-3503J1D01*
G01X355272D01*
G02X354096Y637736I2J3502D01*
G03X353955Y637734I-68J-188D01*
G02X352675Y637492I-1279J3260D01*
G02X351492Y637697I-2J3502D01*
G03X351358I-67J-188D01*
G02X350175Y637492I-1181J3297D01*
G02X348992Y637697I-2J3502D01*
G03X348858I-67J-188D01*
G02X347675Y637492I-1181J3297D01*
G02X346492Y637697I-2J3502D01*
G03X346358I-67J-188D01*
G02X345175Y637492I-1181J3297D01*
G02X343992Y637697I-2J3502D01*
G03X343858I-67J-188D01*
G02X342675Y637492I-1181J3297D01*
G02X339172Y640994I-1J3502D01*
G02X339378Y642176I3503J-2D01*
G03Y642312I-188J68D01*
G02X339172Y643494I3297J1184D01*
G02X339353Y644602I3502J-3D01*
G03X339348Y644740I-190J62D01*
G02X339092Y646054I3247J1315D01*
G02X342595Y649556I3503J-1D01*
G01X342598D01*
G02X343778Y649351I-1J-3502D01*
G03X343912I67J188D01*
G02X345095Y649556I1181J-3297D01*
G02X346278Y649351I2J-3502D01*
G03X346412I67J188D01*
G02X347595Y649556I1181J-3297D01*
G02X348778Y649351I2J-3502D01*
G03X348912I67J188D01*
G02X350095Y649556I1181J-3297D01*
G02X351278Y649351I2J-3502D01*
G03X351412I67J188D01*
G02X352595Y649556I1181J-3297D01*
G02X353774Y649352I1J-3502D01*
G03X353915Y649354I68J188D01*
G37*
G36*
G01X476310Y648139D02*
Y648140D01*
G02X483314I3502J0D01*
G01Y648139D01*
G02X483034Y646768I-3502J1D01*
G03X483035Y646612I185J-77D01*
G02X483202Y646120I-3224J-1369D01*
G03X483369Y645972I194J50D01*
G02X484054Y645808I-461J-3437D01*
G03X484186I66J189D01*
G02X485335Y646004I1149J-3272D01*
G02Y639068I0J-3468D01*
G02X484186Y639264I0J3468D01*
G03X484054I-66J-189D01*
G02X482905Y639068I-1149J3272D01*
G02X481756Y639264I0J3468D01*
G03X481624I-66J-189D01*
G02X481213Y639148I-1146J3273D01*
G02X481214Y639103I-3501J-100D01*
G01Y639099D01*
G02X480934Y637729I-3503J2D01*
G03Y637573I184J-78D01*
G02X481214Y636201I-3223J-1372D01*
G02X477711Y632698I-3503J0D01*
G02X475540Y633453I1J3503D01*
G03X475309Y633465I-124J-157D01*
G02X473445Y632928I-1864J2967D01*
G02X469942Y636431I0J3503D01*
G02X470222Y637803I3503J0D01*
G03Y637959I-184J78D01*
G02X469942Y639331I3223J1372D01*
G02X470222Y640703I3503J0D01*
G03Y640859I-184J78D01*
G02X469942Y642231I3223J1372D01*
G02X473445Y645734I3503J0D01*
G02X475657Y644947I0J-3502D01*
G03X475869Y644921I127J155D01*
G01X476196Y645075D01*
G03X476310Y645255I-86J181D01*
G02X476590Y646612I3502J-15D01*
G03Y646768I-184J78D01*
G02X476310Y648139I3222J1372D01*
G37*
G36*
G01X1452863Y653667D02*
G02X1454046Y653872I1181J-3297D01*
G02X1455229Y653667I2J-3502D01*
G03X1455363I67J188D01*
G02X1456541Y653872I1181J-3297D01*
G01X1456546D01*
G02X1457918Y653592I0J-3502D01*
G03X1458074I78J184D01*
G02X1459445Y653872I1372J-3222D01*
G01X1459446D01*
G02X1462948Y650370I0J-3502D01*
G01Y650365D01*
G02X1462701Y649077I-3502J4D01*
G03X1462699Y648936I186J-73D01*
G02X1462898Y647770I-3303J-1164D01*
G02X1462693Y646587I-3502J-2D01*
G03Y646453I188J-67D01*
G02X1462898Y645273I-3297J-1181D01*
G01Y645270D01*
G02X1459396Y641768I-3502J0D01*
G01X1459395D01*
G02X1458024Y642048I1J3502D01*
G03X1457868I-78J-184D01*
G02X1456496Y641768I-1372J3222D01*
G01X1456491D01*
G02X1455313Y641973I3J3502D01*
G03X1455179I-67J-188D01*
G02X1453996Y641768I-1181J3297D01*
G02X1452813Y641973I-2J3502D01*
G03X1452679I-67J-188D01*
G02X1451496Y641768I-1181J3297D01*
G02X1450313Y641973I-2J3502D01*
G03X1450179I-67J-188D01*
G02X1448996Y641768I-1181J3297D01*
G02X1447757Y641994I-1J3502D01*
G03X1447615I-71J-187D01*
G02X1446376Y641768I-1238J3276D01*
G02X1445193Y641973I-2J3502D01*
G03X1445059I-67J-188D01*
G02X1443879Y641768I-1181J3297D01*
G01X1443876D01*
G02X1440374Y645270I0J3502D01*
G01Y645273D01*
G02X1440579Y646453I3502J-1D01*
G03Y646587I-188J67D01*
G02X1440374Y647770I3297J1181D01*
G02X1440621Y649063I3502J1D01*
G03X1440623Y649204I-186J73D01*
G02X1440424Y650366I3303J1164D01*
G01Y650370D01*
G02X1443926Y653872I3502J0D01*
G01X1443929D01*
G02X1445109Y653667I-1J-3502D01*
G03X1445243I67J188D01*
G02X1446426Y653872I1181J-3297D01*
G02X1447665Y653646I1J-3502D01*
G03X1447807I71J187D01*
G02X1449046Y653872I1238J-3276D01*
G02X1450229Y653667I2J-3502D01*
G03X1450363I67J188D01*
G02X1451546Y653872I1181J-3297D01*
G02X1452729Y653667I2J-3502D01*
G03X1452863I67J188D01*
G37*
G36*
G01X1587462Y661739D02*
Y661741D01*
G02X1594466I3502J0D01*
G01Y661739D01*
G02X1594166Y660322I-3502J1D01*
G03Y660160I183J-81D01*
G02X1594387Y659480I-3203J-1417D01*
G03X1594543Y659326I196J42D01*
G02X1595006Y659199I-684J-3400D01*
G03X1595138I66J189D01*
G02X1596283Y659394I1146J-3272D01*
G01X1596287D01*
G02Y652460I0J-3467D01*
G01X1596283D01*
G02X1595138Y652655I1J3467D01*
G03X1595006I-66J-189D01*
G02X1593857Y652460I-1146J3272D01*
G02X1592708Y652655I-3J3467D01*
G03X1592576I-66J-189D01*
G02X1592165Y652539I-1146J3273D01*
G02X1592166Y652494I-3501J-100D01*
G01Y652490D01*
G02X1591886Y651120I-3503J2D01*
G03Y650964I184J-78D01*
G02X1592166Y649592I-3223J-1372D01*
G02X1588663Y646090I-3503J1D01*
G01X1588662D01*
G02X1586492Y646844I1J3502D01*
G03X1586261Y646856I-124J-157D01*
G02X1584397Y646320I-1862J2967D01*
G02X1580894Y649822I-1J3502D01*
G02X1581174Y651194I3503J0D01*
G03Y651350I-184J78D01*
G02X1580894Y652722I3223J1372D01*
G02X1581174Y654094I3503J0D01*
G03Y654250I-184J78D01*
G02X1580894Y655622I3223J1372D01*
G02X1584397Y659124I3503J-1D01*
G01X1584398D01*
G02X1587198Y657726I0J-3504D01*
G03X1587316Y657650I160J119D01*
G02X1587330Y657647I-727J-3426D01*
G01X1587490Y657813D01*
G03X1587542Y657994I-143J139D01*
G02X1587462Y658741I3422J744D01*
G02X1587762Y660160I3502J1D01*
G03Y660322I-183J81D01*
G02X1587462Y661739I3202J1418D01*
G37*
G36*
G01X246810Y663079D02*
Y663080D01*
G02X253814I3502J0D01*
G01Y663079D01*
G02X253534Y661708I-3502J1D01*
G03X253535Y661552I185J-77D01*
G02X253756Y660818I-3223J-1371D01*
G03X253917Y660658I197J37D01*
G02X254454Y660517I-609J-3414D01*
G03X254586I66J189D01*
G02X255731Y660712I1146J-3272D01*
G01X255735D01*
G02Y653778I0J-3467D01*
G01X255731D01*
G02X254586Y653973I1J3467D01*
G03X254454I-66J-189D01*
G02X253305Y653778I-1146J3272D01*
G02X252156Y653973I-3J3467D01*
G03X252024I-66J-189D01*
G02X251613Y653857I-1146J3273D01*
G02X251614Y653812I-3501J-100D01*
G01Y653808D01*
G02X251334Y652438I-3503J2D01*
G03Y652282I184J-78D01*
G02X251614Y650910I-3223J-1372D01*
G02X248111Y647408I-3503J1D01*
G01X248110D01*
G02X245940Y648162I1J3502D01*
G03X245709Y648174I-124J-157D01*
G02X243845Y647638I-1862J2967D01*
G02X240342Y651140I-1J3502D01*
G02X240622Y652512I3503J0D01*
G03Y652668I-184J78D01*
G02X240342Y654040I3223J1372D01*
G02X240622Y655412I3503J0D01*
G03Y655568I-184J78D01*
G02X240342Y656940I3223J1372D01*
G02X243845Y660442I3503J-1D01*
G01X243846D01*
G02X246158Y659570I0J-3502D01*
G01X246204Y659529D01*
X246324Y659514D01*
X246711Y659708D01*
G03X246821Y659902I-89J179D01*
G02X246810Y660179I3491J277D01*
G01Y660180D01*
G02X247090Y661552I3502J0D01*
G03Y661708I-184J78D01*
G02X246810Y663079I3222J1372D01*
G37*
G36*
G01X1390162Y665283D02*
Y665284D01*
G02X1397166I3502J0D01*
G01Y665283D01*
G02X1396886Y663912I-3502J1D01*
G03Y663756I184J-78D01*
G02X1397105Y663033I-3223J-1371D01*
G03X1397261Y662874I197J37D01*
G02X1397706Y662751I-699J-3396D01*
G03X1397838I66J189D01*
G02X1398983Y662946I1146J-3272D01*
G01X1398987D01*
G02Y656012I0J-3467D01*
G01X1398983D01*
G02X1397838Y656207I1J3467D01*
G03X1397706I-66J-189D01*
G02X1396557Y656012I-1146J3272D01*
G02X1395408Y656207I-3J3467D01*
G03X1395276I-66J-189D01*
G02X1394865Y656091I-1146J3273D01*
G02X1394866Y656046I-3501J-100D01*
G01Y656042D01*
G02X1394586Y654672I-3503J2D01*
G03Y654516I184J-78D01*
G02X1394866Y653144I-3223J-1372D01*
G02X1391363Y649642I-3503J1D01*
G01X1391362D01*
G02X1389192Y650396I1J3502D01*
G03X1388961Y650408I-124J-157D01*
G02X1387097Y649872I-1862J2967D01*
G02X1383594Y653374I-1J3502D01*
G02X1383874Y654746I3503J0D01*
G03Y654902I-184J78D01*
G02X1383594Y656274I3223J1372D01*
G02X1383874Y657646I3503J0D01*
G03Y657802I-184J78D01*
G02X1383594Y659174I3223J1372D01*
G02X1387097Y662676I3503J-1D01*
G02X1389897Y661278I0J-3503D01*
G03X1390016Y661202I160J120D01*
G02X1390055Y661194I-684J-3435D01*
G01X1390214Y661362D01*
G03X1390263Y661547I-145J138D01*
G02X1390162Y662380I3401J835D01*
G01Y662384D01*
G02X1390442Y663756I3502J0D01*
G03Y663912I-184J78D01*
G02X1390162Y665283I3222J1372D01*
G37*
G36*
G01X635567Y670272D02*
G02Y673276I0J1502D01*
G01X638967D01*
G02Y670272I0J-1502D01*
G01X635567D01*
G37*
G36*
G01X443710Y674539D02*
Y674540D01*
G02X450714I3502J0D01*
G01Y674539D01*
G02X450434Y673168I-3502J1D01*
G03X450435Y673012I185J-77D01*
G02X450575Y672618I-3225J-1368D01*
G03X450742Y672476I192J56D01*
G02X451454Y672308I-436J-3440D01*
G03X451586I66J189D01*
G02X452735Y672504I1149J-3272D01*
G02Y665568I0J-3468D01*
G02X451586Y665764I0J3468D01*
G03X451454I-66J-189D01*
G02X450305Y665568I-1149J3272D01*
G02X449156Y665764I0J3468D01*
G03X449024I-66J-189D01*
G02X448613Y665648I-1146J3273D01*
G02X448614Y665603I-3501J-100D01*
G01Y665599D01*
G02X448334Y664229I-3503J2D01*
G03Y664073I184J-78D01*
G02X448614Y662701I-3223J-1372D01*
G02X445111Y659198I-3503J0D01*
G02X442940Y659953I1J3503D01*
G03X442709Y659965I-124J-157D01*
G02X440845Y659428I-1864J2967D01*
G02X437342Y662931I0J3503D01*
G02X437622Y664303I3503J0D01*
G03Y664459I-184J78D01*
G02X437342Y665831I3223J1372D01*
G02X437622Y667203I3503J0D01*
G03Y667359I-184J78D01*
G02X437342Y668731I3223J1372D01*
G02X440845Y672234I3503J0D01*
G02X443057Y671445I-2J-3502D01*
G01X443059D01*
Y671444D01*
G03X443267Y671418I125J156D01*
G01X443594Y671567D01*
G03X443711Y671743I-83J182D01*
G01Y671744D01*
G02X443990Y673012I3501J-106D01*
G03Y673168I-184J78D01*
G02X443710Y674539I3222J1372D01*
G37*
G36*
G01X1554692Y695499D02*
Y695501D01*
G02X1561696I3502J0D01*
G01Y695499D01*
G02X1561396Y694082I-3502J1D01*
G03Y693920I183J-81D01*
G02X1561616Y693249I-3201J-1421D01*
G03X1561772Y693095I196J42D01*
G02X1562236Y692968I-681J-3400D01*
G03X1562368I66J189D01*
G02X1563517Y693164I1149J-3272D01*
G02Y686228I0J-3468D01*
G02X1562368Y686424I0J3468D01*
G03X1562236I-66J-189D01*
G02X1561087Y686228I-1149J3272D01*
G02X1559938Y686424I0J3468D01*
G03X1559806I-66J-189D01*
G02X1559395Y686308I-1146J3273D01*
G02X1559396Y686263I-3501J-100D01*
G01Y686259D01*
G02X1559116Y684889I-3503J2D01*
G03Y684733I184J-78D01*
G02X1559396Y683361I-3223J-1372D01*
G02X1559161Y682101I-3503J1D01*
G03X1559168Y681940I186J-73D01*
G02X1559530Y680391I-3141J-1551D01*
G02X1556581Y676933I-3502J0D01*
G03X1556453Y676856I32J-198D01*
G02X1553657Y675462I-2797J2109D01*
G02X1550154Y678965I0J3503D01*
G02X1550455Y680384I3503J-2D01*
G03Y680546I-183J81D01*
G02X1550154Y681965I3202J1421D01*
G02X1550494Y683470I3503J0D01*
G03X1550498Y683634I-180J86D01*
G02X1550224Y684991I3229J1358D01*
G02X1550574Y686516I3503J-1D01*
G03X1550579Y686678I-180J87D01*
G02X1550324Y687989I3248J1312D01*
G01Y687991D01*
G02X1553827Y691494I3503J0D01*
G02X1554292Y691463I0J-3503D01*
G01X1554340Y691456D01*
X1554429Y691487D01*
X1554686Y691752D01*
G03X1554739Y691925I-144J139D01*
G02X1554692Y692501I3455J572D01*
G02X1554992Y693920I3502J1D01*
G03Y694082I-183J81D01*
G02X1554692Y695499I3202J1418D01*
G37*
G36*
G01X279540Y697279D02*
Y697280D01*
G02X286544I3502J0D01*
G01Y697279D01*
G02X286264Y695908I-3502J1D01*
G03Y695752I184J-78D01*
G02X286477Y695066I-3221J-1376D01*
G03X286638Y694908I196J39D01*
G02X287184Y694765I-603J-3415D01*
G03X287316I66J189D01*
G02X288461Y694960I1146J-3272D01*
G01X288465D01*
G02Y688026I0J-3467D01*
G01X288461D01*
G02X287316Y688221I1J3467D01*
G03X287184I-66J-189D01*
G02X286035Y688026I-1146J3272D01*
G02X284886Y688221I-3J3467D01*
G03X284754I-66J-189D01*
G02X284343Y688105I-1146J3273D01*
G02X284344Y688052I-3501J-93D01*
G01Y688050D01*
G02X284064Y686679I-3503J1D01*
G03Y686523I184J-78D01*
G02X284344Y685151I-3223J-1372D01*
G02X280841Y681648I-3503J0D01*
G02X278670Y682403I1J3503D01*
G03X278439Y682415I-124J-157D01*
G02X276575Y681878I-1864J2967D01*
G02X273072Y685381I0J3503D01*
G02X273352Y686753I3503J0D01*
G03Y686909I-184J78D01*
G02X273072Y688281I3223J1372D01*
G02X273352Y689653I3503J0D01*
G03Y689809I-184J78D01*
G02X273072Y691181I3223J1372D01*
G02X276575Y694684I3503J0D01*
G02X278885Y693814I0J-3502D01*
G01X278930Y693774D01*
X279050Y693758D01*
X279437Y693949D01*
G03X279548Y694142I-88J179D01*
G02X279540Y694377I3494J237D01*
G01Y694380D01*
G02X279820Y695752I3502J0D01*
G03Y695908I-184J78D01*
G02X279540Y697279I3222J1372D01*
G37*
G36*
G01X1422762Y697853D02*
Y697854D01*
G02X1429766I3502J0D01*
G01Y697853D01*
G02X1429486Y696482I-3502J1D01*
G03Y696326I184J-78D01*
G02X1429631Y695916I-3223J-1370D01*
G03X1429789Y695773I193J54D01*
G02X1430336Y695631I-595J-3416D01*
G03X1430468I66J189D01*
G02X1431613Y695826I1146J-3272D01*
G01X1431617D01*
G02Y688892I0J-3467D01*
G01X1431613D01*
G02X1430468Y689087I1J3467D01*
G03X1430336I-66J-189D01*
G02X1429187Y688892I-1146J3272D01*
G02X1428038Y689087I-3J3467D01*
G03X1427906I-66J-189D01*
G02X1427612Y688998I-1151J3271D01*
G03X1427461Y688794I49J-194D01*
G02X1427466Y688624I-3497J-188D01*
G02X1427186Y687252I-3503J0D01*
G03Y687096I184J-78D01*
G02X1427466Y685724I-3223J-1372D01*
G02X1423963Y682222I-3503J1D01*
G01X1423962D01*
G02X1421792Y682976I1J3502D01*
G03X1421561Y682988I-124J-157D01*
G02X1419697Y682452I-1862J2967D01*
G02X1416194Y685954I-1J3502D01*
G02X1416474Y687326I3503J0D01*
G03Y687482I-184J78D01*
G02X1416194Y688854I3223J1372D01*
G02X1416474Y690226I3503J0D01*
G03Y690382I-184J78D01*
G02X1416194Y691754I3223J1372D01*
G02X1419697Y695256I3503J-1D01*
G02X1422498Y693857I0J-3504D01*
G03X1422615Y693782I160J120D01*
G02X1422652Y693774I-722J-3427D01*
G01X1422812Y693943D01*
G03X1422861Y694127I-145J137D01*
G02X1422762Y694954I3405J827D01*
G01Y694955D01*
G02X1423042Y696326I3502J-1D01*
G03Y696482I-184J78D01*
G02X1422762Y697853I3222J1372D01*
G37*
G36*
G01X411210Y699439D02*
Y699440D01*
G02X418214I3502J0D01*
G01Y699439D01*
G02X417934Y698068I-3502J1D01*
G03X417935Y697912I185J-77D01*
G02X418145Y697237I-3223J-1373D01*
G03X418317Y697079I196J40D01*
G02X419054Y696908I-411J-3443D01*
G03X419186I66J189D01*
G02X420335Y697104I1149J-3272D01*
G02Y690168I0J-3468D01*
G02X419186Y690364I0J3468D01*
G03X419054I-66J-189D01*
G02X417905Y690168I-1149J3272D01*
G02X416756Y690364I0J3468D01*
G03X416624I-66J-189D01*
G02X416213Y690248I-1146J3273D01*
G02X416214Y690203I-3501J-100D01*
G01Y690199D01*
G02X415934Y688829I-3503J2D01*
G03Y688673I184J-78D01*
G02X416214Y687301I-3223J-1372D01*
G02X412711Y683798I-3503J0D01*
G02X410540Y684553I1J3503D01*
G03X410309Y684565I-124J-157D01*
G02X408445Y684028I-1864J2967D01*
G02X404942Y687531I0J3503D01*
G02X405222Y688903I3503J0D01*
G03Y689059I-184J78D01*
G02X404942Y690431I3223J1372D01*
G02X405222Y691803I3503J0D01*
G03Y691959I-184J78D01*
G02X404942Y693331I3223J1372D01*
G02X408445Y696834I3503J0D01*
G02X410567Y696116I-3J-3502D01*
G01X410569D01*
Y696115D01*
G03X410780Y696097I120J160D01*
G01X411102Y696262D01*
G03X411211Y696445I-91J178D01*
G02X411210Y696540I3501J84D01*
G02X411490Y697912I3502J0D01*
G03Y698068I-184J78D01*
G02X411210Y699439I3222J1372D01*
G37*
G36*
G01X378310Y717059D02*
Y717060D01*
G02X385314I3502J0D01*
G01Y717059D01*
G02X385034Y715688I-3502J1D01*
G03Y715532I184J-78D01*
G02X385207Y715020I-3221J-1374D01*
G03X385374Y714871I194J49D01*
G02X386054Y714708I-464J-3436D01*
G03X386186I66J189D01*
G02X387335Y714904I1149J-3272D01*
G02Y707968I0J-3468D01*
G02X386186Y708164I0J3468D01*
G03X386054I-66J-189D01*
G02X384905Y707968I-1149J3272D01*
G02X383756Y708164I0J3468D01*
G03X383624I-66J-189D01*
G02X383213Y708048I-1146J3273D01*
G02X383214Y708003I-3501J-100D01*
G01Y707999D01*
G02X382934Y706629I-3503J2D01*
G03Y706473I184J-78D01*
G02X383214Y705101I-3223J-1372D01*
G02X379711Y701598I-3503J0D01*
G02X377540Y702353I1J3503D01*
G03X377309Y702365I-124J-157D01*
G02X375445Y701828I-1864J2967D01*
G02X371942Y705331I0J3503D01*
G02X372222Y706703I3503J0D01*
G03Y706859I-184J78D01*
G02X371942Y708231I3223J1372D01*
G02X372222Y709603I3503J0D01*
G03Y709759I-184J78D01*
G02X371942Y711131I3223J1372D01*
G02X375445Y714634I3503J0D01*
G02X377657Y713847I0J-3502D01*
G01X377702Y713810D01*
X377816Y713796D01*
X378196Y713977D01*
G03X378310Y714157I-86J181D01*
G01Y714161D01*
G02X378590Y715532I3502J-1D01*
G03Y715688I-184J78D01*
G02X378310Y717059I3222J1372D01*
G37*
G36*
G01X345172Y715688D02*
G02X344892Y717060I3223J1372D01*
G02X351898I3503J0D01*
G02X351618Y715688I-3503J0D01*
G03Y715532I184J-78D01*
G02X351832Y714835I-3223J-1371D01*
G02X351862Y714836I130J-3464D01*
G01X351868D01*
G02X353014Y714640I-3J-3468D01*
G03X353146I66J189D01*
G02X354295Y714836I1149J-3272D01*
G02Y707900I0J-3468D01*
G02X353146Y708096I0J3468D01*
G03X353014I-66J-189D01*
G02X351865Y707900I-1149J3272D01*
G02X350716Y708096I0J3468D01*
G03X350584I-66J-189D01*
G02X350173Y707980I-1146J3273D01*
G02X350174Y707935I-3501J-100D01*
G01Y707931D01*
G02X349894Y706561I-3503J2D01*
G03Y706405I184J-78D01*
G02X350174Y705033I-3223J-1372D01*
G02X346671Y701530I-3503J0D01*
G02X344500Y702285I1J3503D01*
G03X344269Y702297I-124J-157D01*
G02X342405Y701760I-1864J2967D01*
G02X338902Y705263I0J3503D01*
G02X339182Y706635I3503J0D01*
G03Y706791I-184J78D01*
G02X338902Y708163I3223J1372D01*
G02X339182Y709535I3503J0D01*
G03Y709691I-184J78D01*
G02X338902Y711063I3223J1372D01*
G02X342405Y714566I3503J0D01*
G02X344283Y714019I-2J-3503D01*
G01X344328Y713990D01*
X344434Y713986D01*
X344789Y714169D01*
G03X344897Y714337I-92J178D01*
G02X345172Y715532I3498J-176D01*
G03Y715688I-184J78D01*
G37*
G36*
G01X1455554Y715722D02*
G02X1455274Y717094I3223J1372D01*
G02X1462280I3503J0D01*
G02X1462000Y715723I-3503J1D01*
G03Y715566I184J-78D01*
G02X1462059Y715418I-3223J-1371D01*
G03X1462235Y715288I188J70D01*
G02X1463194Y715098I-188J-3462D01*
G03X1463326I66J189D01*
G02X1464475Y715294I1149J-3272D01*
G02Y708358I0J-3468D01*
G02X1463326Y708554I0J3468D01*
G03X1463194I-66J-189D01*
G02X1462045Y708358I-1149J3272D01*
G02X1460896Y708554I0J3468D01*
G03X1460764I-66J-189D01*
G02X1460530Y708481I-1149J3272D01*
G03X1460383Y708283I53J-193D01*
G02X1460384Y708201I-3502J-84D01*
G02X1460104Y706829I-3503J0D01*
G03Y706673I184J-78D01*
G02X1460384Y705301I-3223J-1372D01*
G02X1458218Y702064I-3502J0D01*
G03X1458101Y701828I76J-185D01*
G02X1458218Y700932I-3386J-898D01*
G01Y700931D01*
G02X1451212I-3503J0D01*
G02X1451371Y701972I3503J-2D01*
G03X1451362Y702115I-191J60D01*
G01X1451313Y702222D01*
G03X1451211Y702323I-182J-82D01*
G02X1449112Y705531I1403J3209D01*
G02X1451314Y708783I3502J0D01*
G03X1451433Y709021I-74J186D01*
G02X1451312Y709931I3382J913D01*
G02X1454814Y713434I3503J0D01*
G01X1454816D01*
G02X1454883Y713433I-19J-3503D01*
G01X1454926Y713432D01*
X1455005Y713465D01*
X1455237Y713716D01*
G03X1455290Y713870I-146J136D01*
G02X1455274Y714194I3486J335D01*
G02X1455554Y715566I3503J0D01*
G03Y715722I-184J78D01*
G37*
G36*
G01X312410Y717399D02*
Y717400D01*
G02X319414I3502J0D01*
G01Y717399D01*
G02X319134Y716028I-3502J1D01*
G03X319135Y715872I185J-77D01*
G02X319346Y715189I-3224J-1370D01*
G03X319502Y715033I196J40D01*
G02X319954Y714908I-696J-3397D01*
G03X320086I66J189D01*
G02X321235Y715104I1149J-3272D01*
G02Y708168I0J-3468D01*
G02X320086Y708364I0J3468D01*
G03X319954I-66J-189D01*
G02X318805Y708168I-1149J3272D01*
G02X317656Y708364I0J3468D01*
G03X317524I-66J-189D01*
G02X317113Y708248I-1146J3273D01*
G02X317114Y708203I-3501J-100D01*
G01Y708199D01*
G02X316834Y706829I-3503J2D01*
G03Y706673I184J-78D01*
G02X317114Y705301I-3223J-1372D01*
G02X316143Y702881I-3503J1D01*
G03X316089Y702719I144J-138D01*
G02X316114Y702301I-3478J-418D01*
G02X313343Y698876I-3502J0D01*
G03X313226Y698802I42J-196D01*
G02X310445Y697428I-2782J2129D01*
G02X306942Y700931I0J3503D01*
G02X307243Y702350I3503J-2D01*
G03Y702512I-183J81D01*
G02X306942Y703931I3202J1421D01*
G02X307913Y706351I3503J-1D01*
G03X307967Y706513I-144J138D01*
G02X307942Y706931I3478J418D01*
G02X308292Y708456I3503J-1D01*
G03X308297Y708618I-180J87D01*
G02X308042Y709929I3248J1312D01*
G01Y709931D01*
G02X311545Y713434I3503J0D01*
G02X312019Y713401I-6J-3503D01*
G01X312067Y713394D01*
X312157Y713426D01*
X312415Y713696D01*
G03X312467Y713869I-145J138D01*
G01Y713870D01*
G02X312410Y714499I3445J629D01*
G01Y714500D01*
G02X312690Y715872I3502J0D01*
G03Y716028I-184J78D01*
G02X312410Y717399I3222J1372D01*
G37*
G36*
G01X1488762Y717443D02*
Y717444D01*
G02X1495766I3502J0D01*
G01Y717443D01*
G02X1495486Y716072I-3502J1D01*
G03X1495487Y715916I185J-77D01*
G02X1495706Y715190I-3224J-1369D01*
G03X1495862Y715031I197J37D01*
G02X1496306Y714908I-702J-3396D01*
G03X1496438I66J189D01*
G02X1497587Y715104I1149J-3272D01*
G02Y708168I0J-3468D01*
G02X1496438Y708364I0J3468D01*
G03X1496306I-66J-189D01*
G02X1495157Y708168I-1149J3272D01*
G02X1494008Y708364I0J3468D01*
G03X1493876I-66J-189D01*
G02X1493465Y708248I-1146J3273D01*
G02X1493466Y708203I-3501J-100D01*
G01Y708199D01*
G02X1493186Y706829I-3503J2D01*
G03Y706673I184J-78D01*
G02X1493466Y705301I-3223J-1372D01*
G02X1489963Y701798I-3503J0D01*
G02X1487792Y702553I1J3503D01*
G03X1487561Y702565I-124J-157D01*
G02X1485697Y702028I-1864J2967D01*
G02X1482194Y705531I0J3503D01*
G02X1482474Y706903I3503J0D01*
G03Y707059I-184J78D01*
G02X1482194Y708431I3223J1372D01*
G02X1482474Y709803I3503J0D01*
G03Y709959I-184J78D01*
G02X1482194Y711331I3223J1372D01*
G02X1485697Y714834I3503J0D01*
G02X1488498Y713434I0J-3502D01*
G03X1488615Y713359I160J120D01*
G02X1488655Y713350I-749J-3421D01*
G01X1488815Y713519D01*
G03X1488864Y713704I-146J138D01*
G02X1488762Y714542I3400J839D01*
G01Y714544D01*
G02X1489042Y715916I3502J0D01*
G03Y716072I-184J78D01*
G02X1488762Y717443I3222J1372D01*
G37*
G36*
G01X1521562D02*
Y717444D01*
G02X1528566I3502J0D01*
G01Y717443D01*
G02X1528286Y716072I-3502J1D01*
G03X1528287Y715916I185J-77D01*
G02X1528506Y715190I-3224J-1369D01*
G03X1528662Y715031I197J37D01*
G02X1529106Y714908I-702J-3396D01*
G03X1529238I66J189D01*
G02X1530387Y715104I1149J-3272D01*
G02Y708168I0J-3468D01*
G02X1529238Y708364I0J3468D01*
G03X1529106I-66J-189D01*
G02X1527957Y708168I-1149J3272D01*
G02X1526808Y708364I0J3468D01*
G03X1526676I-66J-189D01*
G02X1526265Y708248I-1146J3273D01*
G02X1526266Y708203I-3501J-100D01*
G01Y708199D01*
G02X1525986Y706829I-3503J2D01*
G03Y706673I184J-78D01*
G02X1526266Y705301I-3223J-1372D01*
G02X1522763Y701798I-3503J0D01*
G02X1520592Y702553I1J3503D01*
G03X1520361Y702565I-124J-157D01*
G02X1518497Y702028I-1864J2967D01*
G02X1514994Y705531I0J3503D01*
G02X1515274Y706903I3503J0D01*
G03Y707059I-184J78D01*
G02X1514994Y708431I3223J1372D01*
G02X1515274Y709803I3503J0D01*
G03Y709959I-184J78D01*
G02X1514994Y711331I3223J1372D01*
G02X1518497Y714834I3503J0D01*
G02X1521298Y713434I0J-3502D01*
G03X1521415Y713359I160J120D01*
G02X1521455Y713350I-749J-3421D01*
G01X1521615Y713519D01*
G03X1521664Y713704I-146J138D01*
G02X1521562Y714542I3400J839D01*
G01Y714544D01*
G02X1521842Y715916I3502J0D01*
G03Y716072I-184J78D01*
G02X1521562Y717443I3222J1372D01*
G37*
G36*
G01X869275Y748970D02*
G02Y751974I0J1502D01*
G01X873175D01*
G02Y748970I0J-1502D01*
G01X869275D01*
G37*
G36*
G01X1332812Y854880D02*
G02Y857886I0J1503D01*
G01X1336812D01*
G02Y854880I0J-1503D01*
G01X1332812D01*
G37*
G36*
G01X509572Y863824D02*
G02Y866830I0J1503D01*
G01X513572D01*
G02Y863824I0J-1503D01*
G01X509572D01*
G37*
G36*
G01X368726Y1212952D02*
G02Y1215958I0J1503D01*
G01X372126D01*
G02Y1212952I0J-1503D01*
G01X368726D01*
G37*
G36*
G01X1325972Y1332957D02*
Y1332959D01*
G02X1329474Y1336460I3502J-1D01*
G02X1331645Y1335705I-1J-3503D01*
G03X1331876Y1335693I124J157D01*
G02X1333740Y1336230I1864J-2967D01*
G02X1337242Y1332727I-1J-3503D01*
G01Y1332726D01*
G02X1336962Y1331355I-3502J1D01*
G03Y1331199I184J-78D01*
G02X1337242Y1329827I-3222J-1372D01*
G02X1336962Y1328455I-3502J0D01*
G03Y1328299I184J-78D01*
G02X1337242Y1326927I-3222J-1372D01*
G01Y1326925D01*
G02X1333740Y1323424I-3502J1D01*
G02X1331971Y1323904I1J3503D01*
G01X1331926Y1323930D01*
X1331823Y1323932D01*
X1331476Y1323750D01*
G03X1331370Y1323587I94J-177D01*
G02X1331099Y1322462I-3494J247D01*
G03X1331098Y1322306I184J-79D01*
G02X1331378Y1320935I-3222J-1372D01*
G01Y1320934D01*
G02X1324374I-3502J0D01*
G01Y1320935D01*
G02X1324654Y1322306I3502J-1D01*
G03X1324653Y1322462I-185J77D01*
G02X1324439Y1323158I3223J1372D01*
G02X1324280Y1323154I-167J3464D01*
G02X1323131Y1323350I0J3468D01*
G03X1322999I-66J-189D01*
G02X1321850Y1323154I-1149J3272D01*
G02Y1330090I0J3468D01*
G02X1322999Y1329894I0J-3468D01*
G03X1323131I66J189D01*
G02X1324280Y1330090I1149J-3272D01*
G02X1325429Y1329894I0J-3468D01*
G03X1325561I66J189D01*
G02X1325972Y1330010I1146J-3273D01*
G01Y1330057D01*
G02X1326252Y1331429I3502J0D01*
G03Y1331585I-184J78D01*
G02X1325972Y1332957I3222J1372D01*
G37*
G36*
G01X349842Y1332976D02*
G02X353345Y1336478I3503J-1D01*
G01X353346D01*
G02X355516Y1335724I-1J-3502D01*
G03X355747Y1335712I124J157D01*
G02X357611Y1336248I1862J-2967D01*
G02X361114Y1332746I1J-3502D01*
G02X360834Y1331374I-3503J0D01*
G03Y1331218I184J-78D01*
G02X361114Y1329846I-3223J-1372D01*
G02X360834Y1328474I-3503J0D01*
G03Y1328318I184J-78D01*
G02X361114Y1326946I-3223J-1372D01*
G02X357611Y1323444I-3503J1D01*
G01X357609D01*
G02X355729Y1323992I1J3502D01*
G01X355683Y1324021D01*
X355578Y1324026D01*
X355222Y1323842D01*
G03X355114Y1323675I92J-178D01*
G01Y1323674D01*
G02X354836Y1322471I-3463J167D01*
G03Y1322313I184J-79D01*
G02X355118Y1320945I-3185J-1370D01*
G01Y1320942D01*
G02X348184I-3467J0D01*
G01Y1320945D01*
G02X348466Y1322313I3467J-2D01*
G03Y1322471I-184J79D01*
G02X348248Y1323175I3185J1372D01*
G02X348151Y1323174I-84J3466D01*
G02X347002Y1323369I-3J3467D01*
G03X346870I-66J-189D01*
G02X345725Y1323174I-1146J3272D01*
G01X345721D01*
G02Y1330108I0J3467D01*
G01X345725D01*
G02X346870Y1329913I-1J-3467D01*
G03X347002I66J189D01*
G02X348151Y1330108I1146J-3272D01*
G02X349300Y1329913I3J-3467D01*
G03X349432I66J189D01*
G02X349843Y1330029I1146J-3273D01*
G02X349842Y1330074I3501J100D01*
G01Y1330078D01*
G02X350122Y1331448I3503J-2D01*
G03Y1331604I-184J78D01*
G02X349842Y1332976I3223J1372D01*
G37*
G36*
G01X1293068Y1333014D02*
G02X1296570Y1336516I3502J0D01*
G01X1296571D01*
G02X1298741Y1335762I-1J-3502D01*
G03X1298972Y1335750I124J157D01*
G02X1300833Y1336286I1862J-2967D01*
G01X1300836D01*
G02X1304338Y1332784I0J-3502D01*
G01Y1332783D01*
G02X1304058Y1331412I-3502J1D01*
G03Y1331256I184J-78D01*
G02X1304338Y1329884I-3222J-1372D01*
G02X1304058Y1328512I-3502J0D01*
G03Y1328356I184J-78D01*
G02X1304338Y1326985I-3222J-1372D01*
G01Y1326984D01*
G02X1300836Y1323482I-3502J0D01*
G02X1299056Y1323968I0J3503D01*
G03X1298860Y1323972I-102J-172D01*
G01X1298512Y1323785D01*
X1298456Y1323697D01*
X1298453Y1323645D01*
G02X1298178Y1322462I-3497J189D01*
G03Y1322306I184J-78D01*
G02X1298458Y1320935I-3222J-1372D01*
G01Y1320934D01*
G02X1291454I-3502J0D01*
G01Y1320935D01*
G02X1291734Y1322306I3502J-1D01*
G03Y1322462I-184J78D01*
G02X1291509Y1323214I3222J1374D01*
G02X1291376Y1323212I-119J3465D01*
G02X1290227Y1323407I-3J3467D01*
G03X1290095I-66J-189D01*
G02X1288950Y1323212I-1146J3272D01*
G01X1288946D01*
G02Y1330146I0J3467D01*
G01X1288950D01*
G02X1290095Y1329951I-1J-3467D01*
G03X1290227I66J189D01*
G02X1291376Y1330146I1146J-3272D01*
G02X1292525Y1329951I3J-3467D01*
G03X1292657I66J189D01*
G02X1293068Y1330067I1146J-3273D01*
G01Y1330114D01*
G02X1293348Y1331486I3502J0D01*
G03Y1331642I-184J78D01*
G02X1293068Y1333013I3222J1372D01*
G01Y1333014D01*
G37*
G36*
G01X317218Y1331661D02*
G02X316938Y1333033I3223J1372D01*
G02X320441Y1336536I3503J0D01*
G02X322612Y1335781I-1J-3503D01*
G03X322843Y1335769I124J157D01*
G02X324707Y1336306I1864J-2967D01*
G02X328210Y1332803I0J-3503D01*
G02X327930Y1331431I-3503J0D01*
G03Y1331275I184J-78D01*
G02X328210Y1329903I-3223J-1372D01*
G02X327930Y1328531I-3503J0D01*
G03Y1328375I184J-78D01*
G02X328210Y1327003I-3223J-1372D01*
G02X324707Y1323500I-3503J0D01*
G02X322884Y1324012I0J3503D01*
G01X322838Y1324040D01*
X322732Y1324043D01*
X322381Y1323853D01*
G03X322276Y1323684I95J-176D01*
G02X321996Y1322431I-3465J117D01*
G03Y1322273I184J-79D01*
G02X322278Y1320905I-3185J-1370D01*
G01Y1320902D01*
G02X315344I-3467J0D01*
G01Y1320905D01*
G02X315626Y1322273I3467J-2D01*
G03Y1322431I-184J79D01*
G02X315390Y1323233I3184J1373D01*
G02X315247Y1323230I-144J3465D01*
G02X314098Y1323426I0J3468D01*
G03X313966I-66J-189D01*
G02X312817Y1323230I-1149J3272D01*
G02Y1330166I0J3468D01*
G02X313966Y1329970I0J-3468D01*
G03X314098I66J189D01*
G02X315247Y1330166I1149J-3272D01*
G02X316396Y1329970I0J-3468D01*
G03X316528I66J189D01*
G02X316939Y1330086I1146J-3273D01*
G02X316938Y1330131I3501J100D01*
G01Y1330135D01*
G02X317218Y1331505I3503J-2D01*
G03Y1331661I-184J78D01*
G37*
G36*
G01X1260172Y1333042D02*
G02X1263674Y1336544I3502J0D01*
G01X1263675D01*
G02X1265845Y1335790I-1J-3502D01*
G03X1266076Y1335778I124J157D01*
G02X1267937Y1336314I1862J-2967D01*
G01X1267940D01*
G02X1271442Y1332812I0J-3502D01*
G01Y1332811D01*
G02X1271162Y1331440I-3502J1D01*
G03Y1331284I184J-78D01*
G02X1271442Y1329912I-3222J-1372D01*
G02X1271162Y1328540I-3502J0D01*
G03Y1328384I184J-78D01*
G02X1271442Y1327013I-3222J-1372D01*
G01Y1327012D01*
G02X1267940Y1323510I-3502J0D01*
G01X1267938D01*
G02X1266154Y1323999I1J3502D01*
G01X1266108Y1324026D01*
X1266003Y1324028D01*
X1265607Y1323810D01*
X1265552Y1323720D01*
X1265551Y1323667D01*
G02X1265273Y1322406I-3501J111D01*
G03X1265272Y1322250I184J-79D01*
G02X1265552Y1320879I-3222J-1372D01*
G01Y1320878D01*
G02X1258548I-3502J0D01*
G01Y1320879D01*
G02X1258828Y1322250I3502J-1D01*
G03Y1322406I-184J78D01*
G02X1258589Y1323241I3222J1374D01*
G02X1258481Y1323240I-86J3466D01*
G01X1258479D01*
G02X1257331Y1323435I-2J3467D01*
G03X1257199I-66J-189D01*
G02X1256054Y1323240I-1146J3272D01*
G01X1256050D01*
G02Y1330174I0J3467D01*
G01X1256054D01*
G02X1257199Y1329979I-1J-3467D01*
G03X1257331I66J189D01*
G02X1258480Y1330174I1146J-3272D01*
G02X1259629Y1329979I3J-3467D01*
G03X1259761I66J189D01*
G02X1260172Y1330095I1146J-3273D01*
G01Y1330142D01*
G02X1260452Y1331514I3502J0D01*
G03Y1331670I-184J78D01*
G02X1260172Y1333041I3222J1372D01*
G01Y1333042D01*
G37*
G36*
G01X284322Y1331689D02*
G02X284042Y1333061I3223J1372D01*
G02X287545Y1336564I3503J0D01*
G02X289716Y1335809I-1J-3503D01*
G03X289947Y1335797I124J157D01*
G02X291811Y1336334I1864J-2967D01*
G02X295314Y1332831I0J-3503D01*
G02X295034Y1331459I-3503J0D01*
G03Y1331303I184J-78D01*
G02X295314Y1329931I-3223J-1372D01*
G02X295034Y1328559I-3503J0D01*
G03Y1328403I184J-78D01*
G02X295314Y1327031I-3223J-1372D01*
G02X291811Y1323528I-3503J0D01*
G02X289967Y1324053I1J3503D01*
G01X289921Y1324082D01*
X289815Y1324085D01*
X289415Y1323871D01*
X289358Y1323780D01*
X289357Y1323727D01*
G02X289076Y1322471I-3466J116D01*
G03Y1322313I184J-79D01*
G02X289358Y1320945I-3185J-1370D01*
G01Y1320942D01*
G02X282424I-3467J0D01*
G01Y1320945D01*
G02X282706Y1322313I3467J-2D01*
G03Y1322471I-184J79D01*
G02X282473Y1323261I3186J1369D01*
G02X282352Y1323258I-146J3464D01*
G01X282350D01*
G02X281202Y1323454I1J3468D01*
G03X281070I-66J-189D01*
G02X279921Y1323258I-1149J3272D01*
G02Y1330194I0J3468D01*
G02X281070Y1329998I0J-3468D01*
G03X281202I66J189D01*
G02X282351Y1330194I1149J-3272D01*
G02X283500Y1329998I0J-3468D01*
G03X283632I66J189D01*
G02X284043Y1330114I1146J-3273D01*
G02X284042Y1330159I3501J100D01*
G01Y1330163D01*
G02X284322Y1331533I3503J-2D01*
G03Y1331689I-184J78D01*
G37*
G36*
G01X1361459Y1339463D02*
G03X1361576Y1339543I-47J194D01*
G02X1364440Y1341030I2865J-2016D01*
G02X1367942Y1337527I-1J-3503D01*
G01Y1337525D01*
G02X1367642Y1336108I-3502J1D01*
G03Y1335946I183J-81D01*
G02X1367942Y1334527I-3202J-1418D01*
G02X1367642Y1333108I-3502J-1D01*
G03Y1332946I183J-81D01*
G02X1367942Y1331527I-3202J-1418D01*
G02X1367593Y1330002I-3502J-1D01*
G03X1367587Y1329840I180J-88D01*
G02X1367842Y1328531I-3247J-1312D01*
G01Y1328527D01*
G02X1364563Y1325032I-3502J0D01*
G01X1364561D01*
G03X1364420Y1324959I14J-200D01*
G01X1364208Y1324699D01*
X1364186Y1324618D01*
X1364192Y1324576D01*
G02X1364226Y1324084I-3468J-487D01*
G02X1363946Y1322712I-3502J0D01*
G03Y1322556I184J-78D01*
G02X1364226Y1321185I-3222J-1372D01*
G01Y1321184D01*
G02X1357222I-3502J0D01*
G01Y1321185D01*
G02X1357502Y1322556I3502J-1D01*
G03Y1322712I-184J78D01*
G02X1357334Y1323205I3222J1373D01*
G03X1357137Y1323355I-194J-50D01*
G02X1357080Y1323354I-89J3466D01*
G02X1355931Y1323550I0J3468D01*
G03X1355799I-66J-189D01*
G02X1354650Y1323354I-1149J3272D01*
G02Y1330290I0J3468D01*
G02X1355799Y1330094I0J-3468D01*
G03X1355931I66J189D01*
G02X1357080Y1330290I1149J-3272D01*
G02X1358229Y1330094I0J-3468D01*
G03X1358361I66J189D01*
G02X1358772Y1330210I1146J-3273D01*
G01Y1330257D01*
G02X1359052Y1331629I3502J0D01*
G03Y1331785I-184J78D01*
G02X1358772Y1333157I3222J1372D01*
G02X1359052Y1334529I3502J0D01*
G03Y1334685I-184J78D01*
G02X1358772Y1336056I3222J1372D01*
G01Y1336057D01*
G02X1361459Y1339463I3502J0D01*
G37*
G36*
G01X385890Y1339537D02*
G02X388771Y1341048I2881J-1991D01*
G01X388773D01*
G02X392274Y1337546I-1J-3502D01*
G02X391973Y1336127I-3503J2D01*
G03Y1335965I183J-81D01*
G02X392274Y1334546I-3202J-1421D01*
G02X391711Y1332643I-3503J1D01*
G03X391686Y1332481I168J-109D01*
G02X391814Y1331546I-3375J-938D01*
G02X391464Y1330021I-3503J1D01*
G03X391459Y1329859I180J-87D01*
G02X391714Y1328548I-3248J-1312D01*
G01Y1328546D01*
G02X388300Y1325045I-3502J0D01*
G01X388298D01*
G03X388152Y1324974I7J-200D01*
G01X387930Y1324713D01*
X387907Y1324630D01*
X387913Y1324588D01*
G02X387948Y1324092I-3432J-491D01*
G02X387666Y1322721I-3467J-1D01*
G03Y1322563I184J-79D01*
G02X387948Y1321195I-3185J-1370D01*
G01Y1321192D01*
G02X381014I-3467J0D01*
G01Y1321195D01*
G02X381296Y1322563I3467J-2D01*
G03Y1322721I-184J79D01*
G02X381088Y1323376I3185J1372D01*
G02X380952Y1323374I-119J3465D01*
G01X380950D01*
G02X379802Y1323569I-2J3467D01*
G03X379670I-66J-189D01*
G02X378525Y1323374I-1146J3272D01*
G01X378521D01*
G02Y1330308I0J3467D01*
G01X378525D01*
G02X379670Y1330113I-1J-3467D01*
G03X379802I66J189D01*
G02X380951Y1330308I1146J-3272D01*
G02X382100Y1330113I3J-3467D01*
G03X382232I66J189D01*
G02X382643Y1330229I1146J-3273D01*
G02X382642Y1330274I3501J100D01*
G01Y1330278D01*
G02X382922Y1331648I3503J-2D01*
G03Y1331804I-184J78D01*
G02X382642Y1333176I3223J1372D01*
G02X383188Y1335053I3503J-1D01*
G03X383213Y1335208I-169J107D01*
G02X383108Y1336056I3398J851D01*
G02X385773Y1339457I3503J0D01*
G03X385890Y1339537I-47J194D01*
G37*
G36*
G01X1391354Y1352488D02*
G02X1394856Y1355990I3502J0D01*
G01X1394857D01*
G02X1397027Y1355236I-1J-3502D01*
G03X1397258Y1355224I124J157D01*
G02X1399119Y1355760I1862J-2967D01*
G01X1399122D01*
G02X1402624Y1352258I0J-3502D01*
G01Y1352257D01*
G02X1402344Y1350886I-3502J1D01*
G03Y1350730I184J-78D01*
G02X1402624Y1349358I-3222J-1372D01*
G02X1402344Y1347986I-3502J0D01*
G03Y1347830I184J-78D01*
G02X1402624Y1346459I-3222J-1372D01*
G01Y1346458D01*
G02X1399122Y1342956I-3502J0D01*
G01X1399120D01*
G02X1397123Y1343582I1J3502D01*
G01X1397122D01*
G03X1397009Y1343618I-114J-164D01*
G01X1397008D01*
G03X1396808Y1343418I0J-200D01*
G01Y1343414D01*
G02X1396528Y1342043I-3502J1D01*
G03Y1341887I184J-78D01*
G02X1396808Y1340516I-3222J-1372D01*
G01Y1340515D01*
G02X1389804I-3502J0D01*
G01Y1340516D01*
G02X1390084Y1341887I3502J-1D01*
G03Y1342043I-184J78D01*
G02X1389916Y1342536I3222J1373D01*
G03X1389719Y1342686I-194J-50D01*
G01X1389662D01*
G02X1388513Y1342881I-3J3467D01*
G03X1388381I-66J-189D01*
G02X1387236Y1342686I-1146J3272D01*
G01X1387232D01*
G02Y1349620I0J3467D01*
G01X1387236D01*
G02X1388381Y1349425I-1J-3467D01*
G03X1388513I66J189D01*
G02X1389662Y1349620I1146J-3272D01*
G02X1390811Y1349425I3J-3467D01*
G03X1390943I66J189D01*
G02X1391354Y1349541I1146J-3273D01*
G01Y1349588D01*
G02X1391634Y1350960I3502J0D01*
G03Y1351116I-184J78D01*
G02X1391354Y1352487I3222J1372D01*
G01Y1352488D01*
G37*
G36*
G01X418121Y1355713D02*
G02X421315Y1357778I3194J-1438D01*
G01X421317D01*
G02X424818Y1354276I-1J-3502D01*
G02X424538Y1352904I-3503J0D01*
G03Y1352748I184J-78D01*
G02X424818Y1351376I-3223J-1372D01*
G01Y1351375D01*
G02X424505Y1349928I-3502J0D01*
G03X424499Y1349777I182J-83D01*
G02X424708Y1348586I-3294J-1192D01*
G02X424428Y1347214I-3503J0D01*
G03Y1347058I184J-78D01*
G02X424708Y1345686I-3223J-1372D01*
G02X421205Y1342184I-3503J1D01*
G01X421203D01*
G02X420507Y1342254I1J3502D01*
G03X420282Y1342132I-39J-196D01*
G02X420248Y1342052I-3208J1316D01*
G03Y1341894I184J-79D01*
G02X420530Y1340526I-3185J-1370D01*
G01Y1340523D01*
G02X413596I-3467J0D01*
G01Y1340526D01*
G02X413878Y1341894I3467J-2D01*
G03Y1342052I-184J79D01*
G02X413670Y1342707I3185J1372D01*
G02X413533Y1342704I-144J3465D01*
G02X412384Y1342900I0J3468D01*
G03X412252I-66J-189D01*
G02X411103Y1342704I-1149J3272D01*
G02Y1349640I0J3468D01*
G02X412252Y1349444I0J-3468D01*
G03X412384I66J189D01*
G02X413533Y1349640I1149J-3272D01*
G02X414682Y1349444I0J-3468D01*
G03X414814I66J189D01*
G02X415052Y1349518I1148J-3272D01*
G03X415198Y1349687I-53J193D01*
G02X415452Y1350638I3477J-419D01*
G03Y1350794I-184J78D01*
G02X415172Y1352166I3223J1372D01*
G02X417978Y1355599I3503J0D01*
G03X418121Y1355713I-39J196D01*
G37*
G36*
G01X791071Y1363081D02*
G02X790770Y1364500I3202J1421D01*
G02X797776I3503J0D01*
G02X797475Y1363081I-3503J2D01*
G03Y1362919I183J-81D01*
G02X797776Y1361500I-3202J-1421D01*
G02X797250Y1359655I-3503J1D01*
G03Y1359445I170J-105D01*
G02X797776Y1357600I-2977J-1846D01*
G02X797475Y1356181I-3503J2D01*
G03Y1356019I183J-81D01*
G02X797776Y1354600I-3202J-1421D01*
G02X790770I-3503J0D01*
G02X791071Y1356019I3503J-2D01*
G03Y1356181I-183J81D01*
G02X790770Y1357600I3202J1421D01*
G02X791296Y1359445I3503J-1D01*
G03Y1359655I-170J105D01*
G02X790770Y1361500I2977J1846D01*
G02X791071Y1362919I3503J-2D01*
G03Y1363081I-183J81D01*
G37*
G36*
G01X363406Y1368021D02*
G03X363540I67J188D01*
G02X364723Y1368226I1181J-3297D01*
G02X368226Y1364724I1J-3502D01*
G02X367918Y1363289I-3503J1D01*
G03X367910Y1363146I183J-82D01*
G02X368074Y1362085I-3338J-1059D01*
G02X367898Y1360988I-3502J-1D01*
G03X367909Y1360838I190J-61D01*
G02X368266Y1359298I-3145J-1541D01*
G01Y1359296D01*
G02X364764Y1355794I-3502J0D01*
G01X364761D01*
G02X363581Y1355999I1J3502D01*
G03X363447I-67J-188D01*
G02X362264Y1355794I-1181J3297D01*
G02X361081Y1355999I-2J3502D01*
G03X360947I-67J-188D01*
G02X359764Y1355794I-1181J3297D01*
G02X358345Y1356094I-1J3502D01*
G03X358183I-81J-183D01*
G02X356764Y1355794I-1418J3202D01*
G02X355581Y1355999I-2J3502D01*
G03X355447I-67J-188D01*
G02X354269Y1355794I-1181J3297D01*
G01X354264D01*
G02X353135Y1355981I0J3502D01*
G03X352993Y1355976I-64J-190D01*
G02X351632Y1355700I-1363J3227D01*
G02X348130Y1359203I1J3503D01*
G01Y1359206D01*
G02X348476Y1360723I3502J-1D01*
G03X348484Y1360878I-180J87D01*
G02X348270Y1362085I3288J1205D01*
G02X348577Y1363520I3502J1D01*
G03X348585Y1363663I-183J82D01*
G02X348420Y1364724I3338J1062D01*
G02X351923Y1368226I3503J-1D01*
G01X351926D01*
G02X353106Y1368021I-1J-3502D01*
G03X353240I67J188D01*
G02X354423Y1368226I1181J-3297D01*
G02X355606Y1368021I2J-3502D01*
G03X355740I67J188D01*
G02X356923Y1368226I1181J-3297D01*
G02X358106Y1368021I2J-3502D01*
G03X358240I67J188D01*
G02X359423Y1368226I1181J-3297D01*
G02X360747Y1367967I2J-3502D01*
G03X360899I76J185D01*
G02X362223Y1368226I1322J-3243D01*
G02X363406Y1368021I2J-3502D01*
G37*
G36*
G01X330686Y1378896D02*
Y1378897D01*
G02X337692I3503J0D01*
G01Y1378896D01*
G02X337434Y1377577I-3503J0D01*
G03Y1377427I185J-75D01*
G02X337692Y1376108I-3245J-1319D01*
G02X337384Y1374673I-3503J1D01*
G03X337376Y1374530I183J-82D01*
G02X337540Y1373469I-3338J-1059D01*
G02X337364Y1372372I-3502J-1D01*
G03X337375Y1372222I190J-61D01*
G02X337732Y1370682I-3145J-1541D01*
G01Y1370680D01*
G02X330728I-3502J0D01*
G01Y1370684D01*
G02X330904Y1371777I3502J-3D01*
G03X330893Y1371927I-190J61D01*
G02X330536Y1373469I3145J1541D01*
G02X330843Y1374904I3502J1D01*
G03X330851Y1375047I-183J82D01*
G02X330686Y1376108I3338J1062D01*
G02X330944Y1377427I3503J0D01*
G03Y1377577I-185J75D01*
G02X330686Y1378896I3245J1319D01*
G37*
G36*
G01X1091180Y1379188D02*
G02X1094683Y1382690I3503J-1D01*
G01X1094684D01*
G02X1096854Y1381936I-1J-3502D01*
G03X1097085Y1381924I124J157D01*
G02X1098949Y1382460I1862J-2967D01*
G02X1102452Y1378958I1J-3502D01*
G02X1102172Y1377586I-3503J0D01*
G03Y1377430I184J-78D01*
G02X1102452Y1376058I-3223J-1372D01*
G02X1102172Y1374686I-3503J0D01*
G03Y1374530I184J-78D01*
G02X1102452Y1373158I-3223J-1372D01*
G02X1098949Y1369656I-3503J1D01*
G01X1098947D01*
G02X1097004Y1370245I1J3502D01*
G01X1096960Y1370274D01*
X1096853Y1370282D01*
X1096494Y1370105D01*
G03X1096383Y1369939I89J-179D01*
G02X1096111Y1368806I-3494J240D01*
G03X1096112Y1368650I185J-77D01*
G02X1096392Y1367278I-3223J-1372D01*
G02X1089386I-3503J0D01*
G02X1089666Y1368650I3503J0D01*
G03Y1368806I-184J78D01*
G02X1089513Y1369243I3222J1373D01*
G03X1089330Y1369390I-193J-53D01*
G02X1088340Y1369581I155J3464D01*
G03X1088208I-66J-189D01*
G02X1087063Y1369386I-1146J3272D01*
G01X1087059D01*
G02Y1376320I0J3467D01*
G01X1087063D01*
G02X1088208Y1376125I-1J-3467D01*
G03X1088340I66J189D01*
G02X1089489Y1376320I1146J-3272D01*
G02X1090638Y1376125I3J-3467D01*
G03X1090770I66J189D01*
G02X1091181Y1376241I1146J-3273D01*
G02X1091180Y1376286I3501J100D01*
G01Y1376290D01*
G02X1091460Y1377660I3503J-2D01*
G03Y1377816I-184J78D01*
G02X1091180Y1379188I3223J1372D01*
G37*
G36*
G01X1123780D02*
G02X1127283Y1382690I3503J-1D01*
G01X1127284D01*
G02X1129454Y1381936I-1J-3502D01*
G03X1129685Y1381924I124J157D01*
G02X1131549Y1382460I1862J-2967D01*
G02X1135052Y1378958I1J-3502D01*
G02X1134772Y1377586I-3503J0D01*
G03Y1377430I184J-78D01*
G02X1135052Y1376058I-3223J-1372D01*
G02X1134772Y1374686I-3503J0D01*
G03Y1374530I184J-78D01*
G02X1135052Y1373158I-3223J-1372D01*
G02X1131549Y1369656I-3503J1D01*
G01X1131548D01*
G02X1129594Y1370252I0J3502D01*
G01X1129593Y1370253D01*
G03X1129390Y1370264I-111J-167D01*
G01X1129030Y1370077D01*
X1128972Y1369984D01*
X1128971Y1369929D01*
G02X1128692Y1368636I-3502J79D01*
G03Y1368480I184J-78D01*
G02X1128972Y1367108I-3223J-1372D01*
G02X1121966I-3503J0D01*
G02X1122246Y1368480I3503J0D01*
G03Y1368636I-184J78D01*
G02X1122052Y1369237I3223J1372D01*
G03X1121870Y1369392I-195J-44D01*
G02X1120940Y1369581I219J3461D01*
G03X1120808I-66J-189D01*
G02X1119663Y1369386I-1146J3272D01*
G01X1119659D01*
G02Y1376320I0J3467D01*
G01X1119663D01*
G02X1120808Y1376125I-1J-3467D01*
G03X1120940I66J189D01*
G02X1122089Y1376320I1146J-3272D01*
G02X1123238Y1376125I3J-3467D01*
G03X1123370I66J189D01*
G02X1123781Y1376241I1146J-3273D01*
G02X1123780Y1376286I3501J100D01*
G01Y1376290D01*
G02X1124060Y1377660I3503J-2D01*
G03Y1377816I-184J78D01*
G02X1123780Y1379188I3223J1372D01*
G37*
G36*
G01X1156480D02*
G02X1159983Y1382690I3503J-1D01*
G01X1159984D01*
G02X1162154Y1381936I-1J-3502D01*
G03X1162385Y1381924I124J157D01*
G02X1164249Y1382460I1862J-2967D01*
G02X1167752Y1378958I1J-3502D01*
G02X1167472Y1377586I-3503J0D01*
G03Y1377430I184J-78D01*
G02X1167752Y1376058I-3223J-1372D01*
G02X1167472Y1374686I-3503J0D01*
G03Y1374530I184J-78D01*
G02X1167752Y1373158I-3223J-1372D01*
G02X1164249Y1369656I-3503J1D01*
G01X1164247D01*
G02X1162195Y1370321I1J3502D01*
G01X1162149Y1370354D01*
X1162036Y1370362D01*
X1161617Y1370144D01*
X1161560Y1370046D01*
X1161561Y1369989D01*
G02X1161562Y1369918I-3502J-85D01*
G02X1161282Y1368546I-3503J0D01*
G03Y1368390I184J-78D01*
G02X1161562Y1367018I-3223J-1372D01*
G02X1154556I-3503J0D01*
G02X1154836Y1368390I3503J0D01*
G03Y1368546I-184J78D01*
G02X1154622Y1369242I3223J1372D01*
G03X1154446Y1369403I-196J-38D01*
G02X1153640Y1369581I339J3451D01*
G03X1153508I-66J-189D01*
G02X1152363Y1369386I-1146J3272D01*
G01X1152359D01*
G02Y1376320I0J3467D01*
G01X1152363D01*
G02X1153508Y1376125I-1J-3467D01*
G03X1153640I66J189D01*
G02X1154789Y1376320I1146J-3272D01*
G02X1155938Y1376125I3J-3467D01*
G03X1156070I66J189D01*
G02X1156481Y1376241I1146J-3273D01*
G02X1156480Y1376286I3501J100D01*
G01Y1376290D01*
G02X1156760Y1377660I3503J-2D01*
G03Y1377816I-184J78D01*
G02X1156480Y1379188I3223J1372D01*
G37*
G36*
G01X1189380D02*
G02X1192883Y1382690I3503J-1D01*
G01X1192884D01*
G02X1195054Y1381936I-1J-3502D01*
G03X1195285Y1381924I124J157D01*
G02X1197149Y1382460I1862J-2967D01*
G02X1200652Y1378958I1J-3502D01*
G02X1200372Y1377586I-3503J0D01*
G03Y1377430I184J-78D01*
G02X1200652Y1376058I-3223J-1372D01*
G02X1200372Y1374686I-3503J0D01*
G03Y1374530I184J-78D01*
G02X1200652Y1373158I-3223J-1372D01*
G02X1197149Y1369656I-3503J1D01*
G01X1197146D01*
G02X1195174Y1370265I2J3502D01*
G01X1195129Y1370296D01*
X1195021Y1370304D01*
X1194609Y1370097D01*
X1194551Y1370006D01*
X1194549Y1369951D01*
G02X1194272Y1368716I-3500J136D01*
G03Y1368560I184J-78D01*
G02X1194552Y1367188I-3223J-1372D01*
G02X1187546I-3503J0D01*
G02X1187826Y1368560I3503J0D01*
G03X1187827Y1368716I-184J79D01*
G02X1187651Y1369241I3222J1372D01*
G03X1187469Y1369392I-194J-49D01*
G02X1186540Y1369581I220J3461D01*
G03X1186408I-66J-189D01*
G02X1185263Y1369386I-1146J3272D01*
G01X1185259D01*
G02Y1376320I0J3467D01*
G01X1185263D01*
G02X1186408Y1376125I-1J-3467D01*
G03X1186540I66J189D01*
G02X1187689Y1376320I1146J-3272D01*
G02X1188838Y1376125I3J-3467D01*
G03X1188970I66J189D01*
G02X1189381Y1376241I1146J-3273D01*
G02X1189380Y1376286I3501J100D01*
G01Y1376290D01*
G02X1189660Y1377660I3503J-2D01*
G03Y1377816I-184J78D01*
G02X1189380Y1379188I3223J1372D01*
G37*
G36*
G01X1222180D02*
G02X1225683Y1382690I3503J-1D01*
G01X1225684D01*
G02X1227854Y1381936I-1J-3502D01*
G03X1228085Y1381924I124J157D01*
G02X1229949Y1382460I1862J-2967D01*
G02X1233452Y1378958I1J-3502D01*
G02X1233172Y1377586I-3503J0D01*
G03Y1377430I184J-78D01*
G02X1233452Y1376058I-3223J-1372D01*
G02X1233172Y1374686I-3503J0D01*
G03Y1374530I184J-78D01*
G02X1233452Y1373158I-3223J-1372D01*
G02X1229949Y1369656I-3503J1D01*
G01X1229948D01*
G02X1228009Y1370242I0J3502D01*
G01X1227964Y1370272D01*
X1227857Y1370279D01*
X1227497Y1370097D01*
G03X1227388Y1369927I91J-178D01*
G02X1227112Y1368716I-3499J161D01*
G03Y1368560I184J-78D01*
G02X1227392Y1367188I-3223J-1372D01*
G02X1220386I-3503J0D01*
G02X1220666Y1368560I3503J0D01*
G03X1220667Y1368716I-184J79D01*
G02X1220491Y1369239I3221J1375D01*
G03X1220308Y1369391I-194J-48D01*
G02X1219340Y1369581I177J3463D01*
G03X1219208I-66J-189D01*
G02X1218063Y1369386I-1146J3272D01*
G01X1218059D01*
G02Y1376320I0J3467D01*
G01X1218063D01*
G02X1219208Y1376125I-1J-3467D01*
G03X1219340I66J189D01*
G02X1220489Y1376320I1146J-3272D01*
G02X1221638Y1376125I3J-3467D01*
G03X1221770I66J189D01*
G02X1222181Y1376241I1146J-3273D01*
G02X1222180Y1376286I3501J100D01*
G01Y1376290D01*
G02X1222460Y1377660I3503J-2D01*
G03Y1377816I-184J78D01*
G02X1222180Y1379188I3223J1372D01*
G37*
G36*
G01X119722Y1377835D02*
G02X119442Y1379207I3223J1372D01*
G02X122945Y1382710I3503J0D01*
G02X125116Y1381955I-1J-3503D01*
G03X125347Y1381943I124J157D01*
G02X127211Y1382480I1864J-2967D01*
G02X130714Y1378977I0J-3503D01*
G02X130434Y1377605I-3503J0D01*
G03Y1377449I184J-78D01*
G02X130714Y1376077I-3223J-1372D01*
G02X130434Y1374705I-3503J0D01*
G03Y1374549I184J-78D01*
G02X130714Y1373177I-3223J-1372D01*
G02X127211Y1369674I-3503J0D01*
G02X125355Y1370207I1J3503D01*
G03X125153Y1370213I-106J-169D01*
G01X124800Y1370022D01*
X124744Y1369930D01*
X124743Y1369876D01*
G02X124464Y1368575I-3502J71D01*
G03Y1368419I184J-78D01*
G02X124744Y1367047I-3223J-1372D01*
G02X122784Y1363903I-3502J0D01*
G03X122672Y1363714I88J-180D01*
G02X122674Y1363643I-1465J-77D01*
G02X119740I-1467J0D01*
G02X119743Y1363743I1467J6D01*
G03X119635Y1363934I-199J13D01*
G02X117738Y1367047I1606J3113D01*
G02X118018Y1368419I3503J0D01*
G03X118019Y1368575I-184J79D01*
G02X117781Y1369405I3222J1373D01*
G02X117754Y1369404I-142J3463D01*
G01X117748D01*
G02X116602Y1369600I3J3468D01*
G03X116470I-66J-189D01*
G02X115321Y1369404I-1149J3272D01*
G02Y1376340I0J3468D01*
G02X116470Y1376144I0J-3468D01*
G03X116602I66J189D01*
G02X117751Y1376340I1149J-3272D01*
G02X118900Y1376144I0J-3468D01*
G03X119032I66J189D01*
G02X119443Y1376260I1146J-3273D01*
G02X119442Y1376305I3501J100D01*
G01Y1376309D01*
G02X119722Y1377679I3503J-2D01*
G03Y1377835I-184J78D01*
G37*
G36*
G01X152322D02*
G02X152042Y1379207I3223J1372D01*
G02X155545Y1382710I3503J0D01*
G02X157716Y1381955I-1J-3503D01*
G03X157947Y1381943I124J157D01*
G02X159811Y1382480I1864J-2967D01*
G02X163314Y1378977I0J-3503D01*
G02X163034Y1377605I-3503J0D01*
G03Y1377449I184J-78D01*
G02X163314Y1376077I-3223J-1372D01*
G02X163034Y1374705I-3503J0D01*
G03Y1374549I184J-78D01*
G02X163314Y1373177I-3223J-1372D01*
G02X159811Y1369674I-3503J0D01*
G02X157865Y1370265I1J3503D01*
G01X157819Y1370295D01*
X157709Y1370301D01*
X157350Y1370111D01*
G03X157243Y1369938I93J-177D01*
G01Y1369937D01*
G02X156963Y1368605I-3502J41D01*
G03X156964Y1368449I185J-77D01*
G02X157244Y1367077I-3223J-1372D01*
G02X150238I-3503J0D01*
G02X150518Y1368449I3503J0D01*
G03X150519Y1368605I-184J79D01*
G02X150315Y1369253I3223J1371D01*
G03X150132Y1369411I-196J-42D01*
G02X149202Y1369600I219J3461D01*
G03X149070I-66J-189D01*
G02X147921Y1369404I-1149J3272D01*
G02Y1376340I0J3468D01*
G02X149070Y1376144I0J-3468D01*
G03X149202I66J189D01*
G02X150351Y1376340I1149J-3272D01*
G02X151500Y1376144I0J-3468D01*
G03X151632I66J189D01*
G02X152043Y1376260I1146J-3273D01*
G02X152042Y1376305I3501J100D01*
G01Y1376309D01*
G02X152322Y1377679I3503J-2D01*
G03Y1377835I-184J78D01*
G37*
G36*
G01X185022D02*
G02X184742Y1379207I3223J1372D01*
G02X188245Y1382710I3503J0D01*
G02X190416Y1381955I-1J-3503D01*
G03X190647Y1381943I124J157D01*
G02X192511Y1382480I1864J-2967D01*
G02X196014Y1378977I0J-3503D01*
G02X195734Y1377605I-3503J0D01*
G03Y1377449I184J-78D01*
G02X196014Y1376077I-3223J-1372D01*
G02X195734Y1374705I-3503J0D01*
G03Y1374549I184J-78D01*
G02X196014Y1373177I-3223J-1372D01*
G02X192511Y1369674I-3503J0D01*
G02X190595Y1370245I1J3503D01*
G01X190550Y1370275D01*
X190445Y1370281D01*
X190087Y1370101D01*
G03X189977Y1369934I90J-179D01*
G02X189704Y1368775I-3496J212D01*
G03Y1368619I184J-78D01*
G02X189984Y1367247I-3223J-1372D01*
G02X182978I-3503J0D01*
G02X183258Y1368619I3503J0D01*
G03Y1368775I-184J78D01*
G02X183058Y1369405I3224J1370D01*
G02X183051Y1369404I-489J3398D01*
G02X181902Y1369600I0J3468D01*
G03X181770I-66J-189D01*
G02X180621Y1369404I-1149J3272D01*
G02Y1376340I0J3468D01*
G02X181770Y1376144I0J-3468D01*
G03X181902I66J189D01*
G02X183051Y1376340I1149J-3272D01*
G02X184200Y1376144I0J-3468D01*
G03X184332I66J189D01*
G02X184743Y1376260I1146J-3273D01*
G02X184742Y1376305I3501J100D01*
G01Y1376309D01*
G02X185022Y1377679I3503J-2D01*
G03Y1377835I-184J78D01*
G37*
G36*
G01X217922D02*
G02X217642Y1379207I3223J1372D01*
G02X221145Y1382710I3503J0D01*
G02X223316Y1381955I-1J-3503D01*
G03X223547Y1381943I124J157D01*
G02X225411Y1382480I1864J-2967D01*
G02X228914Y1378977I0J-3503D01*
G02X228634Y1377605I-3503J0D01*
G03Y1377449I184J-78D01*
G02X228914Y1376077I-3223J-1372D01*
G02X228634Y1374705I-3503J0D01*
G03Y1374549I184J-78D01*
G02X228914Y1373177I-3223J-1372D01*
G02X225411Y1369674I-3503J0D01*
G02X223516Y1370231I0J3502D01*
G01X223471Y1370260D01*
X223364Y1370266D01*
X222960Y1370056D01*
X222902Y1369966D01*
X222900Y1369913D01*
G02X222624Y1368695I-3499J153D01*
G03Y1368539I184J-78D01*
G02X222904Y1367167I-3223J-1372D01*
G02X215898I-3503J0D01*
G02X216178Y1368539I3503J0D01*
G03X216179Y1368695I-184J79D01*
G02X215962Y1369405I3222J1373D01*
G01X215960D01*
G02X215942Y1369404I-20J199D01*
G02X214802Y1369600I9J3468D01*
G03X214670I-66J-189D01*
G02X213521Y1369404I-1149J3272D01*
G02Y1376340I0J3468D01*
G02X214670Y1376144I0J-3468D01*
G03X214802I66J189D01*
G02X215951Y1376340I1149J-3272D01*
G02X217100Y1376144I0J-3468D01*
G03X217232I66J189D01*
G02X217643Y1376260I1146J-3273D01*
G02X217642Y1376305I3501J100D01*
G01Y1376309D01*
G02X217922Y1377679I3503J-2D01*
G03Y1377835I-184J78D01*
G37*
G36*
G01X250722D02*
G02X250442Y1379207I3223J1372D01*
G02X253945Y1382710I3503J0D01*
G02X256116Y1381955I-1J-3503D01*
G03X256347Y1381943I124J157D01*
G02X258211Y1382480I1864J-2967D01*
G02X261714Y1378977I0J-3503D01*
G02X261434Y1377605I-3503J0D01*
G03Y1377449I184J-78D01*
G02X261714Y1376077I-3223J-1372D01*
G02X261434Y1374705I-3503J0D01*
G03Y1374549I184J-78D01*
G02X261714Y1373177I-3223J-1372D01*
G02X258211Y1369674I-3503J0D01*
G02X256286Y1370251I1J3503D01*
G01X256285Y1370252D01*
G03X256088Y1370264I-109J-168D01*
G01X255731Y1370090D01*
X255671Y1370002D01*
X255667Y1369950D01*
G02X255396Y1368861I-3456J282D01*
G03Y1368703I184J-79D01*
G02X255678Y1367335I-3185J-1370D01*
G01Y1367332D01*
G02X248744I-3467J0D01*
G01Y1367335D01*
G02X249026Y1368703I3467J-2D01*
G03Y1368861I-184J79D01*
G02X248843Y1369406I3184J1372D01*
G02X248752Y1369404I-122J3465D01*
G01X248750D01*
G02X247602Y1369600I1J3468D01*
G03X247470I-66J-189D01*
G02X246321Y1369404I-1149J3272D01*
G02Y1376340I0J3468D01*
G02X247470Y1376144I0J-3468D01*
G03X247602I66J189D01*
G02X248751Y1376340I1149J-3272D01*
G02X249900Y1376144I0J-3468D01*
G03X250032I66J189D01*
G02X250443Y1376260I1146J-3273D01*
G02X250442Y1376305I3501J100D01*
G01Y1376309D01*
G02X250722Y1377679I3503J-2D01*
G03Y1377835I-184J78D01*
G37*
G36*
G01X320560Y1377966D02*
G02X320206Y1379500I3149J1535D01*
G02X327212I3503J0D01*
G01Y1379499D01*
G02X326859Y1377967I-3504J1D01*
G03Y1377793I180J-87D01*
G02X327212Y1376259I-3149J-1532D01*
G02X326905Y1374824I-3502J-1D01*
G03X326897Y1374681I183J-82D01*
G02X327062Y1373620I-3338J-1062D01*
G02X326886Y1372524I-3503J0D01*
G03X326896Y1372373I190J-63D01*
G02X327254Y1370831I-3145J-1543D01*
G02X320248I-3503J0D01*
G02X320424Y1371927I3503J0D01*
G03X320414Y1372078I-190J63D01*
G02X320056Y1373620I3145J1543D01*
G02X320364Y1375055I3503J-1D01*
G03X320372Y1375198I-183J82D01*
G02X320208Y1376259I3338J1059D01*
G02X320560Y1377791I3502J2D01*
G03Y1377966I-180J88D01*
G37*
G36*
G01X301918Y1388359D02*
G02X301660Y1389678I3245J1319D01*
G02X308666I3503J0D01*
G02X308408Y1388359I-3503J0D01*
G03Y1388209I185J-75D01*
G02X308666Y1386890I-3245J-1319D01*
G01Y1386889D01*
G02X308358Y1385454I-3503J1D01*
G03X308350Y1385311I183J-82D01*
G02X308514Y1384250I-3338J-1059D01*
G02X308338Y1383153I-3502J-1D01*
G03X308349Y1383003I190J-61D01*
G02X308706Y1381463I-3145J-1541D01*
G01Y1381461D01*
G02X301702I-3502J0D01*
G01Y1381465D01*
G02X301878Y1382558I3502J-3D01*
G03X301867Y1382708I-190J61D01*
G02X301510Y1384250I3145J1541D01*
G02X301817Y1385685I3502J1D01*
G03X301825Y1385828I-183J82D01*
G02X301660Y1386889I3338J1062D01*
G01Y1386890D01*
G02X301918Y1388209I3503J0D01*
G03Y1388359I-185J75D01*
G37*
G36*
G01X1345029Y1393101D02*
G02X1346212Y1393306I1181J-3297D01*
G02X1347395Y1393101I2J-3502D01*
G03X1347529I67J188D01*
G02X1348707Y1393306I1181J-3297D01*
G01X1348712D01*
G02X1350387Y1392879I-1J-3502D01*
G03X1350577I95J176D01*
G02X1352225Y1393290I1646J-3091D01*
G02X1355728Y1389788I1J-3502D01*
G02X1355431Y1388378I-3503J2D01*
G03Y1388216I183J-81D01*
G02X1355728Y1386804I-3205J-1411D01*
G02X1355428Y1385385I-3502J-1D01*
G03Y1385223I183J-81D01*
G02X1355728Y1383806I-3202J-1418D01*
G01Y1383804D01*
G02X1352226Y1380302I-3502J0D01*
G01X1352221D01*
G02X1351121Y1380480I2J3502D01*
G03X1350977Y1380473I-63J-190D01*
G02X1349557Y1380172I-1420J3201D01*
G01X1349555D01*
G02X1348137Y1380472I0J3502D01*
G03X1347975I-81J-183D01*
G02X1346557Y1380172I-1418J3202D01*
G01X1346555D01*
G02X1345137Y1380472I0J3502D01*
G03X1344975I-81J-183D01*
G02X1343557Y1380172I-1418J3202D01*
G01X1343555D01*
G02X1342137Y1380472I0J3502D01*
G03X1341975I-81J-183D01*
G02X1340557Y1380172I-1418J3202D01*
G01X1340555D01*
G02X1339137Y1380472I0J3502D01*
G03X1338975I-81J-183D01*
G02X1337558Y1380172I-1418J3202D01*
G01X1337556D01*
G02X1334054Y1383674I0J3502D01*
G01Y1383676D01*
G02X1334354Y1385093I3502J-1D01*
G03Y1385255I-183J81D01*
G02X1334054Y1386674I3202J1418D01*
G02X1334350Y1388084I3502J1D01*
G03Y1388246I-183J81D01*
G02X1334052Y1389658I3205J1414D01*
G02X1337555Y1393160I3503J-1D01*
G01X1337556D01*
G02X1339163Y1392769I-1J-3502D01*
G03X1339360Y1392777I91J178D01*
G02X1341212Y1393306I1851J-2973D01*
G02X1342395Y1393101I2J-3502D01*
G03X1342529I67J188D01*
G02X1343712Y1393306I1181J-3297D01*
G02X1344895Y1393101I2J-3502D01*
G03X1345029I67J188D01*
G37*
G36*
G01X291534Y1388747D02*
G02X291180Y1390281I3149J1535D01*
G02X298186I3503J0D01*
G01Y1390280D01*
G02X297833Y1388748I-3504J1D01*
G03Y1388574I180J-87D01*
G02X298186Y1387040I-3149J-1532D01*
G02X297879Y1385605I-3502J-1D01*
G03X297871Y1385462I183J-82D01*
G02X298036Y1384401I-3338J-1062D01*
G02X297860Y1383305I-3503J0D01*
G03X297870Y1383154I190J-63D01*
G02X298228Y1381612I-3145J-1543D01*
G02X291222I-3503J0D01*
G02X291398Y1382708I3503J0D01*
G03X291388Y1382859I-190J63D01*
G02X291030Y1384401I3145J1543D01*
G02X291338Y1385836I3503J-1D01*
G03X291346Y1385979I-183J82D01*
G02X291182Y1387040I3338J1059D01*
G02X291534Y1388572I3502J2D01*
G03Y1388747I-180J88D01*
G37*
G36*
G01X1674732Y1396505D02*
Y1396507D01*
G02X1678234Y1400008I3502J-1D01*
G02X1680405Y1399253I-1J-3503D01*
G03X1680636Y1399241I124J157D01*
G02X1682500Y1399778I1864J-2967D01*
G02X1686002Y1396275I-1J-3503D01*
G01Y1396274D01*
G02X1685722Y1394903I-3502J1D01*
G03Y1394747I184J-78D01*
G02X1686002Y1393375I-3222J-1372D01*
G02X1685722Y1392003I-3502J0D01*
G03Y1391847I184J-78D01*
G02X1686002Y1390475I-3222J-1372D01*
G01Y1390473D01*
G02X1682500Y1386972I-3502J1D01*
G02X1679699Y1388372I0J3502D01*
G03X1679581Y1388447I-159J-121D01*
G02X1679532Y1388458I743J3423D01*
G01X1679373Y1388289D01*
G03X1679325Y1388102I146J-137D01*
G02X1679434Y1387235I-3394J-867D01*
G02X1679154Y1385863I-3503J0D01*
G03Y1385707I184J-78D01*
G02X1679434Y1384335I-3223J-1372D01*
G02X1672428I-3503J0D01*
G02X1672708Y1385707I3503J0D01*
G03Y1385863I-184J78D01*
G02X1672484Y1386616I3224J1369D01*
G03X1672328Y1386776I-197J-36D01*
G02X1671891Y1386898I712J3394D01*
G03X1671759I-66J-189D01*
G02X1670610Y1386702I-1149J3272D01*
G02Y1393638I0J3468D01*
G02X1671759Y1393442I0J-3468D01*
G03X1671891I66J189D01*
G02X1673040Y1393638I1149J-3272D01*
G02X1674189Y1393442I0J-3468D01*
G03X1674321I66J189D01*
G02X1674732Y1393558I1146J-3273D01*
G01Y1393605D01*
G02X1675012Y1394977I3502J0D01*
G03Y1395133I-184J78D01*
G02X1674732Y1396505I3222J1372D01*
G37*
G36*
G01X1707514Y1396605D02*
Y1396607D01*
G02X1711016Y1400108I3502J-1D01*
G02X1713187Y1399353I-1J-3503D01*
G03X1713418Y1399341I124J157D01*
G02X1715282Y1399878I1864J-2967D01*
G02X1718784Y1396375I-1J-3503D01*
G01Y1396374D01*
G02X1718504Y1395003I-3502J1D01*
G03Y1394847I184J-78D01*
G02X1718784Y1393475I-3222J-1372D01*
G02X1718504Y1392103I-3502J0D01*
G03Y1391947I184J-78D01*
G02X1718784Y1390575I-3222J-1372D01*
G01Y1390573D01*
G02X1715282Y1387072I-3502J1D01*
G02X1712481Y1388472I0J3502D01*
G03X1712363Y1388547I-159J-121D01*
G02X1712314Y1388558I743J3423D01*
G01X1712155Y1388389D01*
G03X1712107Y1388202I146J-137D01*
G02X1712216Y1387335I-3394J-867D01*
G02X1711936Y1385963I-3503J0D01*
G03Y1385807I184J-78D01*
G02X1712216Y1384435I-3223J-1372D01*
G02X1705210I-3503J0D01*
G02X1705490Y1385807I3503J0D01*
G03Y1385963I-184J78D01*
G02X1705266Y1386716I3224J1369D01*
G03X1705110Y1386876I-197J-36D01*
G02X1704673Y1386998I712J3394D01*
G03X1704541I-66J-189D01*
G02X1703392Y1386802I-1149J3272D01*
G02Y1393738I0J3468D01*
G02X1704541Y1393542I0J-3468D01*
G03X1704673I66J189D01*
G02X1705822Y1393738I1149J-3272D01*
G02X1706971Y1393542I0J-3468D01*
G03X1707103I66J189D01*
G02X1707514Y1393658I1146J-3273D01*
G01Y1393705D01*
G02X1707794Y1395077I3502J0D01*
G03Y1395233I-184J78D01*
G02X1707514Y1396605I3222J1372D01*
G37*
G36*
G01X726998Y1397216D02*
G02X730501Y1400718I3503J-1D01*
G01X730502D01*
G02X732672Y1399964I-1J-3502D01*
G03X732903Y1399952I124J157D01*
G02X734767Y1400488I1862J-2967D01*
G02X738270Y1396986I1J-3502D01*
G02X737990Y1395614I-3503J0D01*
G03Y1395458I184J-78D01*
G02X738270Y1394086I-3223J-1372D01*
G02X737990Y1392714I-3503J0D01*
G03Y1392558I184J-78D01*
G02X738270Y1391186I-3223J-1372D01*
G02X734767Y1387684I-3503J1D01*
G02X731966Y1389083I0J3504D01*
G03X731849Y1389158I-160J-120D01*
G02X731821Y1389164I720J3428D01*
G01X731661Y1388997D01*
G03X731611Y1388814I145J-138D01*
G02X731700Y1388026I-3413J-785D01*
G02X731420Y1386654I-3502J0D01*
G03Y1386498I184J-78D01*
G02X731700Y1385127I-3222J-1372D01*
G01Y1385126D01*
G02X724696I-3502J0D01*
G01Y1385127D01*
G02X724976Y1386498I3502J-1D01*
G03Y1386654I-184J78D01*
G02X724766Y1387328I3222J1373D01*
G03X724610Y1387484I-196J-40D01*
G02X724158Y1387609I696J3397D01*
G03X724026I-66J-189D01*
G02X722881Y1387414I-1146J3272D01*
G01X722877D01*
G02Y1394348I0J3467D01*
G01X722881D01*
G02X724026Y1394153I-1J-3467D01*
G03X724158I66J189D01*
G02X725307Y1394348I1146J-3272D01*
G02X726456Y1394153I3J-3467D01*
G03X726588I66J189D01*
G02X726999Y1394269I1146J-3273D01*
G02X726998Y1394314I3501J100D01*
G01Y1394318D01*
G02X727278Y1395688I3503J-2D01*
G03Y1395844I-184J78D01*
G02X726998Y1397216I3223J1372D01*
G37*
G36*
G01X759780Y1397316D02*
G02X763283Y1400818I3503J-1D01*
G01X763284D01*
G02X765454Y1400064I-1J-3502D01*
G03X765685Y1400052I124J157D01*
G02X767549Y1400588I1862J-2967D01*
G02X771052Y1397086I1J-3502D01*
G02X770772Y1395714I-3503J0D01*
G03Y1395558I184J-78D01*
G02X771052Y1394186I-3223J-1372D01*
G02X770772Y1392814I-3503J0D01*
G03Y1392658I184J-78D01*
G02X771052Y1391286I-3223J-1372D01*
G02X767549Y1387784I-3503J1D01*
G02X764748Y1389183I0J3504D01*
G03X764631Y1389258I-160J-120D01*
G02X764581Y1389269I728J3426D01*
G01X764422Y1389099D01*
G03X764373Y1388913I145J-138D01*
G02X764482Y1388046I-3393J-867D01*
G02X764202Y1386674I-3502J0D01*
G03Y1386518I184J-78D01*
G02X764482Y1385147I-3222J-1372D01*
G01Y1385146D01*
G02X757478I-3502J0D01*
G01Y1385147D01*
G02X757758Y1386518I3502J-1D01*
G03X757757Y1386674I-185J77D01*
G02X757533Y1387427I3224J1369D01*
G03X757377Y1387587I-197J-36D01*
G02X756940Y1387709I712J3394D01*
G03X756808I-66J-189D01*
G02X755663Y1387514I-1146J3272D01*
G01X755659D01*
G02Y1394448I0J3467D01*
G01X755663D01*
G02X756808Y1394253I-1J-3467D01*
G03X756940I66J189D01*
G02X758089Y1394448I1146J-3272D01*
G02X759238Y1394253I3J-3467D01*
G03X759370I66J189D01*
G02X759781Y1394369I1146J-3273D01*
G02X759780Y1394414I3501J100D01*
G01Y1394418D01*
G02X760060Y1395788I3503J-2D01*
G03Y1395944I-184J78D01*
G02X759780Y1397316I3223J1372D01*
G37*
G36*
G01X1136147Y1407174D02*
G03X1136283I68J188D01*
G02X1137465Y1407380I1184J-3297D01*
G02X1140968Y1403877I0J-3503D01*
G02X1140762Y1402695I-3503J2D01*
G03Y1402559I188J-68D01*
G02X1140968Y1401377I-3297J-1184D01*
G02X1140718Y1400079I-3503J2D01*
G03X1140716Y1399936I186J-74D01*
G02X1140928Y1398737I-3291J-1200D01*
G02X1137425Y1395234I-3503J0D01*
G02X1136243Y1395440I2J3503D01*
G03X1136107I-68J-188D01*
G02X1134925Y1395234I-1184J3297D01*
G02X1133743Y1395440I2J3503D01*
G03X1133607I-68J-188D01*
G02X1132425Y1395234I-1184J3297D01*
G02X1131243Y1395440I2J3503D01*
G03X1131107I-68J-188D01*
G02X1129925Y1395234I-1184J3297D01*
G02X1128743Y1395440I2J3503D01*
G03X1128607I-68J-188D01*
G02X1127425Y1395234I-1184J3297D01*
G02X1123922Y1398737I0J3503D01*
G02X1124172Y1400035I3503J-2D01*
G03X1124174Y1400178I-186J74D01*
G02X1123962Y1401377I3291J1200D01*
G02X1124168Y1402559I3503J-2D01*
G03Y1402695I-188J68D01*
G02X1123962Y1403877I3297J1184D01*
G02X1127465Y1407380I3503J0D01*
G02X1128647Y1407174I-2J-3503D01*
G03X1128783I68J188D01*
G02X1129965Y1407380I1184J-3297D01*
G02X1131147Y1407174I-2J-3503D01*
G03X1131283I68J188D01*
G02X1132465Y1407380I1184J-3297D01*
G02X1133647Y1407174I-2J-3503D01*
G03X1133783I68J188D01*
G02X1134965Y1407380I1184J-3297D01*
G02X1136147Y1407174I-2J-3503D01*
G37*
G36*
G01X197990Y1413173D02*
G03X198124I67J188D01*
G02X199307Y1413378I1181J-3297D01*
G02X202810Y1409876I1J-3502D01*
G02X202672Y1408904I-3503J2D01*
G03X202683Y1408766I192J-54D01*
G02X202998Y1407315I-3188J-1452D01*
G01Y1407313D01*
G02X202792Y1406131I-3503J2D01*
G03Y1405995I188J-68D01*
G02X202998Y1404813I-3297J-1184D01*
G02X199495Y1401310I-3503J0D01*
G02X198313Y1401516I2J3503D01*
G03X198177I-68J-188D01*
G02X196995Y1401310I-1184J3297D01*
G02X195813Y1401516I2J3503D01*
G03X195677I-68J-188D01*
G02X194495Y1401310I-1184J3297D01*
G02X193313Y1401516I2J3503D01*
G03X193177I-68J-188D01*
G02X191995Y1401310I-1184J3297D01*
G02X190434Y1401678I2J3503D01*
G03X190256I-89J-179D01*
G02X188695Y1401310I-1563J3135D01*
G02X185192Y1404813I0J3503D01*
G02X185398Y1405995I3503J-2D01*
G03Y1406131I-188J68D01*
G02X185192Y1407313I3297J1184D01*
G02X185330Y1408285I3503J-2D01*
G03X185319Y1408423I-192J54D01*
G02X185004Y1409874I3188J1452D01*
G01Y1409876D01*
G02X188507Y1413378I3503J-1D01*
G02X190068Y1413011I0J-3503D01*
G03X190246I89J179D01*
G02X191807Y1413378I1561J-3136D01*
G01X191810D01*
G02X192990Y1413173I-1J-3502D01*
G03X193124I67J188D01*
G02X194307Y1413378I1181J-3297D01*
G02X195490Y1413173I2J-3502D01*
G03X195624I67J188D01*
G02X196807Y1413378I1181J-3297D01*
G02X197990Y1413173I2J-3502D01*
G37*
G36*
G01X169700Y1414247D02*
Y1414249D01*
G02X176704I3502J0D01*
G01Y1414248D01*
G02X176327Y1412668I-3502J1D01*
G03X176315Y1412517I178J-90D01*
G02X176478Y1411460I-3340J-1056D01*
G02X176341Y1410488I-3502J-2D01*
G03X176351Y1410350I192J-55D01*
G02X176666Y1408897I-3187J-1452D01*
G02X176461Y1407714I-3502J-2D01*
G03Y1407580I188J-67D01*
G02X176666Y1406400I-3297J-1181D01*
G01Y1406397D01*
G02X169662I-3502J0D01*
G01Y1406400D01*
G02X169867Y1407580I3502J-1D01*
G03Y1407714I-188J67D01*
G02X169662Y1408897I3297J1181D01*
G02X169799Y1409869I3502J2D01*
G03X169789Y1410007I-192J55D01*
G02X169474Y1411460I3187J1452D01*
G02X169851Y1413041I3502J0D01*
G03X169863Y1413192I-178J90D01*
G02X169700Y1414247I3340J1056D01*
G37*
G36*
G01X159760Y1413343D02*
G02X159596Y1414400I3339J1059D01*
G02X166602I3503J0D01*
G02X166224Y1412819I-3503J2D01*
G03X166212Y1412668I178J-90D01*
G02X166376Y1411611I-3339J-1059D01*
G02X166238Y1410639I-3503J2D01*
G03X166249Y1410501I192J-54D01*
G02X166564Y1409050I-3188J-1452D01*
G01Y1409048D01*
G02X166358Y1407866I-3503J2D01*
G03Y1407730I188J-68D01*
G02X166564Y1406548I-3297J-1184D01*
G02X159558I-3503J0D01*
G02X159764Y1407730I3503J-2D01*
G03Y1407866I-188J68D01*
G02X159558Y1409048I3297J1184D01*
G02X159696Y1410020I3503J-2D01*
G03X159685Y1410158I-192J54D01*
G02X159370Y1411609I3188J1452D01*
G01Y1411611D01*
G02X159748Y1413192I3503J-2D01*
G03X159760Y1413343I-178J90D01*
G37*
G36*
G01X1715866Y1426415D02*
G03X1716028I81J183D01*
G02X1717447Y1426716I1421J-3202D01*
G02X1720950Y1423213I0J-3503D01*
G02X1720649Y1421794I-3503J2D01*
G03Y1421632I183J-81D01*
G02X1720950Y1420213I-3202J-1421D01*
G02X1720649Y1418794I-3503J2D01*
G03Y1418632I183J-81D01*
G02X1720950Y1417213I-3202J-1421D01*
G02X1717447Y1413710I-3503J0D01*
G02X1716028Y1414011I2J3503D01*
G03X1715866I-81J-183D01*
G02X1714447Y1413710I-1421J3202D01*
G02X1710944Y1417213I0J3503D01*
G02X1711245Y1418632I3503J-2D01*
G03Y1418794I-183J81D01*
G02X1710944Y1420213I3202J1421D01*
G02X1711245Y1421632I3503J-2D01*
G03Y1421794I-183J81D01*
G02X1710944Y1423213I3202J1421D01*
G02X1714447Y1426716I3503J0D01*
G02X1715866Y1426415I-2J-3503D01*
G37*
G36*
G01X733999Y1429324D02*
G02X735416Y1429624I1418J-3202D01*
G01X735418D01*
G02X738920Y1426122I0J-3502D01*
G01Y1426120D01*
G02X738620Y1424703I-3502J1D01*
G03Y1424541I183J-81D01*
G02X738920Y1423122I-3202J-1418D01*
G02X738620Y1421703I-3502J-1D01*
G03Y1421541I183J-81D01*
G02X738920Y1420124I-3202J-1418D01*
G01Y1420122D01*
G02X735418Y1416620I-3502J0D01*
G01X735416D01*
G02X733999Y1416920I1J3502D01*
G03X733837I-81J-183D01*
G02X732420Y1416620I-1418J3202D01*
G01X732418D01*
G02X728916Y1420122I0J3502D01*
G01Y1420124D01*
G02X729216Y1421541I3502J-1D01*
G03Y1421703I-183J81D01*
G02X728916Y1423122I3202J1418D01*
G02X729216Y1424541I3502J1D01*
G03Y1424703I-183J81D01*
G02X728916Y1426120I3202J1418D01*
G01Y1426122D01*
G02X732418Y1429624I3502J0D01*
G01X732420D01*
G02X733837Y1429324I-1J-3502D01*
G03X733999I81J183D01*
G37*
G36*
G01X176051Y1451392D02*
G02Y1454398I0J1503D01*
G01X179451D01*
G02Y1451392I0J-1503D01*
G01X176051D01*
G37*
G36*
G01X202851D02*
G02Y1454398I0J1503D01*
G01X206251D01*
G02Y1451392I0J-1503D01*
G01X202851D01*
G37*
G36*
G01X229651D02*
G02Y1454398I0J1503D01*
G01X233051D01*
G02Y1451392I0J-1503D01*
G01X229651D01*
G37*
G36*
G01X256451D02*
G02Y1454398I0J1503D01*
G01X259851D01*
G02Y1451392I0J-1503D01*
G01X256451D01*
G37*
G36*
G01X269851D02*
G02Y1454398I0J1503D01*
G01X273251D01*
G02Y1451392I0J-1503D01*
G01X269851D01*
G37*
G36*
G01X304113D02*
G02Y1454398I0J1503D01*
G01X307513D01*
G02Y1451392I0J-1503D01*
G01X304113D01*
G37*
G36*
G01X330913D02*
G02Y1454398I0J1503D01*
G01X334313D01*
G02Y1451392I0J-1503D01*
G01X330913D01*
G37*
G36*
G01X357713D02*
G02Y1454398I0J1503D01*
G01X361113D01*
G02Y1451392I0J-1503D01*
G01X357713D01*
G37*
G36*
G01X384513D02*
G02Y1454398I0J1503D01*
G01X387913D01*
G02Y1451392I0J-1503D01*
G01X384513D01*
G37*
G36*
G01X397913D02*
G02Y1454398I0J1503D01*
G01X401313D01*
G02Y1451392I0J-1503D01*
G01X397913D01*
G37*
G36*
G01X440224D02*
G02Y1454398I0J1503D01*
G01X443624D01*
G02Y1451392I0J-1503D01*
G01X440224D01*
G37*
G36*
G01X467024D02*
G02Y1454398I0J1503D01*
G01X470424D01*
G02Y1451392I0J-1503D01*
G01X467024D01*
G37*
G36*
G01X493824D02*
G02Y1454398I0J1503D01*
G01X497224D01*
G02Y1451392I0J-1503D01*
G01X493824D01*
G37*
G36*
G01X520624D02*
G02Y1454398I0J1503D01*
G01X524024D01*
G02Y1451392I0J-1503D01*
G01X520624D01*
G37*
G36*
G01X534024D02*
G02Y1454398I0J1503D01*
G01X537424D01*
G02Y1451392I0J-1503D01*
G01X534024D01*
G37*
G36*
G01X568286D02*
G02Y1454398I0J1503D01*
G01X571686D01*
G02Y1451392I0J-1503D01*
G01X568286D01*
G37*
G36*
G01X595086D02*
G02Y1454398I0J1503D01*
G01X598486D01*
G02Y1451392I0J-1503D01*
G01X595086D01*
G37*
G36*
G01X621886D02*
G02Y1454398I0J1503D01*
G01X625286D01*
G02Y1451392I0J-1503D01*
G01X621886D01*
G37*
G36*
G01X648686D02*
G02Y1454398I0J1503D01*
G01X652086D01*
G02Y1451392I0J-1503D01*
G01X648686D01*
G37*
G36*
G01X662086D02*
G02Y1454398I0J1503D01*
G01X665486D01*
G02Y1451392I0J-1503D01*
G01X662086D01*
G37*
G36*
G01X691276Y1453610D02*
G02Y1456614I0J1502D01*
G01X694676D01*
G02Y1453610I0J-1502D01*
G01X691276D01*
G37*
G36*
G01X169351Y1461092D02*
G02Y1464098I0J1503D01*
G01X172751D01*
G02Y1461092I0J-1503D01*
G01X169351D01*
G37*
G36*
G01X196151D02*
G02Y1464098I0J1503D01*
G01X199551D01*
G02Y1461092I0J-1503D01*
G01X196151D01*
G37*
G36*
G01X222951D02*
G02Y1464098I0J1503D01*
G01X226351D01*
G02Y1461092I0J-1503D01*
G01X222951D01*
G37*
G36*
G01X249751D02*
G02Y1464098I0J1503D01*
G01X253151D01*
G02Y1461092I0J-1503D01*
G01X249751D01*
G37*
G36*
G01X297413D02*
G02Y1464098I0J1503D01*
G01X300813D01*
G02Y1461092I0J-1503D01*
G01X297413D01*
G37*
G36*
G01X324213D02*
G02Y1464098I0J1503D01*
G01X327613D01*
G02Y1461092I0J-1503D01*
G01X324213D01*
G37*
G36*
G01X351013D02*
G02Y1464098I0J1503D01*
G01X354413D01*
G02Y1461092I0J-1503D01*
G01X351013D01*
G37*
G36*
G01X377813D02*
G02Y1464098I0J1503D01*
G01X381213D01*
G02Y1461092I0J-1503D01*
G01X377813D01*
G37*
G36*
G01X433524D02*
G02Y1464098I0J1503D01*
G01X436924D01*
G02Y1461092I0J-1503D01*
G01X433524D01*
G37*
G36*
G01X460324D02*
G02Y1464098I0J1503D01*
G01X463724D01*
G02Y1461092I0J-1503D01*
G01X460324D01*
G37*
G36*
G01X487124D02*
G02Y1464098I0J1503D01*
G01X490524D01*
G02Y1461092I0J-1503D01*
G01X487124D01*
G37*
G36*
G01X513924D02*
G02Y1464098I0J1503D01*
G01X517324D01*
G02Y1461092I0J-1503D01*
G01X513924D01*
G37*
G36*
G01X561586D02*
G02Y1464098I0J1503D01*
G01X564986D01*
G02Y1461092I0J-1503D01*
G01X561586D01*
G37*
G36*
G01X588386D02*
G02Y1464098I0J1503D01*
G01X591786D01*
G02Y1461092I0J-1503D01*
G01X588386D01*
G37*
G36*
G01X615186D02*
G02Y1464098I0J1503D01*
G01X618586D01*
G02Y1461092I0J-1503D01*
G01X615186D01*
G37*
G36*
G01X641986D02*
G02Y1464098I0J1503D01*
G01X645386D01*
G02Y1461092I0J-1503D01*
G01X641986D01*
G37*
G36*
G01X189451Y1470792D02*
G02Y1473798I0J1503D01*
G01X192851D01*
G02Y1470792I0J-1503D01*
G01X189451D01*
G37*
G36*
G01X216251D02*
G02Y1473798I0J1503D01*
G01X219651D01*
G02Y1470792I0J-1503D01*
G01X216251D01*
G37*
G36*
G01X243051D02*
G02Y1473798I0J1503D01*
G01X246451D01*
G02Y1470792I0J-1503D01*
G01X243051D01*
G37*
G36*
G01X317513D02*
G02Y1473798I0J1503D01*
G01X320913D01*
G02Y1470792I0J-1503D01*
G01X317513D01*
G37*
G36*
G01X344313D02*
G02Y1473798I0J1503D01*
G01X347713D01*
G02Y1470792I0J-1503D01*
G01X344313D01*
G37*
G36*
G01X371113D02*
G02Y1473798I0J1503D01*
G01X374513D01*
G02Y1470792I0J-1503D01*
G01X371113D01*
G37*
G36*
G01X453624D02*
G02Y1473798I0J1503D01*
G01X457024D01*
G02Y1470792I0J-1503D01*
G01X453624D01*
G37*
G36*
G01X480424D02*
G02Y1473798I0J1503D01*
G01X483824D01*
G02Y1470792I0J-1503D01*
G01X480424D01*
G37*
G36*
G01X507224D02*
G02Y1473798I0J1503D01*
G01X510624D01*
G02Y1470792I0J-1503D01*
G01X507224D01*
G37*
G36*
G01X581686D02*
G02Y1473798I0J1503D01*
G01X585086D01*
G02Y1470792I0J-1503D01*
G01X581686D01*
G37*
G36*
G01X608486D02*
G02Y1473798I0J1503D01*
G01X611886D01*
G02Y1470792I0J-1503D01*
G01X608486D01*
G37*
G36*
G01X635286D02*
G02Y1473798I0J1503D01*
G01X638686D01*
G02Y1470792I0J-1503D01*
G01X635286D01*
G37*
G36*
G01X1183924Y1484392D02*
G02Y1487398I0J1503D01*
G01X1187324D01*
G02Y1484392I0J-1503D01*
G01X1183924D01*
G37*
G36*
G01X1210724D02*
G02Y1487398I0J1503D01*
G01X1214124D01*
G02Y1484392I0J-1503D01*
G01X1210724D01*
G37*
G36*
G01X1237524D02*
G02Y1487398I0J1503D01*
G01X1240924D01*
G02Y1484392I0J-1503D01*
G01X1237524D01*
G37*
G36*
G01X1264324D02*
G02Y1487398I0J1503D01*
G01X1267724D01*
G02Y1484392I0J-1503D01*
G01X1264324D01*
G37*
G36*
G01X1277724D02*
G02Y1487398I0J1503D01*
G01X1281124D01*
G02Y1484392I0J-1503D01*
G01X1277724D01*
G37*
G36*
G01X1311986D02*
G02Y1487398I0J1503D01*
G01X1315386D01*
G02Y1484392I0J-1503D01*
G01X1311986D01*
G37*
G36*
G01X1338786D02*
G02Y1487398I0J1503D01*
G01X1342186D01*
G02Y1484392I0J-1503D01*
G01X1338786D01*
G37*
G36*
G01X1365586D02*
G02Y1487398I0J1503D01*
G01X1368986D01*
G02Y1484392I0J-1503D01*
G01X1365586D01*
G37*
G36*
G01X1392386D02*
G02Y1487398I0J1503D01*
G01X1395786D01*
G02Y1484392I0J-1503D01*
G01X1392386D01*
G37*
G36*
G01X1405786D02*
G02Y1487398I0J1503D01*
G01X1409186D01*
G02Y1484392I0J-1503D01*
G01X1405786D01*
G37*
G36*
G01X1448098D02*
G02Y1487398I0J1503D01*
G01X1451498D01*
G02Y1484392I0J-1503D01*
G01X1448098D01*
G37*
G36*
G01X1474898D02*
G02Y1487398I0J1503D01*
G01X1478298D01*
G02Y1484392I0J-1503D01*
G01X1474898D01*
G37*
G36*
G01X1501698D02*
G02Y1487398I0J1503D01*
G01X1505098D01*
G02Y1484392I0J-1503D01*
G01X1501698D01*
G37*
G36*
G01X1528498D02*
G02Y1487398I0J1503D01*
G01X1531898D01*
G02Y1484392I0J-1503D01*
G01X1528498D01*
G37*
G36*
G01X1541898D02*
G02Y1487398I0J1503D01*
G01X1545298D01*
G02Y1484392I0J-1503D01*
G01X1541898D01*
G37*
G36*
G01X1576160D02*
G02Y1487398I0J1503D01*
G01X1579560D01*
G02Y1484392I0J-1503D01*
G01X1576160D01*
G37*
G36*
G01X1602960D02*
G02Y1487398I0J1503D01*
G01X1606360D01*
G02Y1484392I0J-1503D01*
G01X1602960D01*
G37*
G36*
G01X1629760D02*
G02Y1487398I0J1503D01*
G01X1633160D01*
G02Y1484392I0J-1503D01*
G01X1629760D01*
G37*
G36*
G01X1656560D02*
G02Y1487398I0J1503D01*
G01X1659960D01*
G02Y1484392I0J-1503D01*
G01X1656560D01*
G37*
G36*
G01X1669960D02*
G02Y1487398I0J1503D01*
G01X1673360D01*
G02Y1484392I0J-1503D01*
G01X1669960D01*
G37*
G36*
G01X1177224Y1494092D02*
G02Y1497098I0J1503D01*
G01X1180624D01*
G02Y1494092I0J-1503D01*
G01X1177224D01*
G37*
G36*
G01X1204024D02*
G02Y1497098I0J1503D01*
G01X1207424D01*
G02Y1494092I0J-1503D01*
G01X1204024D01*
G37*
G36*
G01X1230824D02*
G02Y1497098I0J1503D01*
G01X1234224D01*
G02Y1494092I0J-1503D01*
G01X1230824D01*
G37*
G36*
G01X1257624D02*
G02Y1497098I0J1503D01*
G01X1261024D01*
G02Y1494092I0J-1503D01*
G01X1257624D01*
G37*
G36*
G01X1305286D02*
G02Y1497098I0J1503D01*
G01X1308686D01*
G02Y1494092I0J-1503D01*
G01X1305286D01*
G37*
G36*
G01X1332086D02*
G02Y1497098I0J1503D01*
G01X1335486D01*
G02Y1494092I0J-1503D01*
G01X1332086D01*
G37*
G36*
G01X1358886D02*
G02Y1497098I0J1503D01*
G01X1362286D01*
G02Y1494092I0J-1503D01*
G01X1358886D01*
G37*
G36*
G01X1385686D02*
G02Y1497098I0J1503D01*
G01X1389086D01*
G02Y1494092I0J-1503D01*
G01X1385686D01*
G37*
G36*
G01X1441398D02*
G02Y1497098I0J1503D01*
G01X1444798D01*
G02Y1494092I0J-1503D01*
G01X1441398D01*
G37*
G36*
G01X1468198D02*
G02Y1497098I0J1503D01*
G01X1471598D01*
G02Y1494092I0J-1503D01*
G01X1468198D01*
G37*
G36*
G01X1494998D02*
G02Y1497098I0J1503D01*
G01X1498398D01*
G02Y1494092I0J-1503D01*
G01X1494998D01*
G37*
G36*
G01X1521798D02*
G02Y1497098I0J1503D01*
G01X1525198D01*
G02Y1494092I0J-1503D01*
G01X1521798D01*
G37*
G36*
G01X1569460D02*
G02Y1497098I0J1503D01*
G01X1572860D01*
G02Y1494092I0J-1503D01*
G01X1569460D01*
G37*
G36*
G01X1596260D02*
G02Y1497098I0J1503D01*
G01X1599660D01*
G02Y1494092I0J-1503D01*
G01X1596260D01*
G37*
G36*
G01X1623060D02*
G02Y1497098I0J1503D01*
G01X1626460D01*
G02Y1494092I0J-1503D01*
G01X1623060D01*
G37*
G36*
G01X1649860D02*
G02Y1497098I0J1503D01*
G01X1653260D01*
G02Y1494092I0J-1503D01*
G01X1649860D01*
G37*
G36*
G01X1197324Y1503792D02*
G02Y1506798I0J1503D01*
G01X1200724D01*
G02Y1503792I0J-1503D01*
G01X1197324D01*
G37*
G36*
G01X1224124D02*
G02Y1506798I0J1503D01*
G01X1227524D01*
G02Y1503792I0J-1503D01*
G01X1224124D01*
G37*
G36*
G01X1250924D02*
G02Y1506798I0J1503D01*
G01X1254324D01*
G02Y1503792I0J-1503D01*
G01X1250924D01*
G37*
G36*
G01X1325386D02*
G02Y1506798I0J1503D01*
G01X1328786D01*
G02Y1503792I0J-1503D01*
G01X1325386D01*
G37*
G36*
G01X1352186D02*
G02Y1506798I0J1503D01*
G01X1355586D01*
G02Y1503792I0J-1503D01*
G01X1352186D01*
G37*
G36*
G01X1378986D02*
G02Y1506798I0J1503D01*
G01X1382386D01*
G02Y1503792I0J-1503D01*
G01X1378986D01*
G37*
G36*
G01X1461498D02*
G02Y1506798I0J1503D01*
G01X1464898D01*
G02Y1503792I0J-1503D01*
G01X1461498D01*
G37*
G36*
G01X1488298D02*
G02Y1506798I0J1503D01*
G01X1491698D01*
G02Y1503792I0J-1503D01*
G01X1488298D01*
G37*
G36*
G01X1515098D02*
G02Y1506798I0J1503D01*
G01X1518498D01*
G02Y1503792I0J-1503D01*
G01X1515098D01*
G37*
G36*
G01X1589560D02*
G02Y1506798I0J1503D01*
G01X1592960D01*
G02Y1503792I0J-1503D01*
G01X1589560D01*
G37*
G36*
G01X1616360D02*
G02Y1506798I0J1503D01*
G01X1619760D01*
G02Y1503792I0J-1503D01*
G01X1616360D01*
G37*
G36*
G01X1643160D02*
G02Y1506798I0J1503D01*
G01X1646560D01*
G02Y1503792I0J-1503D01*
G01X1643160D01*
G37*
G36*
G01X188668Y1520261D02*
X188670Y1520264D01*
G02X189730Y1520900I1060J-565D01*
G02X190932Y1519698I0J-1202D01*
G01Y1519697D01*
G02X190772Y1519098I-1203J1D01*
G01X189227Y1516425D01*
X189225Y1516421D01*
G02X188155Y1515768I-1070J550D01*
G01X188153D01*
G02X186952Y1516970I1J1202D01*
G01Y1516972D01*
G02X187102Y1517551I1203J-3D01*
G01X188668Y1520261D01*
G37*
G36*
G01X193392D02*
X193394Y1520264D01*
G02X194454Y1520900I1060J-565D01*
G02X195656Y1519698I0J-1202D01*
G01Y1519697D01*
G02X195496Y1519098I-1203J1D01*
G01X193951Y1516425D01*
X193949Y1516421D01*
G02X192879Y1515768I-1070J550D01*
G01X192877D01*
G02X191676Y1516970I1J1202D01*
G01Y1516972D01*
G02X191826Y1517551I1203J-3D01*
G01X193392Y1520261D01*
G37*
G36*
G01X198116D02*
X198118Y1520264D01*
G02X199178Y1520900I1060J-565D01*
G02X200380Y1519698I0J-1202D01*
G01Y1519697D01*
G02X200220Y1519098I-1203J1D01*
G01X198675Y1516425D01*
X198673Y1516421D01*
G02X197603Y1515768I-1070J550D01*
G01X197601D01*
G02X196400Y1516970I1J1202D01*
G01Y1516972D01*
G02X196550Y1517551I1203J-3D01*
G01X198116Y1520261D01*
G37*
G36*
G01X202843Y1520264D02*
G02X203903Y1520900I1060J-565D01*
G01X203905D01*
G02X205106Y1519698I-1J-1202D01*
G02X204945Y1519098I-1204J1D01*
G01X203400Y1516425D01*
X203398Y1516421D01*
G02X202328Y1515768I-1070J550D01*
G02X201126Y1516970I0J1202D01*
G01Y1516972D01*
G02X201275Y1517551I1202J-1D01*
G01X202841Y1520261D01*
X202843Y1520264D01*
G37*
G36*
G01X207567D02*
G02X208627Y1520900I1060J-565D01*
G01X208629D01*
G02X209830Y1519698I-1J-1202D01*
G02X209669Y1519098I-1204J1D01*
G01X208124Y1516425D01*
X208122Y1516421D01*
G02X207052Y1515768I-1070J550D01*
G02X205850Y1516970I0J1202D01*
G01Y1516972D01*
G02X205999Y1517551I1202J-1D01*
G01X207565Y1520261D01*
X207567Y1520264D01*
G37*
G36*
G01X212290Y1520261D02*
X212292Y1520264D01*
G02X213352Y1520900I1060J-565D01*
G02X214554Y1519698I0J-1202D01*
G01Y1519697D01*
G02X214394Y1519098I-1203J1D01*
G01X212849Y1516425D01*
X212847Y1516421D01*
G02X211777Y1515768I-1070J550D01*
G01X211775D01*
G02X210574Y1516970I1J1202D01*
G01Y1516972D01*
G02X210724Y1517551I1203J-3D01*
G01X212290Y1520261D01*
G37*
G36*
G01X217014D02*
X217016Y1520264D01*
G02X218076Y1520900I1060J-565D01*
G02X219278Y1519698I0J-1202D01*
G01Y1519697D01*
G02X219118Y1519098I-1203J1D01*
G01X217573Y1516425D01*
X217571Y1516421D01*
G02X216501Y1515768I-1070J550D01*
G01X216499D01*
G02X215298Y1516970I1J1202D01*
G01Y1516972D01*
G02X215448Y1517551I1203J-3D01*
G01X217014Y1520261D01*
G37*
G36*
G01X221738D02*
X221740Y1520264D01*
G02X222800Y1520900I1060J-565D01*
G02X224002Y1519698I0J-1202D01*
G01Y1519697D01*
G02X223842Y1519098I-1203J1D01*
G01X222297Y1516425D01*
X222295Y1516421D01*
G02X221225Y1515768I-1070J550D01*
G01X221223D01*
G02X220022Y1516970I1J1202D01*
G01Y1516972D01*
G02X220172Y1517551I1203J-3D01*
G01X221738Y1520261D01*
G37*
G36*
G01X226465Y1520264D02*
G02X227525Y1520900I1060J-565D01*
G01X227526D01*
G02X228728Y1519698I0J-1202D01*
G01Y1519697D01*
G02X228568Y1519098I-1203J1D01*
G01X227023Y1516425D01*
X227021Y1516421D01*
G02X225951Y1515768I-1070J550D01*
G01X225950D01*
G02X224748Y1516970I0J1202D01*
G01Y1516972D01*
G02X224897Y1517551I1202J-1D01*
G01X226463Y1520261D01*
X226465Y1520264D01*
G37*
G36*
G01X231189D02*
G02X232249Y1520900I1060J-565D01*
G01X232250D01*
G02X233452Y1519698I0J-1202D01*
G01Y1519697D01*
G02X233292Y1519098I-1203J1D01*
G01X231747Y1516425D01*
X231745Y1516421D01*
G02X230675Y1515768I-1070J550D01*
G01X230674D01*
G02X229472Y1516970I0J1202D01*
G01Y1516972D01*
G02X229621Y1517551I1202J-1D01*
G01X231187Y1520261D01*
X231189Y1520264D01*
G37*
G36*
G01X235912Y1520261D02*
X235914Y1520264D01*
G02X236974Y1520900I1060J-565D01*
G02X238176Y1519698I0J-1202D01*
G01Y1519697D01*
G02X238016Y1519098I-1203J1D01*
G01X236471Y1516425D01*
X236469Y1516421D01*
G02X235399Y1515768I-1070J550D01*
G01X235397D01*
G02X234196Y1516970I1J1202D01*
G01Y1516972D01*
G02X234346Y1517551I1203J-3D01*
G01X235912Y1520261D01*
G37*
G36*
G01X250087Y1520264D02*
G02X251147Y1520900I1060J-565D01*
G01X251148D01*
G02X252350Y1519698I0J-1202D01*
G01Y1519697D01*
G02X252190Y1519098I-1203J1D01*
G01X250645Y1516425D01*
X250643Y1516421D01*
G02X249573Y1515768I-1070J550D01*
G01X249572D01*
G02X248370Y1516970I0J1202D01*
G01Y1516972D01*
G02X248519Y1517551I1202J-1D01*
G01X250085Y1520261D01*
X250087Y1520264D01*
G37*
G36*
G01X254811D02*
G02X255871Y1520900I1060J-565D01*
G01X255872D01*
G02X257074Y1519698I0J-1202D01*
G01Y1519697D01*
G02X256914Y1519098I-1203J1D01*
G01X255369Y1516425D01*
X255367Y1516421D01*
G02X254297Y1515768I-1070J550D01*
G01X254296D01*
G02X253094Y1516970I0J1202D01*
G01Y1516972D01*
G02X253243Y1517551I1202J-1D01*
G01X254809Y1520261D01*
X254811Y1520264D01*
G37*
G36*
G01X259534Y1520261D02*
X259536Y1520264D01*
G02X260596Y1520900I1060J-565D01*
G02X261798Y1519698I0J-1202D01*
G01Y1519697D01*
G02X261638Y1519098I-1203J1D01*
G01X260093Y1516425D01*
X260091Y1516421D01*
G02X259021Y1515768I-1070J550D01*
G01X259019D01*
G02X257818Y1516970I1J1202D01*
G01Y1516972D01*
G02X257968Y1517551I1203J-3D01*
G01X259534Y1520261D01*
G37*
G36*
G01X316730D02*
X316732Y1520264D01*
G02X317792Y1520900I1060J-565D01*
G02X318994Y1519698I0J-1202D01*
G01Y1519697D01*
G02X318834Y1519098I-1203J1D01*
G01X317289Y1516425D01*
X317287Y1516421D01*
G02X316217Y1515768I-1070J550D01*
G01X316215D01*
G02X315014Y1516970I1J1202D01*
G01Y1516972D01*
G02X315164Y1517551I1203J-3D01*
G01X316730Y1520261D01*
G37*
G36*
G01X321454D02*
X321456Y1520264D01*
G02X322516Y1520900I1060J-565D01*
G02X323718Y1519698I0J-1202D01*
G01Y1519697D01*
G02X323558Y1519098I-1203J1D01*
G01X322013Y1516425D01*
X322011Y1516421D01*
G02X320941Y1515768I-1070J550D01*
G01X320939D01*
G02X319738Y1516970I1J1202D01*
G01Y1516972D01*
G02X319888Y1517551I1203J-3D01*
G01X321454Y1520261D01*
G37*
G36*
G01X326178D02*
X326180Y1520264D01*
G02X327240Y1520900I1060J-565D01*
G02X328442Y1519698I0J-1202D01*
G01Y1519697D01*
G02X328282Y1519098I-1203J1D01*
G01X326737Y1516425D01*
X326735Y1516421D01*
G02X325665Y1515768I-1070J550D01*
G01X325663D01*
G02X324462Y1516970I1J1202D01*
G01Y1516972D01*
G02X324612Y1517551I1203J-3D01*
G01X326178Y1520261D01*
G37*
G36*
G01X330905Y1520264D02*
G02X331965Y1520900I1060J-565D01*
G01X331967D01*
G02X333168Y1519698I-1J-1202D01*
G02X333007Y1519098I-1204J1D01*
G01X331462Y1516425D01*
X331460Y1516421D01*
G02X330390Y1515768I-1070J550D01*
G02X329188Y1516970I0J1202D01*
G01Y1516972D01*
G02X329337Y1517551I1202J-1D01*
G01X330903Y1520261D01*
X330905Y1520264D01*
G37*
G36*
G01X335629D02*
G02X336689Y1520900I1060J-565D01*
G01X336691D01*
G02X337892Y1519698I-1J-1202D01*
G02X337731Y1519098I-1204J1D01*
G01X336186Y1516425D01*
X336184Y1516421D01*
G02X335114Y1515768I-1070J550D01*
G02X333912Y1516970I0J1202D01*
G01Y1516972D01*
G02X334061Y1517551I1202J-1D01*
G01X335627Y1520261D01*
X335629Y1520264D01*
G37*
G36*
G01X340352Y1520261D02*
X340354Y1520264D01*
G02X341414Y1520900I1060J-565D01*
G02X342616Y1519698I0J-1202D01*
G01Y1519697D01*
G02X342456Y1519098I-1203J1D01*
G01X340911Y1516425D01*
X340909Y1516421D01*
G02X339839Y1515768I-1070J550D01*
G01X339837D01*
G02X338636Y1516970I1J1202D01*
G01Y1516972D01*
G02X338786Y1517551I1203J-3D01*
G01X340352Y1520261D01*
G37*
G36*
G01X345076D02*
X345078Y1520264D01*
G02X346138Y1520900I1060J-565D01*
G02X347340Y1519698I0J-1202D01*
G01Y1519697D01*
G02X347180Y1519098I-1203J1D01*
G01X345635Y1516425D01*
X345633Y1516421D01*
G02X344563Y1515768I-1070J550D01*
G01X344561D01*
G02X343360Y1516970I1J1202D01*
G01Y1516972D01*
G02X343510Y1517551I1203J-3D01*
G01X345076Y1520261D01*
G37*
G36*
G01X349800D02*
X349802Y1520264D01*
G02X350862Y1520900I1060J-565D01*
G02X352064Y1519698I0J-1202D01*
G01Y1519697D01*
G02X351904Y1519098I-1203J1D01*
G01X350359Y1516425D01*
X350357Y1516421D01*
G02X349287Y1515768I-1070J550D01*
G01X349285D01*
G02X348084Y1516970I1J1202D01*
G01Y1516972D01*
G02X348234Y1517551I1203J-3D01*
G01X349800Y1520261D01*
G37*
G36*
G01X354527Y1520264D02*
G02X355587Y1520900I1060J-565D01*
G01X355589D01*
G02X356790Y1519698I-1J-1202D01*
G02X356629Y1519098I-1204J1D01*
G01X355084Y1516425D01*
X355082Y1516421D01*
G02X354012Y1515768I-1070J550D01*
G02X352810Y1516970I0J1202D01*
G01Y1516972D01*
G02X352959Y1517551I1202J-1D01*
G01X354525Y1520261D01*
X354527Y1520264D01*
G37*
G36*
G01X359251D02*
G02X360311Y1520900I1060J-565D01*
G01X360313D01*
G02X361514Y1519698I-1J-1202D01*
G02X361353Y1519098I-1204J1D01*
G01X359808Y1516425D01*
X359806Y1516421D01*
G02X358736Y1515768I-1070J550D01*
G02X357534Y1516970I0J1202D01*
G01Y1516972D01*
G02X357683Y1517551I1202J-1D01*
G01X359249Y1520261D01*
X359251Y1520264D01*
G37*
G36*
G01X363974Y1520261D02*
X363976Y1520264D01*
G02X365036Y1520900I1060J-565D01*
G02X366238Y1519698I0J-1202D01*
G01Y1519697D01*
G02X366078Y1519098I-1203J1D01*
G01X364533Y1516425D01*
X364531Y1516421D01*
G02X363461Y1515768I-1070J550D01*
G01X363459D01*
G02X362258Y1516970I1J1202D01*
G01Y1516972D01*
G02X362408Y1517551I1203J-3D01*
G01X363974Y1520261D01*
G37*
G36*
G01X368698D02*
X368700Y1520264D01*
G02X369760Y1520900I1060J-565D01*
G02X370962Y1519698I0J-1202D01*
G01Y1519697D01*
G02X370802Y1519098I-1203J1D01*
G01X369257Y1516425D01*
X369255Y1516421D01*
G02X368185Y1515768I-1070J550D01*
G01X368183D01*
G02X366982Y1516970I1J1202D01*
G01Y1516972D01*
G02X367132Y1517551I1203J-3D01*
G01X368698Y1520261D01*
G37*
G36*
G01X373422D02*
X373424Y1520264D01*
G02X374484Y1520900I1060J-565D01*
G02X375686Y1519698I0J-1202D01*
G01Y1519697D01*
G02X375526Y1519098I-1203J1D01*
G01X373981Y1516425D01*
X373979Y1516421D01*
G02X372909Y1515768I-1070J550D01*
G01X372907D01*
G02X371706Y1516970I1J1202D01*
G01Y1516972D01*
G02X371856Y1517551I1203J-3D01*
G01X373422Y1520261D01*
G37*
G36*
G01X378149Y1520264D02*
G02X379209Y1520900I1060J-565D01*
G01X379211D01*
G02X380412Y1519698I-1J-1202D01*
G02X380251Y1519098I-1204J1D01*
G01X378706Y1516425D01*
X378704Y1516421D01*
G02X377634Y1515768I-1070J550D01*
G02X376432Y1516970I0J1202D01*
G01Y1516972D01*
G02X376581Y1517551I1202J-1D01*
G01X378147Y1520261D01*
X378149Y1520264D01*
G37*
G36*
G01X382873D02*
G02X383933Y1520900I1060J-565D01*
G01X383935D01*
G02X385136Y1519698I-1J-1202D01*
G02X384975Y1519098I-1204J1D01*
G01X383430Y1516425D01*
X383428Y1516421D01*
G02X382358Y1515768I-1070J550D01*
G02X381156Y1516970I0J1202D01*
G01Y1516972D01*
G02X381305Y1517551I1202J-1D01*
G01X382871Y1520261D01*
X382873Y1520264D01*
G37*
G36*
G01X387596Y1520261D02*
X387598Y1520264D01*
G02X388658Y1520900I1060J-565D01*
G02X389860Y1519698I0J-1202D01*
G01Y1519697D01*
G02X389700Y1519098I-1203J1D01*
G01X388155Y1516425D01*
X388153Y1516421D01*
G02X387083Y1515768I-1070J550D01*
G01X387081D01*
G02X385880Y1516970I1J1202D01*
G01Y1516972D01*
G02X386030Y1517551I1203J-3D01*
G01X387596Y1520261D01*
G37*
G36*
G01X452843Y1520264D02*
G02X453903Y1520900I1060J-565D01*
G01X453905D01*
G02X455106Y1519698I-1J-1202D01*
G02X454945Y1519098I-1204J1D01*
G01X453400Y1516425D01*
X453398Y1516421D01*
G02X452328Y1515768I-1070J550D01*
G02X451126Y1516970I0J1202D01*
G01Y1516972D01*
G02X451275Y1517551I1202J-1D01*
G01X452841Y1520261D01*
X452843Y1520264D01*
G37*
G36*
G01X457567D02*
G02X458627Y1520900I1060J-565D01*
G01X458629D01*
G02X459830Y1519698I-1J-1202D01*
G02X459669Y1519098I-1204J1D01*
G01X458124Y1516425D01*
X458122Y1516421D01*
G02X457052Y1515768I-1070J550D01*
G02X455850Y1516970I0J1202D01*
G01Y1516972D01*
G02X455999Y1517551I1202J-1D01*
G01X457565Y1520261D01*
X457567Y1520264D01*
G37*
G36*
G01X462291D02*
G02X463351Y1520900I1060J-565D01*
G01X463353D01*
G02X464554Y1519698I-1J-1202D01*
G02X464393Y1519098I-1204J1D01*
G01X462848Y1516425D01*
X462846Y1516421D01*
G02X461776Y1515768I-1070J550D01*
G02X460574Y1516970I0J1202D01*
G01Y1516972D01*
G02X460723Y1517551I1202J-1D01*
G01X462289Y1520261D01*
X462291Y1520264D01*
G37*
G36*
G01X467014Y1520261D02*
X467016Y1520264D01*
G02X468076Y1520900I1060J-565D01*
G02X469278Y1519698I0J-1202D01*
G01Y1519697D01*
G02X469118Y1519098I-1203J1D01*
G01X467573Y1516425D01*
X467571Y1516421D01*
G02X466501Y1515768I-1070J550D01*
G01X466499D01*
G02X465298Y1516970I1J1202D01*
G01Y1516972D01*
G02X465448Y1517551I1203J-3D01*
G01X467014Y1520261D01*
G37*
G36*
G01X471738D02*
X471740Y1520264D01*
G02X472800Y1520900I1060J-565D01*
G02X474002Y1519698I0J-1202D01*
G01Y1519697D01*
G02X473842Y1519098I-1203J1D01*
G01X472297Y1516425D01*
X472295Y1516421D01*
G02X471225Y1515768I-1070J550D01*
G01X471223D01*
G02X470022Y1516970I1J1202D01*
G01Y1516972D01*
G02X470172Y1517551I1203J-3D01*
G01X471738Y1520261D01*
G37*
G36*
G01X476465Y1520264D02*
G02X477525Y1520900I1060J-565D01*
G01X477527D01*
G02X478728Y1519698I-1J-1202D01*
G02X478567Y1519098I-1204J1D01*
G01X477022Y1516425D01*
X477020Y1516421D01*
G02X475950Y1515768I-1070J550D01*
G02X474748Y1516970I0J1202D01*
G01Y1516972D01*
G02X474897Y1517551I1202J-1D01*
G01X476463Y1520261D01*
X476465Y1520264D01*
G37*
G36*
G01X481189D02*
G02X482249Y1520900I1060J-565D01*
G01X482251D01*
G02X483452Y1519698I-1J-1202D01*
G02X483291Y1519098I-1204J1D01*
G01X481746Y1516425D01*
X481744Y1516421D01*
G02X480674Y1515768I-1070J550D01*
G02X479472Y1516970I0J1202D01*
G01Y1516972D01*
G02X479621Y1517551I1202J-1D01*
G01X481187Y1520261D01*
X481189Y1520264D01*
G37*
G36*
G01X485913D02*
G02X486973Y1520900I1060J-565D01*
G01X486975D01*
G02X488176Y1519698I-1J-1202D01*
G02X488015Y1519098I-1204J1D01*
G01X486470Y1516425D01*
X486468Y1516421D01*
G02X485398Y1515768I-1070J550D01*
G02X484196Y1516970I0J1202D01*
G01Y1516972D01*
G02X484345Y1517551I1202J-1D01*
G01X485911Y1520261D01*
X485913Y1520264D01*
G37*
G36*
G01X490636Y1520261D02*
X490638Y1520264D01*
G02X491698Y1520900I1060J-565D01*
G02X492900Y1519698I0J-1202D01*
G01Y1519697D01*
G02X492740Y1519098I-1203J1D01*
G01X491195Y1516425D01*
X491193Y1516421D01*
G02X490123Y1515768I-1070J550D01*
G01X490121D01*
G02X488920Y1516970I1J1202D01*
G01Y1516972D01*
G02X489070Y1517551I1203J-3D01*
G01X490636Y1520261D01*
G37*
G36*
G01X495360D02*
X495362Y1520264D01*
G02X496422Y1520900I1060J-565D01*
G02X497624Y1519698I0J-1202D01*
G01Y1519697D01*
G02X497464Y1519098I-1203J1D01*
G01X495919Y1516425D01*
X495917Y1516421D01*
G02X494847Y1515768I-1070J550D01*
G01X494845D01*
G02X493644Y1516970I1J1202D01*
G01Y1516972D01*
G02X493794Y1517551I1203J-3D01*
G01X495360Y1520261D01*
G37*
G36*
G01X500087Y1520264D02*
G02X501147Y1520900I1060J-565D01*
G01X501149D01*
G02X502350Y1519698I-1J-1202D01*
G02X502189Y1519098I-1204J1D01*
G01X500644Y1516425D01*
X500642Y1516421D01*
G02X499572Y1515768I-1070J550D01*
G02X498370Y1516970I0J1202D01*
G01Y1516972D01*
G02X498519Y1517551I1202J-1D01*
G01X500085Y1520261D01*
X500087Y1520264D01*
G37*
G36*
G01X504811D02*
G02X505871Y1520900I1060J-565D01*
G01X505873D01*
G02X507074Y1519698I-1J-1202D01*
G02X506913Y1519098I-1204J1D01*
G01X505368Y1516425D01*
X505366Y1516421D01*
G02X504296Y1515768I-1070J550D01*
G02X503094Y1516970I0J1202D01*
G01Y1516972D01*
G02X503243Y1517551I1202J-1D01*
G01X504809Y1520261D01*
X504811Y1520264D01*
G37*
G36*
G01X509535D02*
G02X510595Y1520900I1060J-565D01*
G01X510597D01*
G02X511798Y1519698I-1J-1202D01*
G02X511637Y1519098I-1204J1D01*
G01X510092Y1516425D01*
X510090Y1516421D01*
G02X509020Y1515768I-1070J550D01*
G02X507818Y1516970I0J1202D01*
G01Y1516972D01*
G02X507967Y1517551I1202J-1D01*
G01X509533Y1520261D01*
X509535Y1520264D01*
G37*
G36*
G01X514258Y1520261D02*
X514260Y1520264D01*
G02X515320Y1520900I1060J-565D01*
G02X516522Y1519698I0J-1202D01*
G01Y1519697D01*
G02X516362Y1519098I-1203J1D01*
G01X514817Y1516425D01*
X514815Y1516421D01*
G02X513745Y1515768I-1070J550D01*
G01X513743D01*
G02X512542Y1516970I1J1202D01*
G01Y1516972D01*
G02X512692Y1517551I1203J-3D01*
G01X514258Y1520261D01*
G37*
G36*
G01X518982D02*
X518984Y1520264D01*
G02X520044Y1520900I1060J-565D01*
G02X521246Y1519698I0J-1202D01*
G01Y1519697D01*
G02X521086Y1519098I-1203J1D01*
G01X519541Y1516425D01*
X519539Y1516421D01*
G02X518469Y1515768I-1070J550D01*
G01X518467D01*
G02X517266Y1516970I1J1202D01*
G01Y1516972D01*
G02X517416Y1517551I1203J-3D01*
G01X518982Y1520261D01*
G37*
G36*
G01X523709Y1520264D02*
G02X524769Y1520900I1060J-565D01*
G01X524771D01*
G02X525972Y1519698I-1J-1202D01*
G02X525811Y1519098I-1204J1D01*
G01X524266Y1516425D01*
X524264Y1516421D01*
G02X523194Y1515768I-1070J550D01*
G02X521992Y1516970I0J1202D01*
G01Y1516972D01*
G02X522141Y1517551I1202J-1D01*
G01X523707Y1520261D01*
X523709Y1520264D01*
G37*
G36*
G01X580905D02*
G02X581965Y1520900I1060J-565D01*
G01X581967D01*
G02X583168Y1519698I-1J-1202D01*
G02X583007Y1519098I-1204J1D01*
G01X581462Y1516425D01*
X581460Y1516421D01*
G02X580390Y1515768I-1070J550D01*
G02X579188Y1516970I0J1202D01*
G01Y1516972D01*
G02X579337Y1517551I1202J-1D01*
G01X580903Y1520261D01*
X580905Y1520264D01*
G37*
G36*
G01X585629D02*
G02X586689Y1520900I1060J-565D01*
G01X586691D01*
G02X587892Y1519698I-1J-1202D01*
G02X587731Y1519098I-1204J1D01*
G01X586186Y1516425D01*
X586184Y1516421D01*
G02X585114Y1515768I-1070J550D01*
G02X583912Y1516970I0J1202D01*
G01Y1516972D01*
G02X584061Y1517551I1202J-1D01*
G01X585627Y1520261D01*
X585629Y1520264D01*
G37*
G36*
G01X590353D02*
G02X591413Y1520900I1060J-565D01*
G01X591415D01*
G02X592616Y1519698I-1J-1202D01*
G02X592455Y1519098I-1204J1D01*
G01X590910Y1516425D01*
X590908Y1516421D01*
G02X589838Y1515768I-1070J550D01*
G02X588636Y1516970I0J1202D01*
G01Y1516972D01*
G02X588785Y1517551I1202J-1D01*
G01X590351Y1520261D01*
X590353Y1520264D01*
G37*
G36*
G01X595076Y1520261D02*
X595078Y1520264D01*
G02X596138Y1520900I1060J-565D01*
G02X597340Y1519698I0J-1202D01*
G01Y1519697D01*
G02X597180Y1519098I-1203J1D01*
G01X595635Y1516425D01*
X595633Y1516421D01*
G02X594563Y1515768I-1070J550D01*
G01X594561D01*
G02X593360Y1516970I1J1202D01*
G01Y1516972D01*
G02X593510Y1517551I1203J-3D01*
G01X595076Y1520261D01*
G37*
G36*
G01X599800D02*
X599802Y1520264D01*
G02X600862Y1520900I1060J-565D01*
G02X602064Y1519698I0J-1202D01*
G01Y1519697D01*
G02X601904Y1519098I-1203J1D01*
G01X600359Y1516425D01*
X600357Y1516421D01*
G02X599287Y1515768I-1070J550D01*
G01X599285D01*
G02X598084Y1516970I1J1202D01*
G01Y1516972D01*
G02X598234Y1517551I1203J-3D01*
G01X599800Y1520261D01*
G37*
G36*
G01X604527Y1520264D02*
G02X605587Y1520900I1060J-565D01*
G01X605589D01*
G02X606790Y1519698I-1J-1202D01*
G02X606629Y1519098I-1204J1D01*
G01X605084Y1516425D01*
X605082Y1516421D01*
G02X604012Y1515768I-1070J550D01*
G02X602810Y1516970I0J1202D01*
G01Y1516972D01*
G02X602959Y1517551I1202J-1D01*
G01X604525Y1520261D01*
X604527Y1520264D01*
G37*
G36*
G01X609251D02*
G02X610311Y1520900I1060J-565D01*
G01X610313D01*
G02X611514Y1519698I-1J-1202D01*
G02X611353Y1519098I-1204J1D01*
G01X609808Y1516425D01*
X609806Y1516421D01*
G02X608736Y1515768I-1070J550D01*
G02X607534Y1516970I0J1202D01*
G01Y1516972D01*
G02X607683Y1517551I1202J-1D01*
G01X609249Y1520261D01*
X609251Y1520264D01*
G37*
G36*
G01X613975D02*
G02X615035Y1520900I1060J-565D01*
G01X615037D01*
G02X616238Y1519698I-1J-1202D01*
G02X616077Y1519098I-1204J1D01*
G01X614532Y1516425D01*
X614530Y1516421D01*
G02X613460Y1515768I-1070J550D01*
G02X612258Y1516970I0J1202D01*
G01Y1516972D01*
G02X612407Y1517551I1202J-1D01*
G01X613973Y1520261D01*
X613975Y1520264D01*
G37*
G36*
G01X618698Y1520261D02*
X618700Y1520264D01*
G02X619760Y1520900I1060J-565D01*
G02X620962Y1519698I0J-1202D01*
G01Y1519697D01*
G02X620802Y1519098I-1203J1D01*
G01X619257Y1516425D01*
X619255Y1516421D01*
G02X618185Y1515768I-1070J550D01*
G01X618183D01*
G02X616982Y1516970I1J1202D01*
G01Y1516972D01*
G02X617132Y1517551I1203J-3D01*
G01X618698Y1520261D01*
G37*
G36*
G01X623422D02*
X623424Y1520264D01*
G02X624484Y1520900I1060J-565D01*
G02X625686Y1519698I0J-1202D01*
G01Y1519697D01*
G02X625526Y1519098I-1203J1D01*
G01X623981Y1516425D01*
X623979Y1516421D01*
G02X622909Y1515768I-1070J550D01*
G01X622907D01*
G02X621706Y1516970I1J1202D01*
G01Y1516972D01*
G02X621856Y1517551I1203J-3D01*
G01X623422Y1520261D01*
G37*
G36*
G01X628149Y1520264D02*
G02X629209Y1520900I1060J-565D01*
G01X629211D01*
G02X630412Y1519698I-1J-1202D01*
G02X630251Y1519098I-1204J1D01*
G01X628706Y1516425D01*
X628704Y1516421D01*
G02X627634Y1515768I-1070J550D01*
G02X626432Y1516970I0J1202D01*
G01Y1516972D01*
G02X626581Y1517551I1202J-1D01*
G01X628147Y1520261D01*
X628149Y1520264D01*
G37*
G36*
G01X632873D02*
G02X633933Y1520900I1060J-565D01*
G01X633935D01*
G02X635136Y1519698I-1J-1202D01*
G02X634975Y1519098I-1204J1D01*
G01X633430Y1516425D01*
X633428Y1516421D01*
G02X632358Y1515768I-1070J550D01*
G02X631156Y1516970I0J1202D01*
G01Y1516972D01*
G02X631305Y1517551I1202J-1D01*
G01X632871Y1520261D01*
X632873Y1520264D01*
G37*
G36*
G01X637597D02*
G02X638657Y1520900I1060J-565D01*
G01X638659D01*
G02X639860Y1519698I-1J-1202D01*
G02X639699Y1519098I-1204J1D01*
G01X638154Y1516425D01*
X638152Y1516421D01*
G02X637082Y1515768I-1070J550D01*
G02X635880Y1516970I0J1202D01*
G01Y1516972D01*
G02X636029Y1517551I1202J-1D01*
G01X637595Y1520261D01*
X637597Y1520264D01*
G37*
G36*
G01X642320Y1520261D02*
X642322Y1520264D01*
G02X643382Y1520900I1060J-565D01*
G02X644584Y1519698I0J-1202D01*
G01Y1519697D01*
G02X644424Y1519098I-1203J1D01*
G01X642879Y1516425D01*
X642877Y1516421D01*
G02X641807Y1515768I-1070J550D01*
G01X641805D01*
G02X640604Y1516970I1J1202D01*
G01Y1516972D01*
G02X640754Y1517551I1203J-3D01*
G01X642320Y1520261D01*
G37*
G36*
G01X647044D02*
X647046Y1520264D01*
G02X648106Y1520900I1060J-565D01*
G02X649308Y1519698I0J-1202D01*
G01Y1519697D01*
G02X649148Y1519098I-1203J1D01*
G01X647603Y1516425D01*
X647601Y1516421D01*
G02X646531Y1515768I-1070J550D01*
G01X646529D01*
G02X645328Y1516970I1J1202D01*
G01Y1516972D01*
G02X645478Y1517551I1203J-3D01*
G01X647044Y1520261D01*
G37*
G36*
G01X651771Y1520264D02*
G02X652831Y1520900I1060J-565D01*
G01X652833D01*
G02X654034Y1519698I-1J-1202D01*
G02X653873Y1519098I-1204J1D01*
G01X652328Y1516425D01*
X652326Y1516421D01*
G02X651256Y1515768I-1070J550D01*
G02X650054Y1516970I0J1202D01*
G01Y1516972D01*
G02X650203Y1517551I1202J-1D01*
G01X651769Y1520261D01*
X651771Y1520264D01*
G37*
G36*
G01X241698Y1520900D02*
X241699D01*
G02X242902Y1519698I1J-1202D01*
G02X242741Y1519098I-1204J1D01*
G01X241196Y1516425D01*
X241194Y1516421D01*
G02X240124Y1515768I-1070J550D01*
G01X240123D01*
G02X238920Y1516970I-1J1202D01*
G01Y1516972D01*
G02X239070Y1517551I1203J-3D01*
G01X240636Y1520261D01*
X240638Y1520264D01*
G02X241698Y1520900I1060J-565D01*
G37*
G36*
G01X246422D02*
X246423D01*
G02X247626Y1519698I1J-1202D01*
G02X247465Y1519098I-1204J1D01*
G01X245920Y1516425D01*
X245918Y1516421D01*
G02X244848Y1515768I-1070J550D01*
G01X244847D01*
G02X243644Y1516970I-1J1202D01*
G01Y1516972D01*
G02X243794Y1517551I1203J-3D01*
G01X245360Y1520261D01*
X245362Y1520264D01*
G02X246422Y1520900I1060J-565D01*
G37*
G36*
G01X188668Y1533899D02*
X188670Y1533902D01*
G02X189730Y1534538I1060J-565D01*
G02X190932Y1533336I0J-1202D01*
G01Y1533335D01*
G02X190772Y1532736I-1203J1D01*
G01X189227Y1530063D01*
X189225Y1530059D01*
G02X188155Y1529406I-1070J550D01*
G01X188153D01*
G02X186952Y1530608I1J1202D01*
G01Y1530610D01*
G02X187102Y1531189I1203J-3D01*
G01X188668Y1533899D01*
G37*
G36*
G01X193392D02*
X193394Y1533902D01*
G02X194454Y1534538I1060J-565D01*
G02X195656Y1533336I0J-1202D01*
G01Y1533335D01*
G02X195496Y1532736I-1203J1D01*
G01X193951Y1530063D01*
X193949Y1530059D01*
G02X192879Y1529406I-1070J550D01*
G01X192877D01*
G02X191676Y1530608I1J1202D01*
G01Y1530610D01*
G02X191826Y1531189I1203J-3D01*
G01X193392Y1533899D01*
G37*
G36*
G01X198116D02*
X198118Y1533902D01*
G02X199178Y1534538I1060J-565D01*
G02X200380Y1533336I0J-1202D01*
G01Y1533335D01*
G02X200220Y1532736I-1203J1D01*
G01X198675Y1530063D01*
X198673Y1530059D01*
G02X197603Y1529406I-1070J550D01*
G01X197601D01*
G02X196400Y1530608I1J1202D01*
G01Y1530610D01*
G02X196550Y1531189I1203J-3D01*
G01X198116Y1533899D01*
G37*
G36*
G01X202843Y1533902D02*
G02X203903Y1534538I1060J-565D01*
G01X203905D01*
G02X205106Y1533336I-1J-1202D01*
G02X204945Y1532736I-1204J1D01*
G01X203400Y1530063D01*
X203398Y1530059D01*
G02X202328Y1529406I-1070J550D01*
G02X201126Y1530608I0J1202D01*
G01Y1530610D01*
G02X201275Y1531189I1202J-1D01*
G01X202841Y1533899D01*
X202843Y1533902D01*
G37*
G36*
G01X207567D02*
G02X208627Y1534538I1060J-565D01*
G01X208629D01*
G02X209830Y1533336I-1J-1202D01*
G02X209669Y1532736I-1204J1D01*
G01X208124Y1530063D01*
X208122Y1530059D01*
G02X207052Y1529406I-1070J550D01*
G02X205850Y1530608I0J1202D01*
G01Y1530610D01*
G02X205999Y1531189I1202J-1D01*
G01X207565Y1533899D01*
X207567Y1533902D01*
G37*
G36*
G01X212290Y1533899D02*
X212292Y1533902D01*
G02X213352Y1534538I1060J-565D01*
G02X214554Y1533336I0J-1202D01*
G01Y1533335D01*
G02X214394Y1532736I-1203J1D01*
G01X212849Y1530063D01*
X212847Y1530059D01*
G02X211777Y1529406I-1070J550D01*
G01X211775D01*
G02X210574Y1530608I1J1202D01*
G01Y1530610D01*
G02X210724Y1531189I1203J-3D01*
G01X212290Y1533899D01*
G37*
G36*
G01X217014D02*
X217016Y1533902D01*
G02X218076Y1534538I1060J-565D01*
G02X219278Y1533336I0J-1202D01*
G01Y1533335D01*
G02X219118Y1532736I-1203J1D01*
G01X217573Y1530063D01*
X217571Y1530059D01*
G02X216501Y1529406I-1070J550D01*
G01X216499D01*
G02X215298Y1530608I1J1202D01*
G01Y1530610D01*
G02X215448Y1531189I1203J-3D01*
G01X217014Y1533899D01*
G37*
G36*
G01X221738D02*
X221740Y1533902D01*
G02X222800Y1534538I1060J-565D01*
G02X224002Y1533336I0J-1202D01*
G01Y1533335D01*
G02X223842Y1532736I-1203J1D01*
G01X222297Y1530063D01*
X222295Y1530059D01*
G02X221225Y1529406I-1070J550D01*
G01X221223D01*
G02X220022Y1530608I1J1202D01*
G01Y1530610D01*
G02X220172Y1531189I1203J-3D01*
G01X221738Y1533899D01*
G37*
G36*
G01X226465Y1533902D02*
G02X227525Y1534538I1060J-565D01*
G01X227527D01*
G02X228728Y1533336I-1J-1202D01*
G02X228567Y1532736I-1204J1D01*
G01X227022Y1530063D01*
X227020Y1530059D01*
G02X225950Y1529406I-1070J550D01*
G02X224748Y1530608I0J1202D01*
G01Y1530610D01*
G02X224897Y1531189I1202J-1D01*
G01X226463Y1533899D01*
X226465Y1533902D01*
G37*
G36*
G01X231189D02*
G02X232249Y1534538I1060J-565D01*
G01X232251D01*
G02X233452Y1533336I-1J-1202D01*
G02X233291Y1532736I-1204J1D01*
G01X231746Y1530063D01*
X231744Y1530059D01*
G02X230674Y1529406I-1070J550D01*
G02X229472Y1530608I0J1202D01*
G01Y1530610D01*
G02X229621Y1531189I1202J-1D01*
G01X231187Y1533899D01*
X231189Y1533902D01*
G37*
G36*
G01X235912Y1533899D02*
X235914Y1533902D01*
G02X236974Y1534538I1060J-565D01*
G02X238176Y1533336I0J-1202D01*
G01Y1533335D01*
G02X238016Y1532736I-1203J1D01*
G01X236471Y1530063D01*
X236469Y1530059D01*
G02X235399Y1529406I-1070J550D01*
G01X235397D01*
G02X234196Y1530608I1J1202D01*
G01Y1530610D01*
G02X234346Y1531189I1203J-3D01*
G01X235912Y1533899D01*
G37*
G36*
G01X240636D02*
X240638Y1533902D01*
G02X241698Y1534538I1060J-565D01*
G02X242900Y1533336I0J-1202D01*
G01Y1533335D01*
G02X242740Y1532736I-1203J1D01*
G01X241195Y1530063D01*
X241193Y1530059D01*
G02X240123Y1529406I-1070J550D01*
G01X240121D01*
G02X238920Y1530608I1J1202D01*
G01Y1530610D01*
G02X239070Y1531189I1203J-3D01*
G01X240636Y1533899D01*
G37*
G36*
G01X245360D02*
X245362Y1533902D01*
G02X246422Y1534538I1060J-565D01*
G02X247624Y1533336I0J-1202D01*
G01Y1533335D01*
G02X247464Y1532736I-1203J1D01*
G01X245919Y1530063D01*
X245917Y1530059D01*
G02X244847Y1529406I-1070J550D01*
G01X244845D01*
G02X243644Y1530608I1J1202D01*
G01Y1530610D01*
G02X243794Y1531189I1203J-3D01*
G01X245360Y1533899D01*
G37*
G36*
G01X250087Y1533902D02*
G02X251147Y1534538I1060J-565D01*
G01X251149D01*
G02X252350Y1533336I-1J-1202D01*
G02X252189Y1532736I-1204J1D01*
G01X250644Y1530063D01*
X250642Y1530059D01*
G02X249572Y1529406I-1070J550D01*
G02X248370Y1530608I0J1202D01*
G01Y1530610D01*
G02X248519Y1531189I1202J-1D01*
G01X250085Y1533899D01*
X250087Y1533902D01*
G37*
G36*
G01X254811D02*
G02X255871Y1534538I1060J-565D01*
G01X255873D01*
G02X257074Y1533336I-1J-1202D01*
G02X256913Y1532736I-1204J1D01*
G01X255368Y1530063D01*
X255366Y1530059D01*
G02X254296Y1529406I-1070J550D01*
G02X253094Y1530608I0J1202D01*
G01Y1530610D01*
G02X253243Y1531189I1202J-1D01*
G01X254809Y1533899D01*
X254811Y1533902D01*
G37*
G36*
G01X259534Y1533899D02*
X259536Y1533902D01*
G02X260596Y1534538I1060J-565D01*
G02X261798Y1533336I0J-1202D01*
G01Y1533335D01*
G02X261638Y1532736I-1203J1D01*
G01X260093Y1530063D01*
X260091Y1530059D01*
G02X259021Y1529406I-1070J550D01*
G01X259019D01*
G02X257818Y1530608I1J1202D01*
G01Y1530610D01*
G02X257968Y1531189I1203J-3D01*
G01X259534Y1533899D01*
G37*
G36*
G01X316730D02*
X316732Y1533902D01*
G02X317792Y1534538I1060J-565D01*
G02X318994Y1533336I0J-1202D01*
G01Y1533335D01*
G02X318834Y1532736I-1203J1D01*
G01X317289Y1530063D01*
X317287Y1530059D01*
G02X316217Y1529406I-1070J550D01*
G01X316215D01*
G02X315014Y1530608I1J1202D01*
G01Y1530610D01*
G02X315164Y1531189I1203J-3D01*
G01X316730Y1533899D01*
G37*
G36*
G01X321454D02*
X321456Y1533902D01*
G02X322516Y1534538I1060J-565D01*
G02X323718Y1533336I0J-1202D01*
G01Y1533335D01*
G02X323558Y1532736I-1203J1D01*
G01X322013Y1530063D01*
X322011Y1530059D01*
G02X320941Y1529406I-1070J550D01*
G01X320939D01*
G02X319738Y1530608I1J1202D01*
G01Y1530610D01*
G02X319888Y1531189I1203J-3D01*
G01X321454Y1533899D01*
G37*
G36*
G01X326178D02*
X326180Y1533902D01*
G02X327240Y1534538I1060J-565D01*
G02X328442Y1533336I0J-1202D01*
G01Y1533335D01*
G02X328282Y1532736I-1203J1D01*
G01X326737Y1530063D01*
X326735Y1530059D01*
G02X325665Y1529406I-1070J550D01*
G01X325663D01*
G02X324462Y1530608I1J1202D01*
G01Y1530610D01*
G02X324612Y1531189I1203J-3D01*
G01X326178Y1533899D01*
G37*
G36*
G01X330905Y1533902D02*
G02X331965Y1534538I1060J-565D01*
G01X331967D01*
G02X333168Y1533336I-1J-1202D01*
G02X333007Y1532736I-1204J1D01*
G01X331462Y1530063D01*
X331460Y1530059D01*
G02X330390Y1529406I-1070J550D01*
G02X329188Y1530608I0J1202D01*
G01Y1530610D01*
G02X329337Y1531189I1202J-1D01*
G01X330903Y1533899D01*
X330905Y1533902D01*
G37*
G36*
G01X335629D02*
G02X336689Y1534538I1060J-565D01*
G01X336691D01*
G02X337892Y1533336I-1J-1202D01*
G02X337731Y1532736I-1204J1D01*
G01X336186Y1530063D01*
X336184Y1530059D01*
G02X335114Y1529406I-1070J550D01*
G02X333912Y1530608I0J1202D01*
G01Y1530610D01*
G02X334061Y1531189I1202J-1D01*
G01X335627Y1533899D01*
X335629Y1533902D01*
G37*
G36*
G01X340352Y1533899D02*
X340354Y1533902D01*
G02X341414Y1534538I1060J-565D01*
G02X342616Y1533336I0J-1202D01*
G01Y1533335D01*
G02X342456Y1532736I-1203J1D01*
G01X340911Y1530063D01*
X340909Y1530059D01*
G02X339839Y1529406I-1070J550D01*
G01X339837D01*
G02X338636Y1530608I1J1202D01*
G01Y1530610D01*
G02X338786Y1531189I1203J-3D01*
G01X340352Y1533899D01*
G37*
G36*
G01X345076D02*
X345078Y1533902D01*
G02X346138Y1534538I1060J-565D01*
G02X347340Y1533336I0J-1202D01*
G01Y1533335D01*
G02X347180Y1532736I-1203J1D01*
G01X345635Y1530063D01*
X345633Y1530059D01*
G02X344563Y1529406I-1070J550D01*
G01X344561D01*
G02X343360Y1530608I1J1202D01*
G01Y1530610D01*
G02X343510Y1531189I1203J-3D01*
G01X345076Y1533899D01*
G37*
G36*
G01X349800D02*
X349802Y1533902D01*
G02X350862Y1534538I1060J-565D01*
G02X352064Y1533336I0J-1202D01*
G01Y1533335D01*
G02X351904Y1532736I-1203J1D01*
G01X350359Y1530063D01*
X350357Y1530059D01*
G02X349287Y1529406I-1070J550D01*
G01X349285D01*
G02X348084Y1530608I1J1202D01*
G01Y1530610D01*
G02X348234Y1531189I1203J-3D01*
G01X349800Y1533899D01*
G37*
G36*
G01X354527Y1533902D02*
G02X355587Y1534538I1060J-565D01*
G01X355589D01*
G02X356790Y1533336I-1J-1202D01*
G02X356629Y1532736I-1204J1D01*
G01X355084Y1530063D01*
X355082Y1530059D01*
G02X354012Y1529406I-1070J550D01*
G02X352810Y1530608I0J1202D01*
G01Y1530610D01*
G02X352959Y1531189I1202J-1D01*
G01X354525Y1533899D01*
X354527Y1533902D01*
G37*
G36*
G01X359251D02*
G02X360311Y1534538I1060J-565D01*
G01X360313D01*
G02X361514Y1533336I-1J-1202D01*
G02X361353Y1532736I-1204J1D01*
G01X359808Y1530063D01*
X359806Y1530059D01*
G02X358736Y1529406I-1070J550D01*
G02X357534Y1530608I0J1202D01*
G01Y1530610D01*
G02X357683Y1531189I1202J-1D01*
G01X359249Y1533899D01*
X359251Y1533902D01*
G37*
G36*
G01X363974Y1533899D02*
X363976Y1533902D01*
G02X365036Y1534538I1060J-565D01*
G02X366238Y1533336I0J-1202D01*
G01Y1533335D01*
G02X366078Y1532736I-1203J1D01*
G01X364533Y1530063D01*
X364531Y1530059D01*
G02X363461Y1529406I-1070J550D01*
G01X363459D01*
G02X362258Y1530608I1J1202D01*
G01Y1530610D01*
G02X362408Y1531189I1203J-3D01*
G01X363974Y1533899D01*
G37*
G36*
G01X368698D02*
X368700Y1533902D01*
G02X369760Y1534538I1060J-565D01*
G02X370962Y1533336I0J-1202D01*
G01Y1533335D01*
G02X370802Y1532736I-1203J1D01*
G01X369257Y1530063D01*
X369255Y1530059D01*
G02X368185Y1529406I-1070J550D01*
G01X368183D01*
G02X366982Y1530608I1J1202D01*
G01Y1530610D01*
G02X367132Y1531189I1203J-3D01*
G01X368698Y1533899D01*
G37*
G36*
G01X373422D02*
X373424Y1533902D01*
G02X374484Y1534538I1060J-565D01*
G02X375686Y1533336I0J-1202D01*
G01Y1533335D01*
G02X375526Y1532736I-1203J1D01*
G01X373981Y1530063D01*
X373979Y1530059D01*
G02X372909Y1529406I-1070J550D01*
G01X372907D01*
G02X371706Y1530608I1J1202D01*
G01Y1530610D01*
G02X371856Y1531189I1203J-3D01*
G01X373422Y1533899D01*
G37*
G36*
G01X378149Y1533902D02*
G02X379209Y1534538I1060J-565D01*
G01X379211D01*
G02X380412Y1533336I-1J-1202D01*
G02X380251Y1532736I-1204J1D01*
G01X378706Y1530063D01*
X378704Y1530059D01*
G02X377634Y1529406I-1070J550D01*
G02X376432Y1530608I0J1202D01*
G01Y1530610D01*
G02X376581Y1531189I1202J-1D01*
G01X378147Y1533899D01*
X378149Y1533902D01*
G37*
G36*
G01X382873D02*
G02X383933Y1534538I1060J-565D01*
G01X383935D01*
G02X385136Y1533336I-1J-1202D01*
G02X384975Y1532736I-1204J1D01*
G01X383430Y1530063D01*
X383428Y1530059D01*
G02X382358Y1529406I-1070J550D01*
G02X381156Y1530608I0J1202D01*
G01Y1530610D01*
G02X381305Y1531189I1202J-1D01*
G01X382871Y1533899D01*
X382873Y1533902D01*
G37*
G36*
G01X387596Y1533899D02*
X387598Y1533902D01*
G02X388658Y1534538I1060J-565D01*
G02X389860Y1533336I0J-1202D01*
G01Y1533335D01*
G02X389700Y1532736I-1203J1D01*
G01X388155Y1530063D01*
X388153Y1530059D01*
G02X387083Y1529406I-1070J550D01*
G01X387081D01*
G02X385880Y1530608I1J1202D01*
G01Y1530610D01*
G02X386030Y1531189I1203J-3D01*
G01X387596Y1533899D01*
G37*
G36*
G01X452843Y1533902D02*
G02X453903Y1534538I1060J-565D01*
G01X453905D01*
G02X455106Y1533336I-1J-1202D01*
G02X454945Y1532736I-1204J1D01*
G01X453400Y1530063D01*
X453398Y1530059D01*
G02X452328Y1529406I-1070J550D01*
G02X451126Y1530608I0J1202D01*
G01Y1530610D01*
G02X451275Y1531189I1202J-1D01*
G01X452841Y1533899D01*
X452843Y1533902D01*
G37*
G36*
G01X457567D02*
G02X458627Y1534538I1060J-565D01*
G01X458629D01*
G02X459830Y1533336I-1J-1202D01*
G02X459669Y1532736I-1204J1D01*
G01X458124Y1530063D01*
X458122Y1530059D01*
G02X457052Y1529406I-1070J550D01*
G02X455850Y1530608I0J1202D01*
G01Y1530610D01*
G02X455999Y1531189I1202J-1D01*
G01X457565Y1533899D01*
X457567Y1533902D01*
G37*
G36*
G01X462291D02*
G02X463351Y1534538I1060J-565D01*
G01X463353D01*
G02X464554Y1533336I-1J-1202D01*
G02X464393Y1532736I-1204J1D01*
G01X462848Y1530063D01*
X462846Y1530059D01*
G02X461776Y1529406I-1070J550D01*
G02X460574Y1530608I0J1202D01*
G01Y1530610D01*
G02X460723Y1531189I1202J-1D01*
G01X462289Y1533899D01*
X462291Y1533902D01*
G37*
G36*
G01X467014Y1533899D02*
X467016Y1533902D01*
G02X468076Y1534538I1060J-565D01*
G02X469278Y1533336I0J-1202D01*
G01Y1533335D01*
G02X469118Y1532736I-1203J1D01*
G01X467573Y1530063D01*
X467571Y1530059D01*
G02X466501Y1529406I-1070J550D01*
G01X466499D01*
G02X465298Y1530608I1J1202D01*
G01Y1530610D01*
G02X465448Y1531189I1203J-3D01*
G01X467014Y1533899D01*
G37*
G36*
G01X471738D02*
X471740Y1533902D01*
G02X472800Y1534538I1060J-565D01*
G02X474002Y1533336I0J-1202D01*
G01Y1533335D01*
G02X473842Y1532736I-1203J1D01*
G01X472297Y1530063D01*
X472295Y1530059D01*
G02X471225Y1529406I-1070J550D01*
G01X471223D01*
G02X470022Y1530608I1J1202D01*
G01Y1530610D01*
G02X470172Y1531189I1203J-3D01*
G01X471738Y1533899D01*
G37*
G36*
G01X476465Y1533902D02*
G02X477525Y1534538I1060J-565D01*
G01X477527D01*
G02X478728Y1533336I-1J-1202D01*
G02X478567Y1532736I-1204J1D01*
G01X477022Y1530063D01*
X477020Y1530059D01*
G02X475950Y1529406I-1070J550D01*
G02X474748Y1530608I0J1202D01*
G01Y1530610D01*
G02X474897Y1531189I1202J-1D01*
G01X476463Y1533899D01*
X476465Y1533902D01*
G37*
G36*
G01X481189D02*
G02X482249Y1534538I1060J-565D01*
G01X482251D01*
G02X483452Y1533336I-1J-1202D01*
G02X483291Y1532736I-1204J1D01*
G01X481746Y1530063D01*
X481744Y1530059D01*
G02X480674Y1529406I-1070J550D01*
G02X479472Y1530608I0J1202D01*
G01Y1530610D01*
G02X479621Y1531189I1202J-1D01*
G01X481187Y1533899D01*
X481189Y1533902D01*
G37*
G36*
G01X485913D02*
G02X486973Y1534538I1060J-565D01*
G01X486975D01*
G02X488176Y1533336I-1J-1202D01*
G02X488015Y1532736I-1204J1D01*
G01X486470Y1530063D01*
X486468Y1530059D01*
G02X485398Y1529406I-1070J550D01*
G02X484196Y1530608I0J1202D01*
G01Y1530610D01*
G02X484345Y1531189I1202J-1D01*
G01X485911Y1533899D01*
X485913Y1533902D01*
G37*
G36*
G01X490636Y1533899D02*
X490638Y1533902D01*
G02X491698Y1534538I1060J-565D01*
G02X492900Y1533336I0J-1202D01*
G01Y1533335D01*
G02X492740Y1532736I-1203J1D01*
G01X491195Y1530063D01*
X491193Y1530059D01*
G02X490123Y1529406I-1070J550D01*
G01X490121D01*
G02X488920Y1530608I1J1202D01*
G01Y1530610D01*
G02X489070Y1531189I1203J-3D01*
G01X490636Y1533899D01*
G37*
G36*
G01X495360D02*
X495362Y1533902D01*
G02X496422Y1534538I1060J-565D01*
G02X497624Y1533336I0J-1202D01*
G01Y1533335D01*
G02X497464Y1532736I-1203J1D01*
G01X495919Y1530063D01*
X495917Y1530059D01*
G02X494847Y1529406I-1070J550D01*
G01X494845D01*
G02X493644Y1530608I1J1202D01*
G01Y1530610D01*
G02X493794Y1531189I1203J-3D01*
G01X495360Y1533899D01*
G37*
G36*
G01X500087Y1533902D02*
G02X501147Y1534538I1060J-565D01*
G01X501149D01*
G02X502350Y1533336I-1J-1202D01*
G02X502189Y1532736I-1204J1D01*
G01X500644Y1530063D01*
X500642Y1530059D01*
G02X499572Y1529406I-1070J550D01*
G02X498370Y1530608I0J1202D01*
G01Y1530610D01*
G02X498519Y1531189I1202J-1D01*
G01X500085Y1533899D01*
X500087Y1533902D01*
G37*
G36*
G01X504811D02*
G02X505871Y1534538I1060J-565D01*
G01X505873D01*
G02X507074Y1533336I-1J-1202D01*
G02X506913Y1532736I-1204J1D01*
G01X505368Y1530063D01*
X505366Y1530059D01*
G02X504296Y1529406I-1070J550D01*
G02X503094Y1530608I0J1202D01*
G01Y1530610D01*
G02X503243Y1531189I1202J-1D01*
G01X504809Y1533899D01*
X504811Y1533902D01*
G37*
G36*
G01X509535D02*
G02X510595Y1534538I1060J-565D01*
G01X510597D01*
G02X511798Y1533336I-1J-1202D01*
G02X511637Y1532736I-1204J1D01*
G01X510092Y1530063D01*
X510090Y1530059D01*
G02X509020Y1529406I-1070J550D01*
G02X507818Y1530608I0J1202D01*
G01Y1530610D01*
G02X507967Y1531189I1202J-1D01*
G01X509533Y1533899D01*
X509535Y1533902D01*
G37*
G36*
G01X514258Y1533899D02*
X514260Y1533902D01*
G02X515320Y1534538I1060J-565D01*
G02X516522Y1533336I0J-1202D01*
G01Y1533335D01*
G02X516362Y1532736I-1203J1D01*
G01X514817Y1530063D01*
X514815Y1530059D01*
G02X513745Y1529406I-1070J550D01*
G01X513743D01*
G02X512542Y1530608I1J1202D01*
G01Y1530610D01*
G02X512692Y1531189I1203J-3D01*
G01X514258Y1533899D01*
G37*
G36*
G01X518982D02*
X518984Y1533902D01*
G02X520044Y1534538I1060J-565D01*
G02X521246Y1533336I0J-1202D01*
G01Y1533335D01*
G02X521086Y1532736I-1203J1D01*
G01X519541Y1530063D01*
X519539Y1530059D01*
G02X518469Y1529406I-1070J550D01*
G01X518467D01*
G02X517266Y1530608I1J1202D01*
G01Y1530610D01*
G02X517416Y1531189I1203J-3D01*
G01X518982Y1533899D01*
G37*
G36*
G01X523709Y1533902D02*
G02X524769Y1534538I1060J-565D01*
G01X524771D01*
G02X525972Y1533336I-1J-1202D01*
G02X525811Y1532736I-1204J1D01*
G01X524266Y1530063D01*
X524264Y1530059D01*
G02X523194Y1529406I-1070J550D01*
G02X521992Y1530608I0J1202D01*
G01Y1530610D01*
G02X522141Y1531189I1202J-1D01*
G01X523707Y1533899D01*
X523709Y1533902D01*
G37*
G36*
G01X580905D02*
G02X581965Y1534538I1060J-565D01*
G01X581967D01*
G02X583168Y1533336I-1J-1202D01*
G02X583007Y1532736I-1204J1D01*
G01X581462Y1530063D01*
X581460Y1530059D01*
G02X580390Y1529406I-1070J550D01*
G02X579188Y1530608I0J1202D01*
G01Y1530610D01*
G02X579337Y1531189I1202J-1D01*
G01X580903Y1533899D01*
X580905Y1533902D01*
G37*
G36*
G01X585629D02*
G02X586689Y1534538I1060J-565D01*
G01X586691D01*
G02X587892Y1533336I-1J-1202D01*
G02X587731Y1532736I-1204J1D01*
G01X586186Y1530063D01*
X586184Y1530059D01*
G02X585114Y1529406I-1070J550D01*
G02X583912Y1530608I0J1202D01*
G01Y1530610D01*
G02X584061Y1531189I1202J-1D01*
G01X585627Y1533899D01*
X585629Y1533902D01*
G37*
G36*
G01X590353D02*
G02X591413Y1534538I1060J-565D01*
G01X591415D01*
G02X592616Y1533336I-1J-1202D01*
G02X592455Y1532736I-1204J1D01*
G01X590910Y1530063D01*
X590908Y1530059D01*
G02X589838Y1529406I-1070J550D01*
G02X588636Y1530608I0J1202D01*
G01Y1530610D01*
G02X588785Y1531189I1202J-1D01*
G01X590351Y1533899D01*
X590353Y1533902D01*
G37*
G36*
G01X595076Y1533899D02*
X595078Y1533902D01*
G02X596138Y1534538I1060J-565D01*
G02X597340Y1533336I0J-1202D01*
G01Y1533335D01*
G02X597180Y1532736I-1203J1D01*
G01X595635Y1530063D01*
X595633Y1530059D01*
G02X594563Y1529406I-1070J550D01*
G01X594561D01*
G02X593360Y1530608I1J1202D01*
G01Y1530610D01*
G02X593510Y1531189I1203J-3D01*
G01X595076Y1533899D01*
G37*
G36*
G01X599800D02*
X599802Y1533902D01*
G02X600862Y1534538I1060J-565D01*
G02X602064Y1533336I0J-1202D01*
G01Y1533335D01*
G02X601904Y1532736I-1203J1D01*
G01X600359Y1530063D01*
X600357Y1530059D01*
G02X599287Y1529406I-1070J550D01*
G01X599285D01*
G02X598084Y1530608I1J1202D01*
G01Y1530610D01*
G02X598234Y1531189I1203J-3D01*
G01X599800Y1533899D01*
G37*
G36*
G01X604527Y1533902D02*
G02X605587Y1534538I1060J-565D01*
G01X605589D01*
G02X606790Y1533336I-1J-1202D01*
G02X606629Y1532736I-1204J1D01*
G01X605084Y1530063D01*
X605082Y1530059D01*
G02X604012Y1529406I-1070J550D01*
G02X602810Y1530608I0J1202D01*
G01Y1530610D01*
G02X602959Y1531189I1202J-1D01*
G01X604525Y1533899D01*
X604527Y1533902D01*
G37*
G36*
G01X609251D02*
G02X610311Y1534538I1060J-565D01*
G01X610313D01*
G02X611514Y1533336I-1J-1202D01*
G02X611353Y1532736I-1204J1D01*
G01X609808Y1530063D01*
X609806Y1530059D01*
G02X608736Y1529406I-1070J550D01*
G02X607534Y1530608I0J1202D01*
G01Y1530610D01*
G02X607683Y1531189I1202J-1D01*
G01X609249Y1533899D01*
X609251Y1533902D01*
G37*
G36*
G01X613975D02*
G02X615035Y1534538I1060J-565D01*
G01X615037D01*
G02X616238Y1533336I-1J-1202D01*
G02X616077Y1532736I-1204J1D01*
G01X614532Y1530063D01*
X614530Y1530059D01*
G02X613460Y1529406I-1070J550D01*
G02X612258Y1530608I0J1202D01*
G01Y1530610D01*
G02X612407Y1531189I1202J-1D01*
G01X613973Y1533899D01*
X613975Y1533902D01*
G37*
G36*
G01X618698Y1533899D02*
X618700Y1533902D01*
G02X619760Y1534538I1060J-565D01*
G02X620962Y1533336I0J-1202D01*
G01Y1533335D01*
G02X620802Y1532736I-1203J1D01*
G01X619257Y1530063D01*
X619255Y1530059D01*
G02X618185Y1529406I-1070J550D01*
G01X618183D01*
G02X616982Y1530608I1J1202D01*
G01Y1530610D01*
G02X617132Y1531189I1203J-3D01*
G01X618698Y1533899D01*
G37*
G36*
G01X623422D02*
X623424Y1533902D01*
G02X624484Y1534538I1060J-565D01*
G02X625686Y1533336I0J-1202D01*
G01Y1533335D01*
G02X625526Y1532736I-1203J1D01*
G01X623981Y1530063D01*
X623979Y1530059D01*
G02X622909Y1529406I-1070J550D01*
G01X622907D01*
G02X621706Y1530608I1J1202D01*
G01Y1530610D01*
G02X621856Y1531189I1203J-3D01*
G01X623422Y1533899D01*
G37*
G36*
G01X628149Y1533902D02*
G02X629209Y1534538I1060J-565D01*
G01X629211D01*
G02X630412Y1533336I-1J-1202D01*
G02X630251Y1532736I-1204J1D01*
G01X628706Y1530063D01*
X628704Y1530059D01*
G02X627634Y1529406I-1070J550D01*
G02X626432Y1530608I0J1202D01*
G01Y1530610D01*
G02X626581Y1531189I1202J-1D01*
G01X628147Y1533899D01*
X628149Y1533902D01*
G37*
G36*
G01X632873D02*
G02X633933Y1534538I1060J-565D01*
G01X633935D01*
G02X635136Y1533336I-1J-1202D01*
G02X634975Y1532736I-1204J1D01*
G01X633430Y1530063D01*
X633428Y1530059D01*
G02X632358Y1529406I-1070J550D01*
G02X631156Y1530608I0J1202D01*
G01Y1530610D01*
G02X631305Y1531189I1202J-1D01*
G01X632871Y1533899D01*
X632873Y1533902D01*
G37*
G36*
G01X637597D02*
G02X638657Y1534538I1060J-565D01*
G01X638659D01*
G02X639860Y1533336I-1J-1202D01*
G02X639699Y1532736I-1204J1D01*
G01X638154Y1530063D01*
X638152Y1530059D01*
G02X637082Y1529406I-1070J550D01*
G02X635880Y1530608I0J1202D01*
G01Y1530610D01*
G02X636029Y1531189I1202J-1D01*
G01X637595Y1533899D01*
X637597Y1533902D01*
G37*
G36*
G01X642320Y1533899D02*
X642322Y1533902D01*
G02X643382Y1534538I1060J-565D01*
G02X644584Y1533336I0J-1202D01*
G01Y1533335D01*
G02X644424Y1532736I-1203J1D01*
G01X642879Y1530063D01*
X642877Y1530059D01*
G02X641807Y1529406I-1070J550D01*
G01X641805D01*
G02X640604Y1530608I1J1202D01*
G01Y1530610D01*
G02X640754Y1531189I1203J-3D01*
G01X642320Y1533899D01*
G37*
G36*
G01X647044D02*
X647046Y1533902D01*
G02X648106Y1534538I1060J-565D01*
G02X649308Y1533336I0J-1202D01*
G01Y1533335D01*
G02X649148Y1532736I-1203J1D01*
G01X647603Y1530063D01*
X647601Y1530059D01*
G02X646531Y1529406I-1070J550D01*
G01X646529D01*
G02X645328Y1530608I1J1202D01*
G01Y1530610D01*
G02X645478Y1531189I1203J-3D01*
G01X647044Y1533899D01*
G37*
G36*
G01X651771Y1533902D02*
G02X652831Y1534538I1060J-565D01*
G01X652833D01*
G02X654034Y1533336I-1J-1202D01*
G02X653873Y1532736I-1204J1D01*
G01X652328Y1530063D01*
X652326Y1530059D01*
G02X651256Y1529406I-1070J550D01*
G02X650054Y1530608I0J1202D01*
G01Y1530610D01*
G02X650203Y1531189I1202J-1D01*
G01X651769Y1533899D01*
X651771Y1533902D01*
G37*
G36*
G01X1196543Y1553264D02*
G02X1197603Y1553900I1060J-565D01*
G01X1197605D01*
G02X1198806Y1552698I-1J-1202D01*
G02X1198645Y1552098I-1204J1D01*
G01X1197100Y1549425D01*
X1197098Y1549421D01*
G02X1196028Y1548768I-1070J550D01*
G02X1194826Y1549970I0J1202D01*
G01Y1549972D01*
G02X1194975Y1550551I1202J-1D01*
G01X1196541Y1553261D01*
X1196543Y1553264D01*
G37*
G36*
G01X1201267D02*
G02X1202327Y1553900I1060J-565D01*
G01X1202329D01*
G02X1203530Y1552698I-1J-1202D01*
G02X1203369Y1552098I-1204J1D01*
G01X1201824Y1549425D01*
X1201822Y1549421D01*
G02X1200752Y1548768I-1070J550D01*
G02X1199550Y1549970I0J1202D01*
G01Y1549972D01*
G02X1199699Y1550551I1202J-1D01*
G01X1201265Y1553261D01*
X1201267Y1553264D01*
G37*
G36*
G01X1205991D02*
G02X1207051Y1553900I1060J-565D01*
G01X1207052D01*
G02X1208254Y1552698I0J-1202D01*
G01Y1552697D01*
G02X1208094Y1552098I-1203J1D01*
G01X1206549Y1549425D01*
X1206547Y1549421D01*
G02X1205477Y1548768I-1070J550D01*
G01X1205476D01*
G02X1204274Y1549970I0J1202D01*
G01Y1549972D01*
G02X1204423Y1550551I1202J-1D01*
G01X1205989Y1553261D01*
X1205991Y1553264D01*
G37*
G36*
G01X1210714Y1553261D02*
X1210716Y1553264D01*
G02X1211776Y1553900I1060J-565D01*
G02X1212978Y1552698I0J-1202D01*
G01Y1552697D01*
G02X1212818Y1552098I-1203J1D01*
G01X1211273Y1549425D01*
X1211271Y1549421D01*
G02X1210201Y1548768I-1070J550D01*
G01X1210199D01*
G02X1208998Y1549970I1J1202D01*
G01Y1549972D01*
G02X1209148Y1550551I1203J-3D01*
G01X1210714Y1553261D01*
G37*
G36*
G01X1215438D02*
X1215440Y1553264D01*
G02X1216500Y1553900I1060J-565D01*
G02X1217702Y1552698I0J-1202D01*
G01Y1552697D01*
G02X1217542Y1552098I-1203J1D01*
G01X1215997Y1549425D01*
X1215995Y1549421D01*
G02X1214925Y1548768I-1070J550D01*
G01X1214923D01*
G02X1213722Y1549970I1J1202D01*
G01Y1549972D01*
G02X1213872Y1550551I1203J-3D01*
G01X1215438Y1553261D01*
G37*
G36*
G01X1220165Y1553264D02*
G02X1221225Y1553900I1060J-565D01*
G01X1221227D01*
G02X1222428Y1552698I-1J-1202D01*
G02X1222267Y1552098I-1204J1D01*
G01X1220722Y1549425D01*
X1220720Y1549421D01*
G02X1219650Y1548768I-1070J550D01*
G02X1218448Y1549970I0J1202D01*
G01Y1549972D01*
G02X1218597Y1550551I1202J-1D01*
G01X1220163Y1553261D01*
X1220165Y1553264D01*
G37*
G36*
G01X1224889D02*
G02X1225949Y1553900I1060J-565D01*
G01X1225951D01*
G02X1227152Y1552698I-1J-1202D01*
G02X1226991Y1552098I-1204J1D01*
G01X1225446Y1549425D01*
X1225444Y1549421D01*
G02X1224374Y1548768I-1070J550D01*
G02X1223172Y1549970I0J1202D01*
G01Y1549972D01*
G02X1223321Y1550551I1202J-1D01*
G01X1224887Y1553261D01*
X1224889Y1553264D01*
G37*
G36*
G01X1229613D02*
G02X1230673Y1553900I1060J-565D01*
G01X1230674D01*
G02X1231876Y1552698I0J-1202D01*
G01Y1552697D01*
G02X1231716Y1552098I-1203J1D01*
G01X1230171Y1549425D01*
X1230169Y1549421D01*
G02X1229099Y1548768I-1070J550D01*
G01X1229098D01*
G02X1227896Y1549970I0J1202D01*
G01Y1549972D01*
G02X1228045Y1550551I1202J-1D01*
G01X1229611Y1553261D01*
X1229613Y1553264D01*
G37*
G36*
G01X1243787D02*
G02X1244847Y1553900I1060J-565D01*
G01X1244849D01*
G02X1246050Y1552698I-1J-1202D01*
G02X1245889Y1552098I-1204J1D01*
G01X1244344Y1549425D01*
X1244342Y1549421D01*
G02X1243272Y1548768I-1070J550D01*
G02X1242070Y1549970I0J1202D01*
G01Y1549972D01*
G02X1242219Y1550551I1202J-1D01*
G01X1243785Y1553261D01*
X1243787Y1553264D01*
G37*
G36*
G01X1248511D02*
G02X1249571Y1553900I1060J-565D01*
G01X1249572D01*
G02X1250774Y1552698I0J-1202D01*
G01Y1552697D01*
G02X1250614Y1552098I-1203J1D01*
G01X1249069Y1549425D01*
X1249067Y1549421D01*
G02X1247997Y1548768I-1070J550D01*
G01X1247996D01*
G02X1246794Y1549970I0J1202D01*
G01Y1549972D01*
G02X1246943Y1550551I1202J-1D01*
G01X1248509Y1553261D01*
X1248511Y1553264D01*
G37*
G36*
G01X1253234Y1553261D02*
X1253236Y1553264D01*
G02X1254296Y1553900I1060J-565D01*
G02X1255498Y1552698I0J-1202D01*
G01Y1552697D01*
G02X1255338Y1552098I-1203J1D01*
G01X1253793Y1549425D01*
X1253791Y1549421D01*
G02X1252721Y1548768I-1070J550D01*
G01X1252719D01*
G02X1251518Y1549970I1J1202D01*
G01Y1549972D01*
G02X1251668Y1550551I1203J-3D01*
G01X1253234Y1553261D01*
G37*
G36*
G01X1262685Y1553264D02*
G02X1263745Y1553900I1060J-565D01*
G01X1263747D01*
G02X1264948Y1552698I-1J-1202D01*
G02X1264787Y1552098I-1204J1D01*
G01X1263242Y1549425D01*
X1263240Y1549421D01*
G02X1262170Y1548768I-1070J550D01*
G02X1260968Y1549970I0J1202D01*
G01Y1549972D01*
G02X1261117Y1550551I1202J-1D01*
G01X1262683Y1553261D01*
X1262685Y1553264D01*
G37*
G36*
G01X1267409D02*
G02X1268469Y1553900I1060J-565D01*
G01X1268471D01*
G02X1269672Y1552698I-1J-1202D01*
G02X1269511Y1552098I-1204J1D01*
G01X1267966Y1549425D01*
X1267964Y1549421D01*
G02X1266894Y1548768I-1070J550D01*
G02X1265692Y1549970I0J1202D01*
G01Y1549972D01*
G02X1265841Y1550551I1202J-1D01*
G01X1267407Y1553261D01*
X1267409Y1553264D01*
G37*
G36*
G01X1324605D02*
G02X1325665Y1553900I1060J-565D01*
G01X1325667D01*
G02X1326868Y1552698I-1J-1202D01*
G02X1326707Y1552098I-1204J1D01*
G01X1325162Y1549425D01*
X1325160Y1549421D01*
G02X1324090Y1548768I-1070J550D01*
G02X1322888Y1549970I0J1202D01*
G01Y1549972D01*
G02X1323037Y1550551I1202J-1D01*
G01X1324603Y1553261D01*
X1324605Y1553264D01*
G37*
G36*
G01X1329329D02*
G02X1330389Y1553900I1060J-565D01*
G01X1330391D01*
G02X1331592Y1552698I-1J-1202D01*
G02X1331431Y1552098I-1204J1D01*
G01X1329886Y1549425D01*
X1329884Y1549421D01*
G02X1328814Y1548768I-1070J550D01*
G02X1327612Y1549970I0J1202D01*
G01Y1549972D01*
G02X1327761Y1550551I1202J-1D01*
G01X1329327Y1553261D01*
X1329329Y1553264D01*
G37*
G36*
G01X1334052Y1553261D02*
X1334054Y1553264D01*
G02X1335114Y1553900I1060J-565D01*
G02X1336316Y1552698I0J-1202D01*
G01Y1552697D01*
G02X1336156Y1552098I-1203J1D01*
G01X1334611Y1549425D01*
X1334609Y1549421D01*
G02X1333539Y1548768I-1070J550D01*
G01X1333537D01*
G02X1332336Y1549970I1J1202D01*
G01Y1549972D01*
G02X1332486Y1550551I1203J-3D01*
G01X1334052Y1553261D01*
G37*
G36*
G01X1338776D02*
X1338778Y1553264D01*
G02X1339838Y1553900I1060J-565D01*
G02X1341040Y1552698I0J-1202D01*
G01Y1552697D01*
G02X1340880Y1552098I-1203J1D01*
G01X1339335Y1549425D01*
X1339333Y1549421D01*
G02X1338263Y1548768I-1070J550D01*
G01X1338261D01*
G02X1337060Y1549970I1J1202D01*
G01Y1549972D01*
G02X1337210Y1550551I1203J-3D01*
G01X1338776Y1553261D01*
G37*
G36*
G01X1343500D02*
X1343502Y1553264D01*
G02X1344562Y1553900I1060J-565D01*
G02X1345764Y1552698I0J-1202D01*
G01Y1552697D01*
G02X1345604Y1552098I-1203J1D01*
G01X1344059Y1549425D01*
X1344057Y1549421D01*
G02X1342987Y1548768I-1070J550D01*
G01X1342985D01*
G02X1341784Y1549970I1J1202D01*
G01Y1549972D01*
G02X1341934Y1550551I1203J-3D01*
G01X1343500Y1553261D01*
G37*
G36*
G01X1348227Y1553264D02*
G02X1349287Y1553900I1060J-565D01*
G01X1349289D01*
G02X1350490Y1552698I-1J-1202D01*
G02X1350329Y1552098I-1204J1D01*
G01X1348784Y1549425D01*
X1348782Y1549421D01*
G02X1347712Y1548768I-1070J550D01*
G02X1346510Y1549970I0J1202D01*
G01Y1549972D01*
G02X1346659Y1550551I1202J-1D01*
G01X1348225Y1553261D01*
X1348227Y1553264D01*
G37*
G36*
G01X1352951D02*
G02X1354011Y1553900I1060J-565D01*
G01X1354013D01*
G02X1355214Y1552698I-1J-1202D01*
G02X1355053Y1552098I-1204J1D01*
G01X1353508Y1549425D01*
X1353506Y1549421D01*
G02X1352436Y1548768I-1070J550D01*
G02X1351234Y1549970I0J1202D01*
G01Y1549972D01*
G02X1351383Y1550551I1202J-1D01*
G01X1352949Y1553261D01*
X1352951Y1553264D01*
G37*
G36*
G01X1357674Y1553261D02*
X1357676Y1553264D01*
G02X1358736Y1553900I1060J-565D01*
G02X1359938Y1552698I0J-1202D01*
G01Y1552697D01*
G02X1359778Y1552098I-1203J1D01*
G01X1358233Y1549425D01*
X1358231Y1549421D01*
G02X1357161Y1548768I-1070J550D01*
G01X1357159D01*
G02X1355958Y1549970I1J1202D01*
G01Y1549972D01*
G02X1356108Y1550551I1203J-3D01*
G01X1357674Y1553261D01*
G37*
G36*
G01X1362398D02*
X1362400Y1553264D01*
G02X1363460Y1553900I1060J-565D01*
G02X1364662Y1552698I0J-1202D01*
G01Y1552697D01*
G02X1364502Y1552098I-1203J1D01*
G01X1362957Y1549425D01*
X1362955Y1549421D01*
G02X1361885Y1548768I-1070J550D01*
G01X1361883D01*
G02X1360682Y1549970I1J1202D01*
G01Y1549972D01*
G02X1360832Y1550551I1203J-3D01*
G01X1362398Y1553261D01*
G37*
G36*
G01X1367122D02*
X1367124Y1553264D01*
G02X1368184Y1553900I1060J-565D01*
G02X1369386Y1552698I0J-1202D01*
G01Y1552697D01*
G02X1369226Y1552098I-1203J1D01*
G01X1367681Y1549425D01*
X1367679Y1549421D01*
G02X1366609Y1548768I-1070J550D01*
G01X1366607D01*
G02X1365406Y1549970I1J1202D01*
G01Y1549972D01*
G02X1365556Y1550551I1203J-3D01*
G01X1367122Y1553261D01*
G37*
G36*
G01X1371849Y1553264D02*
G02X1372909Y1553900I1060J-565D01*
G01X1372911D01*
G02X1374112Y1552698I-1J-1202D01*
G02X1373951Y1552098I-1204J1D01*
G01X1372406Y1549425D01*
X1372404Y1549421D01*
G02X1371334Y1548768I-1070J550D01*
G02X1370132Y1549970I0J1202D01*
G01Y1549972D01*
G02X1370281Y1550551I1202J-1D01*
G01X1371847Y1553261D01*
X1371849Y1553264D01*
G37*
G36*
G01X1376573D02*
G02X1377633Y1553900I1060J-565D01*
G01X1377635D01*
G02X1378836Y1552698I-1J-1202D01*
G02X1378675Y1552098I-1204J1D01*
G01X1377130Y1549425D01*
X1377128Y1549421D01*
G02X1376058Y1548768I-1070J550D01*
G02X1374856Y1549970I0J1202D01*
G01Y1549972D01*
G02X1375005Y1550551I1202J-1D01*
G01X1376571Y1553261D01*
X1376573Y1553264D01*
G37*
G36*
G01X1381296Y1553261D02*
X1381298Y1553264D01*
G02X1382358Y1553900I1060J-565D01*
G02X1383560Y1552698I0J-1202D01*
G01Y1552697D01*
G02X1383400Y1552098I-1203J1D01*
G01X1381855Y1549425D01*
X1381853Y1549421D01*
G02X1380783Y1548768I-1070J550D01*
G01X1380781D01*
G02X1379580Y1549970I1J1202D01*
G01Y1549972D01*
G02X1379730Y1550551I1203J-3D01*
G01X1381296Y1553261D01*
G37*
G36*
G01X1386020D02*
X1386022Y1553264D01*
G02X1387082Y1553900I1060J-565D01*
G02X1388284Y1552698I0J-1202D01*
G01Y1552697D01*
G02X1388124Y1552098I-1203J1D01*
G01X1386579Y1549425D01*
X1386577Y1549421D01*
G02X1385507Y1548768I-1070J550D01*
G01X1385505D01*
G02X1384304Y1549970I1J1202D01*
G01Y1549972D01*
G02X1384454Y1550551I1203J-3D01*
G01X1386020Y1553261D01*
G37*
G36*
G01X1390747Y1553264D02*
G02X1391807Y1553900I1060J-565D01*
G01X1391809D01*
G02X1393010Y1552698I-1J-1202D01*
G02X1392849Y1552098I-1204J1D01*
G01X1391304Y1549425D01*
X1391302Y1549421D01*
G02X1390232Y1548768I-1070J550D01*
G02X1389030Y1549970I0J1202D01*
G01Y1549972D01*
G02X1389179Y1550551I1202J-1D01*
G01X1390745Y1553261D01*
X1390747Y1553264D01*
G37*
G36*
G01X1395471D02*
G02X1396531Y1553900I1060J-565D01*
G01X1396533D01*
G02X1397734Y1552698I-1J-1202D01*
G02X1397573Y1552098I-1204J1D01*
G01X1396028Y1549425D01*
X1396026Y1549421D01*
G02X1394956Y1548768I-1070J550D01*
G02X1393754Y1549970I0J1202D01*
G01Y1549972D01*
G02X1393903Y1550551I1202J-1D01*
G01X1395469Y1553261D01*
X1395471Y1553264D01*
G37*
G36*
G01X1460717D02*
G02X1461777Y1553900I1060J-565D01*
G01X1461779D01*
G02X1462980Y1552698I-1J-1202D01*
G02X1462819Y1552098I-1204J1D01*
G01X1461274Y1549425D01*
X1461272Y1549421D01*
G02X1460202Y1548768I-1070J550D01*
G02X1459000Y1549970I0J1202D01*
G01Y1549972D01*
G02X1459149Y1550551I1202J-1D01*
G01X1460715Y1553261D01*
X1460717Y1553264D01*
G37*
G36*
G01X1465441D02*
G02X1466501Y1553900I1060J-565D01*
G01X1466503D01*
G02X1467704Y1552698I-1J-1202D01*
G02X1467543Y1552098I-1204J1D01*
G01X1465998Y1549425D01*
X1465996Y1549421D01*
G02X1464926Y1548768I-1070J550D01*
G02X1463724Y1549970I0J1202D01*
G01Y1549972D01*
G02X1463873Y1550551I1202J-1D01*
G01X1465439Y1553261D01*
X1465441Y1553264D01*
G37*
G36*
G01X1470165D02*
G02X1471225Y1553900I1060J-565D01*
G01X1471227D01*
G02X1472428Y1552698I-1J-1202D01*
G02X1472267Y1552098I-1204J1D01*
G01X1470722Y1549425D01*
X1470720Y1549421D01*
G02X1469650Y1548768I-1070J550D01*
G02X1468448Y1549970I0J1202D01*
G01Y1549972D01*
G02X1468597Y1550551I1202J-1D01*
G01X1470163Y1553261D01*
X1470165Y1553264D01*
G37*
G36*
G01X1474888Y1553261D02*
X1474890Y1553264D01*
G02X1475950Y1553900I1060J-565D01*
G02X1477152Y1552698I0J-1202D01*
G01Y1552697D01*
G02X1476992Y1552098I-1203J1D01*
G01X1475447Y1549425D01*
X1475445Y1549421D01*
G02X1474375Y1548768I-1070J550D01*
G01X1474373D01*
G02X1473172Y1549970I1J1202D01*
G01Y1549972D01*
G02X1473322Y1550551I1203J-3D01*
G01X1474888Y1553261D01*
G37*
G36*
G01X1479612D02*
X1479614Y1553264D01*
G02X1480674Y1553900I1060J-565D01*
G02X1481876Y1552698I0J-1202D01*
G01Y1552697D01*
G02X1481716Y1552098I-1203J1D01*
G01X1480171Y1549425D01*
X1480169Y1549421D01*
G02X1479099Y1548768I-1070J550D01*
G01X1479097D01*
G02X1477896Y1549970I1J1202D01*
G01Y1549972D01*
G02X1478046Y1550551I1203J-3D01*
G01X1479612Y1553261D01*
G37*
G36*
G01X1484339Y1553264D02*
G02X1485399Y1553900I1060J-565D01*
G01X1485401D01*
G02X1486602Y1552698I-1J-1202D01*
G02X1486441Y1552098I-1204J1D01*
G01X1484896Y1549425D01*
X1484894Y1549421D01*
G02X1483824Y1548768I-1070J550D01*
G02X1482622Y1549970I0J1202D01*
G01Y1549972D01*
G02X1482771Y1550551I1202J-1D01*
G01X1484337Y1553261D01*
X1484339Y1553264D01*
G37*
G36*
G01X1489063D02*
G02X1490123Y1553900I1060J-565D01*
G01X1490125D01*
G02X1491326Y1552698I-1J-1202D01*
G02X1491165Y1552098I-1204J1D01*
G01X1489620Y1549425D01*
X1489618Y1549421D01*
G02X1488548Y1548768I-1070J550D01*
G02X1487346Y1549970I0J1202D01*
G01Y1549972D01*
G02X1487495Y1550551I1202J-1D01*
G01X1489061Y1553261D01*
X1489063Y1553264D01*
G37*
G36*
G01X1493787D02*
G02X1494847Y1553900I1060J-565D01*
G01X1494849D01*
G02X1496050Y1552698I-1J-1202D01*
G02X1495889Y1552098I-1204J1D01*
G01X1494344Y1549425D01*
X1494342Y1549421D01*
G02X1493272Y1548768I-1070J550D01*
G02X1492070Y1549970I0J1202D01*
G01Y1549972D01*
G02X1492219Y1550551I1202J-1D01*
G01X1493785Y1553261D01*
X1493787Y1553264D01*
G37*
G36*
G01X1498510Y1553261D02*
X1498512Y1553264D01*
G02X1499572Y1553900I1060J-565D01*
G02X1500774Y1552698I0J-1202D01*
G01Y1552697D01*
G02X1500614Y1552098I-1203J1D01*
G01X1499069Y1549425D01*
X1499067Y1549421D01*
G02X1497997Y1548768I-1070J550D01*
G01X1497995D01*
G02X1496794Y1549970I1J1202D01*
G01Y1549972D01*
G02X1496944Y1550551I1203J-3D01*
G01X1498510Y1553261D01*
G37*
G36*
G01X1503234D02*
X1503236Y1553264D01*
G02X1504296Y1553900I1060J-565D01*
G02X1505498Y1552698I0J-1202D01*
G01Y1552697D01*
G02X1505338Y1552098I-1203J1D01*
G01X1503793Y1549425D01*
X1503791Y1549421D01*
G02X1502721Y1548768I-1070J550D01*
G01X1502719D01*
G02X1501518Y1549970I1J1202D01*
G01Y1549972D01*
G02X1501668Y1550551I1203J-3D01*
G01X1503234Y1553261D01*
G37*
G36*
G01X1507961Y1553264D02*
G02X1509021Y1553900I1060J-565D01*
G01X1509023D01*
G02X1510224Y1552698I-1J-1202D01*
G02X1510063Y1552098I-1204J1D01*
G01X1508518Y1549425D01*
X1508516Y1549421D01*
G02X1507446Y1548768I-1070J550D01*
G02X1506244Y1549970I0J1202D01*
G01Y1549972D01*
G02X1506393Y1550551I1202J-1D01*
G01X1507959Y1553261D01*
X1507961Y1553264D01*
G37*
G36*
G01X1512685D02*
G02X1513745Y1553900I1060J-565D01*
G01X1513747D01*
G02X1514948Y1552698I-1J-1202D01*
G02X1514787Y1552098I-1204J1D01*
G01X1513242Y1549425D01*
X1513240Y1549421D01*
G02X1512170Y1548768I-1070J550D01*
G02X1510968Y1549970I0J1202D01*
G01Y1549972D01*
G02X1511117Y1550551I1202J-1D01*
G01X1512683Y1553261D01*
X1512685Y1553264D01*
G37*
G36*
G01X1517409D02*
G02X1518469Y1553900I1060J-565D01*
G01X1518471D01*
G02X1519672Y1552698I-1J-1202D01*
G02X1519511Y1552098I-1204J1D01*
G01X1517966Y1549425D01*
X1517964Y1549421D01*
G02X1516894Y1548768I-1070J550D01*
G02X1515692Y1549970I0J1202D01*
G01Y1549972D01*
G02X1515841Y1550551I1202J-1D01*
G01X1517407Y1553261D01*
X1517409Y1553264D01*
G37*
G36*
G01X1522132Y1553261D02*
X1522134Y1553264D01*
G02X1523194Y1553900I1060J-565D01*
G02X1524396Y1552698I0J-1202D01*
G01Y1552697D01*
G02X1524236Y1552098I-1203J1D01*
G01X1522691Y1549425D01*
X1522689Y1549421D01*
G02X1521619Y1548768I-1070J550D01*
G01X1521617D01*
G02X1520416Y1549970I1J1202D01*
G01Y1549972D01*
G02X1520566Y1550551I1203J-3D01*
G01X1522132Y1553261D01*
G37*
G36*
G01X1526856D02*
X1526858Y1553264D01*
G02X1527918Y1553900I1060J-565D01*
G02X1529120Y1552698I0J-1202D01*
G01Y1552697D01*
G02X1528960Y1552098I-1203J1D01*
G01X1527415Y1549425D01*
X1527413Y1549421D01*
G02X1526343Y1548768I-1070J550D01*
G01X1526341D01*
G02X1525140Y1549970I1J1202D01*
G01Y1549972D01*
G02X1525290Y1550551I1203J-3D01*
G01X1526856Y1553261D01*
G37*
G36*
G01X1531583Y1553264D02*
G02X1532643Y1553900I1060J-565D01*
G01X1532645D01*
G02X1533846Y1552698I-1J-1202D01*
G02X1533685Y1552098I-1204J1D01*
G01X1532140Y1549425D01*
X1532138Y1549421D01*
G02X1531068Y1548768I-1070J550D01*
G02X1529866Y1549970I0J1202D01*
G01Y1549972D01*
G02X1530015Y1550551I1202J-1D01*
G01X1531581Y1553261D01*
X1531583Y1553264D01*
G37*
G36*
G01X1588779D02*
G02X1589839Y1553900I1060J-565D01*
G01X1589841D01*
G02X1591042Y1552698I-1J-1202D01*
G02X1590881Y1552098I-1204J1D01*
G01X1589336Y1549425D01*
X1589334Y1549421D01*
G02X1588264Y1548768I-1070J550D01*
G02X1587062Y1549970I0J1202D01*
G01Y1549972D01*
G02X1587211Y1550551I1202J-1D01*
G01X1588777Y1553261D01*
X1588779Y1553264D01*
G37*
G36*
G01X1593503D02*
G02X1594563Y1553900I1060J-565D01*
G01X1594565D01*
G02X1595766Y1552698I-1J-1202D01*
G02X1595605Y1552098I-1204J1D01*
G01X1594060Y1549425D01*
X1594058Y1549421D01*
G02X1592988Y1548768I-1070J550D01*
G02X1591786Y1549970I0J1202D01*
G01Y1549972D01*
G02X1591935Y1550551I1202J-1D01*
G01X1593501Y1553261D01*
X1593503Y1553264D01*
G37*
G36*
G01X1598227D02*
G02X1599287Y1553900I1060J-565D01*
G01X1599289D01*
G02X1600490Y1552698I-1J-1202D01*
G02X1600329Y1552098I-1204J1D01*
G01X1598784Y1549425D01*
X1598782Y1549421D01*
G02X1597712Y1548768I-1070J550D01*
G02X1596510Y1549970I0J1202D01*
G01Y1549972D01*
G02X1596659Y1550551I1202J-1D01*
G01X1598225Y1553261D01*
X1598227Y1553264D01*
G37*
G36*
G01X1602950Y1553261D02*
X1602952Y1553264D01*
G02X1604012Y1553900I1060J-565D01*
G02X1605214Y1552698I0J-1202D01*
G01Y1552697D01*
G02X1605054Y1552098I-1203J1D01*
G01X1603509Y1549425D01*
X1603507Y1549421D01*
G02X1602437Y1548768I-1070J550D01*
G01X1602435D01*
G02X1601234Y1549970I1J1202D01*
G01Y1549972D01*
G02X1601384Y1550551I1203J-3D01*
G01X1602950Y1553261D01*
G37*
G36*
G01X1607674D02*
X1607676Y1553264D01*
G02X1608736Y1553900I1060J-565D01*
G02X1609938Y1552698I0J-1202D01*
G01Y1552697D01*
G02X1609778Y1552098I-1203J1D01*
G01X1608233Y1549425D01*
X1608231Y1549421D01*
G02X1607161Y1548768I-1070J550D01*
G01X1607159D01*
G02X1605958Y1549970I1J1202D01*
G01Y1549972D01*
G02X1606108Y1550551I1203J-3D01*
G01X1607674Y1553261D01*
G37*
G36*
G01X1612401Y1553264D02*
G02X1613461Y1553900I1060J-565D01*
G01X1613463D01*
G02X1614664Y1552698I-1J-1202D01*
G02X1614503Y1552098I-1204J1D01*
G01X1612958Y1549425D01*
X1612956Y1549421D01*
G02X1611886Y1548768I-1070J550D01*
G02X1610684Y1549970I0J1202D01*
G01Y1549972D01*
G02X1610833Y1550551I1202J-1D01*
G01X1612399Y1553261D01*
X1612401Y1553264D01*
G37*
G36*
G01X1617125D02*
G02X1618185Y1553900I1060J-565D01*
G01X1618187D01*
G02X1619388Y1552698I-1J-1202D01*
G02X1619227Y1552098I-1204J1D01*
G01X1617682Y1549425D01*
X1617680Y1549421D01*
G02X1616610Y1548768I-1070J550D01*
G02X1615408Y1549970I0J1202D01*
G01Y1549972D01*
G02X1615557Y1550551I1202J-1D01*
G01X1617123Y1553261D01*
X1617125Y1553264D01*
G37*
G36*
G01X1621849D02*
G02X1622909Y1553900I1060J-565D01*
G01X1622911D01*
G02X1624112Y1552698I-1J-1202D01*
G02X1623951Y1552098I-1204J1D01*
G01X1622406Y1549425D01*
X1622404Y1549421D01*
G02X1621334Y1548768I-1070J550D01*
G02X1620132Y1549970I0J1202D01*
G01Y1549972D01*
G02X1620281Y1550551I1202J-1D01*
G01X1621847Y1553261D01*
X1621849Y1553264D01*
G37*
G36*
G01X1626572Y1553261D02*
X1626574Y1553264D01*
G02X1627634Y1553900I1060J-565D01*
G02X1628836Y1552698I0J-1202D01*
G01Y1552697D01*
G02X1628676Y1552098I-1203J1D01*
G01X1627131Y1549425D01*
X1627129Y1549421D01*
G02X1626059Y1548768I-1070J550D01*
G01X1626057D01*
G02X1624856Y1549970I1J1202D01*
G01Y1549972D01*
G02X1625006Y1550551I1203J-3D01*
G01X1626572Y1553261D01*
G37*
G36*
G01X1631296D02*
X1631298Y1553264D01*
G02X1632358Y1553900I1060J-565D01*
G02X1633560Y1552698I0J-1202D01*
G01Y1552697D01*
G02X1633400Y1552098I-1203J1D01*
G01X1631855Y1549425D01*
X1631853Y1549421D01*
G02X1630783Y1548768I-1070J550D01*
G01X1630781D01*
G02X1629580Y1549970I1J1202D01*
G01Y1549972D01*
G02X1629730Y1550551I1203J-3D01*
G01X1631296Y1553261D01*
G37*
G36*
G01X1636023Y1553264D02*
G02X1637083Y1553900I1060J-565D01*
G01X1637085D01*
G02X1638286Y1552698I-1J-1202D01*
G02X1638125Y1552098I-1204J1D01*
G01X1636580Y1549425D01*
X1636578Y1549421D01*
G02X1635508Y1548768I-1070J550D01*
G02X1634306Y1549970I0J1202D01*
G01Y1549972D01*
G02X1634455Y1550551I1202J-1D01*
G01X1636021Y1553261D01*
X1636023Y1553264D01*
G37*
G36*
G01X1640747D02*
G02X1641807Y1553900I1060J-565D01*
G01X1641809D01*
G02X1643010Y1552698I-1J-1202D01*
G02X1642849Y1552098I-1204J1D01*
G01X1641304Y1549425D01*
X1641302Y1549421D01*
G02X1640232Y1548768I-1070J550D01*
G02X1639030Y1549970I0J1202D01*
G01Y1549972D01*
G02X1639179Y1550551I1202J-1D01*
G01X1640745Y1553261D01*
X1640747Y1553264D01*
G37*
G36*
G01X1645471D02*
G02X1646531Y1553900I1060J-565D01*
G01X1646533D01*
G02X1647734Y1552698I-1J-1202D01*
G02X1647573Y1552098I-1204J1D01*
G01X1646028Y1549425D01*
X1646026Y1549421D01*
G02X1644956Y1548768I-1070J550D01*
G02X1643754Y1549970I0J1202D01*
G01Y1549972D01*
G02X1643903Y1550551I1202J-1D01*
G01X1645469Y1553261D01*
X1645471Y1553264D01*
G37*
G36*
G01X1650194Y1553261D02*
X1650196Y1553264D01*
G02X1651256Y1553900I1060J-565D01*
G02X1652458Y1552698I0J-1202D01*
G01Y1552697D01*
G02X1652298Y1552098I-1203J1D01*
G01X1650753Y1549425D01*
X1650751Y1549421D01*
G02X1649681Y1548768I-1070J550D01*
G01X1649679D01*
G02X1648478Y1549970I1J1202D01*
G01Y1549972D01*
G02X1648628Y1550551I1203J-3D01*
G01X1650194Y1553261D01*
G37*
G36*
G01X1654918D02*
X1654920Y1553264D01*
G02X1655980Y1553900I1060J-565D01*
G02X1657182Y1552698I0J-1202D01*
G01Y1552697D01*
G02X1657022Y1552098I-1203J1D01*
G01X1655477Y1549425D01*
X1655475Y1549421D01*
G02X1654405Y1548768I-1070J550D01*
G01X1654403D01*
G02X1653202Y1549970I1J1202D01*
G01Y1549972D01*
G02X1653352Y1550551I1203J-3D01*
G01X1654918Y1553261D01*
G37*
G36*
G01X1659645Y1553264D02*
G02X1660705Y1553900I1060J-565D01*
G01X1660707D01*
G02X1661908Y1552698I-1J-1202D01*
G02X1661747Y1552098I-1204J1D01*
G01X1660202Y1549425D01*
X1660200Y1549421D01*
G02X1659130Y1548768I-1070J550D01*
G02X1657928Y1549970I0J1202D01*
G01Y1549972D01*
G02X1658077Y1550551I1202J-1D01*
G01X1659643Y1553261D01*
X1659645Y1553264D01*
G37*
G36*
G01X1235398Y1553900D02*
X1235399D01*
G02X1236602Y1552698I1J-1202D01*
G02X1236441Y1552098I-1204J1D01*
G01X1234896Y1549425D01*
X1234894Y1549421D01*
G02X1233824Y1548768I-1070J550D01*
G01X1233823D01*
G02X1232620Y1549970I-1J1202D01*
G01Y1549972D01*
G02X1232770Y1550551I1203J-3D01*
G01X1234336Y1553261D01*
X1234338Y1553264D01*
G02X1235398Y1553900I1060J-565D01*
G37*
G36*
G01X1240122D02*
X1240123D01*
G02X1241326Y1552698I1J-1202D01*
G02X1241165Y1552098I-1204J1D01*
G01X1239620Y1549425D01*
X1239618Y1549421D01*
G02X1238548Y1548768I-1070J550D01*
G01X1238547D01*
G02X1237344Y1549970I-1J1202D01*
G01Y1549972D01*
G02X1237494Y1550551I1203J-3D01*
G01X1239060Y1553261D01*
X1239062Y1553264D01*
G02X1240122Y1553900I1060J-565D01*
G37*
G36*
G01X1259020D02*
X1259021D01*
G02X1260224Y1552698I1J-1202D01*
G02X1260063Y1552098I-1204J1D01*
G01X1258518Y1549425D01*
X1258516Y1549421D01*
G02X1257446Y1548768I-1070J550D01*
G01X1257445D01*
G02X1256242Y1549970I-1J1202D01*
G01Y1549972D01*
G02X1256392Y1550551I1203J-3D01*
G01X1257958Y1553261D01*
X1257960Y1553264D01*
G02X1259020Y1553900I1060J-565D01*
G37*
G36*
G01X1196543Y1566902D02*
G02X1197603Y1567538I1060J-565D01*
G01X1197605D01*
G02X1198806Y1566336I-1J-1202D01*
G02X1198645Y1565736I-1204J1D01*
G01X1197100Y1563063D01*
X1197098Y1563059D01*
G02X1196028Y1562406I-1070J550D01*
G02X1194826Y1563608I0J1202D01*
G01Y1563610D01*
G02X1194975Y1564189I1202J-1D01*
G01X1196541Y1566899D01*
X1196543Y1566902D01*
G37*
G36*
G01X1201267D02*
G02X1202327Y1567538I1060J-565D01*
G01X1202329D01*
G02X1203530Y1566336I-1J-1202D01*
G02X1203369Y1565736I-1204J1D01*
G01X1201824Y1563063D01*
X1201822Y1563059D01*
G02X1200752Y1562406I-1070J550D01*
G02X1199550Y1563608I0J1202D01*
G01Y1563610D01*
G02X1199699Y1564189I1202J-1D01*
G01X1201265Y1566899D01*
X1201267Y1566902D01*
G37*
G36*
G01X1205991D02*
G02X1207051Y1567538I1060J-565D01*
G01X1207053D01*
G02X1208254Y1566336I-1J-1202D01*
G02X1208093Y1565736I-1204J1D01*
G01X1206548Y1563063D01*
X1206546Y1563059D01*
G02X1205476Y1562406I-1070J550D01*
G02X1204274Y1563608I0J1202D01*
G01Y1563610D01*
G02X1204423Y1564189I1202J-1D01*
G01X1205989Y1566899D01*
X1205991Y1566902D01*
G37*
G36*
G01X1210714Y1566899D02*
X1210716Y1566902D01*
G02X1211776Y1567538I1060J-565D01*
G02X1212978Y1566336I0J-1202D01*
G01Y1566335D01*
G02X1212818Y1565736I-1203J1D01*
G01X1211273Y1563063D01*
X1211271Y1563059D01*
G02X1210201Y1562406I-1070J550D01*
G01X1210199D01*
G02X1208998Y1563608I1J1202D01*
G01Y1563610D01*
G02X1209148Y1564189I1203J-3D01*
G01X1210714Y1566899D01*
G37*
G36*
G01X1215438D02*
X1215440Y1566902D01*
G02X1216500Y1567538I1060J-565D01*
G02X1217702Y1566336I0J-1202D01*
G01Y1566335D01*
G02X1217542Y1565736I-1203J1D01*
G01X1215997Y1563063D01*
X1215995Y1563059D01*
G02X1214925Y1562406I-1070J550D01*
G01X1214923D01*
G02X1213722Y1563608I1J1202D01*
G01Y1563610D01*
G02X1213872Y1564189I1203J-3D01*
G01X1215438Y1566899D01*
G37*
G36*
G01X1220165Y1566902D02*
G02X1221225Y1567538I1060J-565D01*
G01X1221227D01*
G02X1222428Y1566336I-1J-1202D01*
G02X1222267Y1565736I-1204J1D01*
G01X1220722Y1563063D01*
X1220720Y1563059D01*
G02X1219650Y1562406I-1070J550D01*
G02X1218448Y1563608I0J1202D01*
G01Y1563610D01*
G02X1218597Y1564189I1202J-1D01*
G01X1220163Y1566899D01*
X1220165Y1566902D01*
G37*
G36*
G01X1224889D02*
G02X1225949Y1567538I1060J-565D01*
G01X1225951D01*
G02X1227152Y1566336I-1J-1202D01*
G02X1226991Y1565736I-1204J1D01*
G01X1225446Y1563063D01*
X1225444Y1563059D01*
G02X1224374Y1562406I-1070J550D01*
G02X1223172Y1563608I0J1202D01*
G01Y1563610D01*
G02X1223321Y1564189I1202J-1D01*
G01X1224887Y1566899D01*
X1224889Y1566902D01*
G37*
G36*
G01X1229613D02*
G02X1230673Y1567538I1060J-565D01*
G01X1230675D01*
G02X1231876Y1566336I-1J-1202D01*
G02X1231715Y1565736I-1204J1D01*
G01X1230170Y1563063D01*
X1230168Y1563059D01*
G02X1229098Y1562406I-1070J550D01*
G02X1227896Y1563608I0J1202D01*
G01Y1563610D01*
G02X1228045Y1564189I1202J-1D01*
G01X1229611Y1566899D01*
X1229613Y1566902D01*
G37*
G36*
G01X1234336Y1566899D02*
X1234338Y1566902D01*
G02X1235398Y1567538I1060J-565D01*
G02X1236600Y1566336I0J-1202D01*
G01Y1566335D01*
G02X1236440Y1565736I-1203J1D01*
G01X1234895Y1563063D01*
X1234893Y1563059D01*
G02X1233823Y1562406I-1070J550D01*
G01X1233821D01*
G02X1232620Y1563608I1J1202D01*
G01Y1563610D01*
G02X1232770Y1564189I1203J-3D01*
G01X1234336Y1566899D01*
G37*
G36*
G01X1239060D02*
X1239062Y1566902D01*
G02X1240122Y1567538I1060J-565D01*
G02X1241324Y1566336I0J-1202D01*
G01Y1566335D01*
G02X1241164Y1565736I-1203J1D01*
G01X1239619Y1563063D01*
X1239617Y1563059D01*
G02X1238547Y1562406I-1070J550D01*
G01X1238545D01*
G02X1237344Y1563608I1J1202D01*
G01Y1563610D01*
G02X1237494Y1564189I1203J-3D01*
G01X1239060Y1566899D01*
G37*
G36*
G01X1243787Y1566902D02*
G02X1244847Y1567538I1060J-565D01*
G01X1244849D01*
G02X1246050Y1566336I-1J-1202D01*
G02X1245889Y1565736I-1204J1D01*
G01X1244344Y1563063D01*
X1244342Y1563059D01*
G02X1243272Y1562406I-1070J550D01*
G02X1242070Y1563608I0J1202D01*
G01Y1563610D01*
G02X1242219Y1564189I1202J-1D01*
G01X1243785Y1566899D01*
X1243787Y1566902D01*
G37*
G36*
G01X1248511D02*
G02X1249571Y1567538I1060J-565D01*
G01X1249573D01*
G02X1250774Y1566336I-1J-1202D01*
G02X1250613Y1565736I-1204J1D01*
G01X1249068Y1563063D01*
X1249066Y1563059D01*
G02X1247996Y1562406I-1070J550D01*
G02X1246794Y1563608I0J1202D01*
G01Y1563610D01*
G02X1246943Y1564189I1202J-1D01*
G01X1248509Y1566899D01*
X1248511Y1566902D01*
G37*
G36*
G01X1253235D02*
G02X1254295Y1567538I1060J-565D01*
G01X1254297D01*
G02X1255498Y1566336I-1J-1202D01*
G02X1255337Y1565736I-1204J1D01*
G01X1253792Y1563063D01*
X1253790Y1563059D01*
G02X1252720Y1562406I-1070J550D01*
G02X1251518Y1563608I0J1202D01*
G01Y1563610D01*
G02X1251667Y1564189I1202J-1D01*
G01X1253233Y1566899D01*
X1253235Y1566902D01*
G37*
G36*
G01X1257958Y1566899D02*
X1257960Y1566902D01*
G02X1259020Y1567538I1060J-565D01*
G02X1260222Y1566336I0J-1202D01*
G01Y1566335D01*
G02X1260062Y1565736I-1203J1D01*
G01X1258517Y1563063D01*
X1258515Y1563059D01*
G02X1257445Y1562406I-1070J550D01*
G01X1257443D01*
G02X1256242Y1563608I1J1202D01*
G01Y1563610D01*
G02X1256392Y1564189I1203J-3D01*
G01X1257958Y1566899D01*
G37*
G36*
G01X1262682D02*
X1262684Y1566902D01*
G02X1263744Y1567538I1060J-565D01*
G02X1264946Y1566336I0J-1202D01*
G01Y1566335D01*
G02X1264786Y1565736I-1203J1D01*
G01X1263241Y1563063D01*
X1263239Y1563059D01*
G02X1262169Y1562406I-1070J550D01*
G01X1262167D01*
G02X1260966Y1563608I1J1202D01*
G01Y1563610D01*
G02X1261116Y1564189I1203J-3D01*
G01X1262682Y1566899D01*
G37*
G36*
G01X1267409Y1566902D02*
G02X1268469Y1567538I1060J-565D01*
G01X1268471D01*
G02X1269672Y1566336I-1J-1202D01*
G02X1269511Y1565736I-1204J1D01*
G01X1267966Y1563063D01*
X1267964Y1563059D01*
G02X1266894Y1562406I-1070J550D01*
G02X1265692Y1563608I0J1202D01*
G01Y1563610D01*
G02X1265841Y1564189I1202J-1D01*
G01X1267407Y1566899D01*
X1267409Y1566902D01*
G37*
G36*
G01X1324605D02*
G02X1325665Y1567538I1060J-565D01*
G01X1325667D01*
G02X1326868Y1566336I-1J-1202D01*
G02X1326707Y1565736I-1204J1D01*
G01X1325162Y1563063D01*
X1325160Y1563059D01*
G02X1324090Y1562406I-1070J550D01*
G02X1322888Y1563608I0J1202D01*
G01Y1563610D01*
G02X1323037Y1564189I1202J-1D01*
G01X1324603Y1566899D01*
X1324605Y1566902D01*
G37*
G36*
G01X1329329D02*
G02X1330389Y1567538I1060J-565D01*
G01X1330391D01*
G02X1331592Y1566336I-1J-1202D01*
G02X1331431Y1565736I-1204J1D01*
G01X1329886Y1563063D01*
X1329884Y1563059D01*
G02X1328814Y1562406I-1070J550D01*
G02X1327612Y1563608I0J1202D01*
G01Y1563610D01*
G02X1327761Y1564189I1202J-1D01*
G01X1329327Y1566899D01*
X1329329Y1566902D01*
G37*
G36*
G01X1334053D02*
G02X1335113Y1567538I1060J-565D01*
G01X1335115D01*
G02X1336316Y1566336I-1J-1202D01*
G02X1336155Y1565736I-1204J1D01*
G01X1334610Y1563063D01*
X1334608Y1563059D01*
G02X1333538Y1562406I-1070J550D01*
G02X1332336Y1563608I0J1202D01*
G01Y1563610D01*
G02X1332485Y1564189I1202J-1D01*
G01X1334051Y1566899D01*
X1334053Y1566902D01*
G37*
G36*
G01X1338776Y1566899D02*
X1338778Y1566902D01*
G02X1339838Y1567538I1060J-565D01*
G02X1341040Y1566336I0J-1202D01*
G01Y1566335D01*
G02X1340880Y1565736I-1203J1D01*
G01X1339335Y1563063D01*
X1339333Y1563059D01*
G02X1338263Y1562406I-1070J550D01*
G01X1338261D01*
G02X1337060Y1563608I1J1202D01*
G01Y1563610D01*
G02X1337210Y1564189I1203J-3D01*
G01X1338776Y1566899D01*
G37*
G36*
G01X1343500D02*
X1343502Y1566902D01*
G02X1344562Y1567538I1060J-565D01*
G02X1345764Y1566336I0J-1202D01*
G01Y1566335D01*
G02X1345604Y1565736I-1203J1D01*
G01X1344059Y1563063D01*
X1344057Y1563059D01*
G02X1342987Y1562406I-1070J550D01*
G01X1342985D01*
G02X1341784Y1563608I1J1202D01*
G01Y1563610D01*
G02X1341934Y1564189I1203J-3D01*
G01X1343500Y1566899D01*
G37*
G36*
G01X1348227Y1566902D02*
G02X1349287Y1567538I1060J-565D01*
G01X1349289D01*
G02X1350490Y1566336I-1J-1202D01*
G02X1350329Y1565736I-1204J1D01*
G01X1348784Y1563063D01*
X1348782Y1563059D01*
G02X1347712Y1562406I-1070J550D01*
G02X1346510Y1563608I0J1202D01*
G01Y1563610D01*
G02X1346659Y1564189I1202J-1D01*
G01X1348225Y1566899D01*
X1348227Y1566902D01*
G37*
G36*
G01X1352951D02*
G02X1354011Y1567538I1060J-565D01*
G01X1354013D01*
G02X1355214Y1566336I-1J-1202D01*
G02X1355053Y1565736I-1204J1D01*
G01X1353508Y1563063D01*
X1353506Y1563059D01*
G02X1352436Y1562406I-1070J550D01*
G02X1351234Y1563608I0J1202D01*
G01Y1563610D01*
G02X1351383Y1564189I1202J-1D01*
G01X1352949Y1566899D01*
X1352951Y1566902D01*
G37*
G36*
G01X1357675D02*
G02X1358735Y1567538I1060J-565D01*
G01X1358737D01*
G02X1359938Y1566336I-1J-1202D01*
G02X1359777Y1565736I-1204J1D01*
G01X1358232Y1563063D01*
X1358230Y1563059D01*
G02X1357160Y1562406I-1070J550D01*
G02X1355958Y1563608I0J1202D01*
G01Y1563610D01*
G02X1356107Y1564189I1202J-1D01*
G01X1357673Y1566899D01*
X1357675Y1566902D01*
G37*
G36*
G01X1362398Y1566899D02*
X1362400Y1566902D01*
G02X1363460Y1567538I1060J-565D01*
G02X1364662Y1566336I0J-1202D01*
G01Y1566335D01*
G02X1364502Y1565736I-1203J1D01*
G01X1362957Y1563063D01*
X1362955Y1563059D01*
G02X1361885Y1562406I-1070J550D01*
G01X1361883D01*
G02X1360682Y1563608I1J1202D01*
G01Y1563610D01*
G02X1360832Y1564189I1203J-3D01*
G01X1362398Y1566899D01*
G37*
G36*
G01X1367122D02*
X1367124Y1566902D01*
G02X1368184Y1567538I1060J-565D01*
G02X1369386Y1566336I0J-1202D01*
G01Y1566335D01*
G02X1369226Y1565736I-1203J1D01*
G01X1367681Y1563063D01*
X1367679Y1563059D01*
G02X1366609Y1562406I-1070J550D01*
G01X1366607D01*
G02X1365406Y1563608I1J1202D01*
G01Y1563610D01*
G02X1365556Y1564189I1203J-3D01*
G01X1367122Y1566899D01*
G37*
G36*
G01X1371849Y1566902D02*
G02X1372909Y1567538I1060J-565D01*
G01X1372911D01*
G02X1374112Y1566336I-1J-1202D01*
G02X1373951Y1565736I-1204J1D01*
G01X1372406Y1563063D01*
X1372404Y1563059D01*
G02X1371334Y1562406I-1070J550D01*
G02X1370132Y1563608I0J1202D01*
G01Y1563610D01*
G02X1370281Y1564189I1202J-1D01*
G01X1371847Y1566899D01*
X1371849Y1566902D01*
G37*
G36*
G01X1376573D02*
G02X1377633Y1567538I1060J-565D01*
G01X1377635D01*
G02X1378836Y1566336I-1J-1202D01*
G02X1378675Y1565736I-1204J1D01*
G01X1377130Y1563063D01*
X1377128Y1563059D01*
G02X1376058Y1562406I-1070J550D01*
G02X1374856Y1563608I0J1202D01*
G01Y1563610D01*
G02X1375005Y1564189I1202J-1D01*
G01X1376571Y1566899D01*
X1376573Y1566902D01*
G37*
G36*
G01X1381297D02*
G02X1382357Y1567538I1060J-565D01*
G01X1382359D01*
G02X1383560Y1566336I-1J-1202D01*
G02X1383399Y1565736I-1204J1D01*
G01X1381854Y1563063D01*
X1381852Y1563059D01*
G02X1380782Y1562406I-1070J550D01*
G02X1379580Y1563608I0J1202D01*
G01Y1563610D01*
G02X1379729Y1564189I1202J-1D01*
G01X1381295Y1566899D01*
X1381297Y1566902D01*
G37*
G36*
G01X1386020Y1566899D02*
X1386022Y1566902D01*
G02X1387082Y1567538I1060J-565D01*
G02X1388284Y1566336I0J-1202D01*
G01Y1566335D01*
G02X1388124Y1565736I-1203J1D01*
G01X1386579Y1563063D01*
X1386577Y1563059D01*
G02X1385507Y1562406I-1070J550D01*
G01X1385505D01*
G02X1384304Y1563608I1J1202D01*
G01Y1563610D01*
G02X1384454Y1564189I1203J-3D01*
G01X1386020Y1566899D01*
G37*
G36*
G01X1390744D02*
X1390746Y1566902D01*
G02X1391806Y1567538I1060J-565D01*
G02X1393008Y1566336I0J-1202D01*
G01Y1566335D01*
G02X1392848Y1565736I-1203J1D01*
G01X1391303Y1563063D01*
X1391301Y1563059D01*
G02X1390231Y1562406I-1070J550D01*
G01X1390229D01*
G02X1389028Y1563608I1J1202D01*
G01Y1563610D01*
G02X1389178Y1564189I1203J-3D01*
G01X1390744Y1566899D01*
G37*
G36*
G01X1395471Y1566902D02*
G02X1396531Y1567538I1060J-565D01*
G01X1396533D01*
G02X1397734Y1566336I-1J-1202D01*
G02X1397573Y1565736I-1204J1D01*
G01X1396028Y1563063D01*
X1396026Y1563059D01*
G02X1394956Y1562406I-1070J550D01*
G02X1393754Y1563608I0J1202D01*
G01Y1563610D01*
G02X1393903Y1564189I1202J-1D01*
G01X1395469Y1566899D01*
X1395471Y1566902D01*
G37*
G36*
G01X1460717D02*
G02X1461777Y1567538I1060J-565D01*
G01X1461779D01*
G02X1462980Y1566336I-1J-1202D01*
G02X1462819Y1565736I-1204J1D01*
G01X1461274Y1563063D01*
X1461272Y1563059D01*
G02X1460202Y1562406I-1070J550D01*
G02X1459000Y1563608I0J1202D01*
G01Y1563610D01*
G02X1459149Y1564189I1202J-1D01*
G01X1460715Y1566899D01*
X1460717Y1566902D01*
G37*
G36*
G01X1465441D02*
G02X1466501Y1567538I1060J-565D01*
G01X1466503D01*
G02X1467704Y1566336I-1J-1202D01*
G02X1467543Y1565736I-1204J1D01*
G01X1465998Y1563063D01*
X1465996Y1563059D01*
G02X1464926Y1562406I-1070J550D01*
G02X1463724Y1563608I0J1202D01*
G01Y1563610D01*
G02X1463873Y1564189I1202J-1D01*
G01X1465439Y1566899D01*
X1465441Y1566902D01*
G37*
G36*
G01X1470165D02*
G02X1471225Y1567538I1060J-565D01*
G01X1471227D01*
G02X1472428Y1566336I-1J-1202D01*
G02X1472267Y1565736I-1204J1D01*
G01X1470722Y1563063D01*
X1470720Y1563059D01*
G02X1469650Y1562406I-1070J550D01*
G02X1468448Y1563608I0J1202D01*
G01Y1563610D01*
G02X1468597Y1564189I1202J-1D01*
G01X1470163Y1566899D01*
X1470165Y1566902D01*
G37*
G36*
G01X1474888Y1566899D02*
X1474890Y1566902D01*
G02X1475950Y1567538I1060J-565D01*
G02X1477152Y1566336I0J-1202D01*
G01Y1566335D01*
G02X1476992Y1565736I-1203J1D01*
G01X1475447Y1563063D01*
X1475445Y1563059D01*
G02X1474375Y1562406I-1070J550D01*
G01X1474373D01*
G02X1473172Y1563608I1J1202D01*
G01Y1563610D01*
G02X1473322Y1564189I1203J-3D01*
G01X1474888Y1566899D01*
G37*
G36*
G01X1479612D02*
X1479614Y1566902D01*
G02X1480674Y1567538I1060J-565D01*
G02X1481876Y1566336I0J-1202D01*
G01Y1566335D01*
G02X1481716Y1565736I-1203J1D01*
G01X1480171Y1563063D01*
X1480169Y1563059D01*
G02X1479099Y1562406I-1070J550D01*
G01X1479097D01*
G02X1477896Y1563608I1J1202D01*
G01Y1563610D01*
G02X1478046Y1564189I1203J-3D01*
G01X1479612Y1566899D01*
G37*
G36*
G01X1484339Y1566902D02*
G02X1485399Y1567538I1060J-565D01*
G01X1485401D01*
G02X1486602Y1566336I-1J-1202D01*
G02X1486441Y1565736I-1204J1D01*
G01X1484896Y1563063D01*
X1484894Y1563059D01*
G02X1483824Y1562406I-1070J550D01*
G02X1482622Y1563608I0J1202D01*
G01Y1563610D01*
G02X1482771Y1564189I1202J-1D01*
G01X1484337Y1566899D01*
X1484339Y1566902D01*
G37*
G36*
G01X1489063D02*
G02X1490123Y1567538I1060J-565D01*
G01X1490125D01*
G02X1491326Y1566336I-1J-1202D01*
G02X1491165Y1565736I-1204J1D01*
G01X1489620Y1563063D01*
X1489618Y1563059D01*
G02X1488548Y1562406I-1070J550D01*
G02X1487346Y1563608I0J1202D01*
G01Y1563610D01*
G02X1487495Y1564189I1202J-1D01*
G01X1489061Y1566899D01*
X1489063Y1566902D01*
G37*
G36*
G01X1493787D02*
G02X1494847Y1567538I1060J-565D01*
G01X1494849D01*
G02X1496050Y1566336I-1J-1202D01*
G02X1495889Y1565736I-1204J1D01*
G01X1494344Y1563063D01*
X1494342Y1563059D01*
G02X1493272Y1562406I-1070J550D01*
G02X1492070Y1563608I0J1202D01*
G01Y1563610D01*
G02X1492219Y1564189I1202J-1D01*
G01X1493785Y1566899D01*
X1493787Y1566902D01*
G37*
G36*
G01X1498510Y1566899D02*
X1498512Y1566902D01*
G02X1499572Y1567538I1060J-565D01*
G02X1500774Y1566336I0J-1202D01*
G01Y1566335D01*
G02X1500614Y1565736I-1203J1D01*
G01X1499069Y1563063D01*
X1499067Y1563059D01*
G02X1497997Y1562406I-1070J550D01*
G01X1497995D01*
G02X1496794Y1563608I1J1202D01*
G01Y1563610D01*
G02X1496944Y1564189I1203J-3D01*
G01X1498510Y1566899D01*
G37*
G36*
G01X1503234D02*
X1503236Y1566902D01*
G02X1504296Y1567538I1060J-565D01*
G02X1505498Y1566336I0J-1202D01*
G01Y1566335D01*
G02X1505338Y1565736I-1203J1D01*
G01X1503793Y1563063D01*
X1503791Y1563059D01*
G02X1502721Y1562406I-1070J550D01*
G01X1502719D01*
G02X1501518Y1563608I1J1202D01*
G01Y1563610D01*
G02X1501668Y1564189I1203J-3D01*
G01X1503234Y1566899D01*
G37*
G36*
G01X1507961Y1566902D02*
G02X1509021Y1567538I1060J-565D01*
G01X1509023D01*
G02X1510224Y1566336I-1J-1202D01*
G02X1510063Y1565736I-1204J1D01*
G01X1508518Y1563063D01*
X1508516Y1563059D01*
G02X1507446Y1562406I-1070J550D01*
G02X1506244Y1563608I0J1202D01*
G01Y1563610D01*
G02X1506393Y1564189I1202J-1D01*
G01X1507959Y1566899D01*
X1507961Y1566902D01*
G37*
G36*
G01X1512685D02*
G02X1513745Y1567538I1060J-565D01*
G01X1513747D01*
G02X1514948Y1566336I-1J-1202D01*
G02X1514787Y1565736I-1204J1D01*
G01X1513242Y1563063D01*
X1513240Y1563059D01*
G02X1512170Y1562406I-1070J550D01*
G02X1510968Y1563608I0J1202D01*
G01Y1563610D01*
G02X1511117Y1564189I1202J-1D01*
G01X1512683Y1566899D01*
X1512685Y1566902D01*
G37*
G36*
G01X1517409D02*
G02X1518469Y1567538I1060J-565D01*
G01X1518471D01*
G02X1519672Y1566336I-1J-1202D01*
G02X1519511Y1565736I-1204J1D01*
G01X1517966Y1563063D01*
X1517964Y1563059D01*
G02X1516894Y1562406I-1070J550D01*
G02X1515692Y1563608I0J1202D01*
G01Y1563610D01*
G02X1515841Y1564189I1202J-1D01*
G01X1517407Y1566899D01*
X1517409Y1566902D01*
G37*
G36*
G01X1522132Y1566899D02*
X1522134Y1566902D01*
G02X1523194Y1567538I1060J-565D01*
G02X1524396Y1566336I0J-1202D01*
G01Y1566335D01*
G02X1524236Y1565736I-1203J1D01*
G01X1522691Y1563063D01*
X1522689Y1563059D01*
G02X1521619Y1562406I-1070J550D01*
G01X1521617D01*
G02X1520416Y1563608I1J1202D01*
G01Y1563610D01*
G02X1520566Y1564189I1203J-3D01*
G01X1522132Y1566899D01*
G37*
G36*
G01X1526856D02*
X1526858Y1566902D01*
G02X1527918Y1567538I1060J-565D01*
G02X1529120Y1566336I0J-1202D01*
G01Y1566335D01*
G02X1528960Y1565736I-1203J1D01*
G01X1527415Y1563063D01*
X1527413Y1563059D01*
G02X1526343Y1562406I-1070J550D01*
G01X1526341D01*
G02X1525140Y1563608I1J1202D01*
G01Y1563610D01*
G02X1525290Y1564189I1203J-3D01*
G01X1526856Y1566899D01*
G37*
G36*
G01X1531583Y1566902D02*
G02X1532643Y1567538I1060J-565D01*
G01X1532645D01*
G02X1533846Y1566336I-1J-1202D01*
G02X1533685Y1565736I-1204J1D01*
G01X1532140Y1563063D01*
X1532138Y1563059D01*
G02X1531068Y1562406I-1070J550D01*
G02X1529866Y1563608I0J1202D01*
G01Y1563610D01*
G02X1530015Y1564189I1202J-1D01*
G01X1531581Y1566899D01*
X1531583Y1566902D01*
G37*
G36*
G01X1588779D02*
G02X1589839Y1567538I1060J-565D01*
G01X1589841D01*
G02X1591042Y1566336I-1J-1202D01*
G02X1590881Y1565736I-1204J1D01*
G01X1589336Y1563063D01*
X1589334Y1563059D01*
G02X1588264Y1562406I-1070J550D01*
G02X1587062Y1563608I0J1202D01*
G01Y1563610D01*
G02X1587211Y1564189I1202J-1D01*
G01X1588777Y1566899D01*
X1588779Y1566902D01*
G37*
G36*
G01X1593503D02*
G02X1594563Y1567538I1060J-565D01*
G01X1594565D01*
G02X1595766Y1566336I-1J-1202D01*
G02X1595605Y1565736I-1204J1D01*
G01X1594060Y1563063D01*
X1594058Y1563059D01*
G02X1592988Y1562406I-1070J550D01*
G02X1591786Y1563608I0J1202D01*
G01Y1563610D01*
G02X1591935Y1564189I1202J-1D01*
G01X1593501Y1566899D01*
X1593503Y1566902D01*
G37*
G36*
G01X1598227D02*
G02X1599287Y1567538I1060J-565D01*
G01X1599289D01*
G02X1600490Y1566336I-1J-1202D01*
G02X1600329Y1565736I-1204J1D01*
G01X1598784Y1563063D01*
X1598782Y1563059D01*
G02X1597712Y1562406I-1070J550D01*
G02X1596510Y1563608I0J1202D01*
G01Y1563610D01*
G02X1596659Y1564189I1202J-1D01*
G01X1598225Y1566899D01*
X1598227Y1566902D01*
G37*
G36*
G01X1602950Y1566899D02*
X1602952Y1566902D01*
G02X1604012Y1567538I1060J-565D01*
G02X1605214Y1566336I0J-1202D01*
G01Y1566335D01*
G02X1605054Y1565736I-1203J1D01*
G01X1603509Y1563063D01*
X1603507Y1563059D01*
G02X1602437Y1562406I-1070J550D01*
G01X1602435D01*
G02X1601234Y1563608I1J1202D01*
G01Y1563610D01*
G02X1601384Y1564189I1203J-3D01*
G01X1602950Y1566899D01*
G37*
G36*
G01X1607674D02*
X1607676Y1566902D01*
G02X1608736Y1567538I1060J-565D01*
G02X1609938Y1566336I0J-1202D01*
G01Y1566335D01*
G02X1609778Y1565736I-1203J1D01*
G01X1608233Y1563063D01*
X1608231Y1563059D01*
G02X1607161Y1562406I-1070J550D01*
G01X1607159D01*
G02X1605958Y1563608I1J1202D01*
G01Y1563610D01*
G02X1606108Y1564189I1203J-3D01*
G01X1607674Y1566899D01*
G37*
G36*
G01X1612401Y1566902D02*
G02X1613461Y1567538I1060J-565D01*
G01X1613463D01*
G02X1614664Y1566336I-1J-1202D01*
G02X1614503Y1565736I-1204J1D01*
G01X1612958Y1563063D01*
X1612956Y1563059D01*
G02X1611886Y1562406I-1070J550D01*
G02X1610684Y1563608I0J1202D01*
G01Y1563610D01*
G02X1610833Y1564189I1202J-1D01*
G01X1612399Y1566899D01*
X1612401Y1566902D01*
G37*
G36*
G01X1617125D02*
G02X1618185Y1567538I1060J-565D01*
G01X1618187D01*
G02X1619388Y1566336I-1J-1202D01*
G02X1619227Y1565736I-1204J1D01*
G01X1617682Y1563063D01*
X1617680Y1563059D01*
G02X1616610Y1562406I-1070J550D01*
G02X1615408Y1563608I0J1202D01*
G01Y1563610D01*
G02X1615557Y1564189I1202J-1D01*
G01X1617123Y1566899D01*
X1617125Y1566902D01*
G37*
G36*
G01X1621849D02*
G02X1622909Y1567538I1060J-565D01*
G01X1622911D01*
G02X1624112Y1566336I-1J-1202D01*
G02X1623951Y1565736I-1204J1D01*
G01X1622406Y1563063D01*
X1622404Y1563059D01*
G02X1621334Y1562406I-1070J550D01*
G02X1620132Y1563608I0J1202D01*
G01Y1563610D01*
G02X1620281Y1564189I1202J-1D01*
G01X1621847Y1566899D01*
X1621849Y1566902D01*
G37*
G36*
G01X1626572Y1566899D02*
X1626574Y1566902D01*
G02X1627634Y1567538I1060J-565D01*
G02X1628836Y1566336I0J-1202D01*
G01Y1566335D01*
G02X1628676Y1565736I-1203J1D01*
G01X1627131Y1563063D01*
X1627129Y1563059D01*
G02X1626059Y1562406I-1070J550D01*
G01X1626057D01*
G02X1624856Y1563608I1J1202D01*
G01Y1563610D01*
G02X1625006Y1564189I1203J-3D01*
G01X1626572Y1566899D01*
G37*
G36*
G01X1631296D02*
X1631298Y1566902D01*
G02X1632358Y1567538I1060J-565D01*
G02X1633560Y1566336I0J-1202D01*
G01Y1566335D01*
G02X1633400Y1565736I-1203J1D01*
G01X1631855Y1563063D01*
X1631853Y1563059D01*
G02X1630783Y1562406I-1070J550D01*
G01X1630781D01*
G02X1629580Y1563608I1J1202D01*
G01Y1563610D01*
G02X1629730Y1564189I1203J-3D01*
G01X1631296Y1566899D01*
G37*
G36*
G01X1636023Y1566902D02*
G02X1637083Y1567538I1060J-565D01*
G01X1637085D01*
G02X1638286Y1566336I-1J-1202D01*
G02X1638125Y1565736I-1204J1D01*
G01X1636580Y1563063D01*
X1636578Y1563059D01*
G02X1635508Y1562406I-1070J550D01*
G02X1634306Y1563608I0J1202D01*
G01Y1563610D01*
G02X1634455Y1564189I1202J-1D01*
G01X1636021Y1566899D01*
X1636023Y1566902D01*
G37*
G36*
G01X1640747D02*
G02X1641807Y1567538I1060J-565D01*
G01X1641809D01*
G02X1643010Y1566336I-1J-1202D01*
G02X1642849Y1565736I-1204J1D01*
G01X1641304Y1563063D01*
X1641302Y1563059D01*
G02X1640232Y1562406I-1070J550D01*
G02X1639030Y1563608I0J1202D01*
G01Y1563610D01*
G02X1639179Y1564189I1202J-1D01*
G01X1640745Y1566899D01*
X1640747Y1566902D01*
G37*
G36*
G01X1645471D02*
G02X1646531Y1567538I1060J-565D01*
G01X1646533D01*
G02X1647734Y1566336I-1J-1202D01*
G02X1647573Y1565736I-1204J1D01*
G01X1646028Y1563063D01*
X1646026Y1563059D01*
G02X1644956Y1562406I-1070J550D01*
G02X1643754Y1563608I0J1202D01*
G01Y1563610D01*
G02X1643903Y1564189I1202J-1D01*
G01X1645469Y1566899D01*
X1645471Y1566902D01*
G37*
G36*
G01X1650194Y1566899D02*
X1650196Y1566902D01*
G02X1651256Y1567538I1060J-565D01*
G02X1652458Y1566336I0J-1202D01*
G01Y1566335D01*
G02X1652298Y1565736I-1203J1D01*
G01X1650753Y1563063D01*
X1650751Y1563059D01*
G02X1649681Y1562406I-1070J550D01*
G01X1649679D01*
G02X1648478Y1563608I1J1202D01*
G01Y1563610D01*
G02X1648628Y1564189I1203J-3D01*
G01X1650194Y1566899D01*
G37*
G36*
G01X1654918D02*
X1654920Y1566902D01*
G02X1655980Y1567538I1060J-565D01*
G02X1657182Y1566336I0J-1202D01*
G01Y1566335D01*
G02X1657022Y1565736I-1203J1D01*
G01X1655477Y1563063D01*
X1655475Y1563059D01*
G02X1654405Y1562406I-1070J550D01*
G01X1654403D01*
G02X1653202Y1563608I1J1202D01*
G01Y1563610D01*
G02X1653352Y1564189I1203J-3D01*
G01X1654918Y1566899D01*
G37*
G36*
G01X1659645Y1566902D02*
G02X1660705Y1567538I1060J-565D01*
G01X1660707D01*
G02X1661908Y1566336I-1J-1202D01*
G02X1661747Y1565736I-1204J1D01*
G01X1660202Y1563063D01*
X1660200Y1563059D01*
G02X1659130Y1562406I-1070J550D01*
G02X1657928Y1563608I0J1202D01*
G01Y1563610D01*
G02X1658077Y1564189I1202J-1D01*
G01X1659643Y1566899D01*
X1659645Y1566902D01*
G37*
G36*
G01X408001Y1575620D02*
G02X407422Y1576805I923J1185D01*
G02X410428I1503J0D01*
G02X409849Y1575620I-1502J0D01*
G03X409772Y1575463I123J-158D01*
G01Y1575147D01*
G03X409849Y1574990I200J1D01*
G02X410428Y1573805I-923J-1185D01*
G02X407422I-1503J0D01*
G02X408001Y1574990I1502J0D01*
G03X408078Y1575147I-123J158D01*
G01Y1575463D01*
G03X408001Y1575620I-200J-1D01*
G37*
G36*
G01X188166Y1590878D02*
G02Y1593882I0J1502D01*
G01X191566D01*
G02Y1590878I0J-1502D01*
G01X188166D01*
G37*
G36*
G01X200226D02*
G02Y1593882I0J1502D01*
G01X203626D01*
G02Y1590878I0J-1502D01*
G01X200226D01*
G37*
G36*
G01X212286D02*
G02Y1593882I0J1502D01*
G01X215686D01*
G02Y1590878I0J-1502D01*
G01X212286D01*
G37*
G36*
G01X224346D02*
G02Y1593882I0J1502D01*
G01X227746D01*
G02Y1590878I0J-1502D01*
G01X224346D01*
G37*
G36*
G01X236406D02*
G02Y1593882I0J1502D01*
G01X239806D01*
G02Y1590878I0J-1502D01*
G01X236406D01*
G37*
G36*
G01X248466D02*
G02Y1593882I0J1502D01*
G01X251866D01*
G02Y1590878I0J-1502D01*
G01X248466D01*
G37*
G36*
G01X260526D02*
G02Y1593882I0J1502D01*
G01X263926D01*
G02Y1590878I0J-1502D01*
G01X260526D01*
G37*
G36*
G01X272586D02*
G02Y1593882I0J1502D01*
G01X275986D01*
G02Y1590878I0J-1502D01*
G01X272586D01*
G37*
G36*
G01X284646D02*
G02Y1593882I0J1502D01*
G01X288046D01*
G02Y1590878I0J-1502D01*
G01X284646D01*
G37*
G36*
G01X296706D02*
G02Y1593882I0J1502D01*
G01X300106D01*
G02Y1590878I0J-1502D01*
G01X296706D01*
G37*
G36*
G01X308766D02*
G02Y1593882I0J1502D01*
G01X312166D01*
G02Y1590878I0J-1502D01*
G01X308766D01*
G37*
G36*
G01X320826D02*
G02Y1593882I0J1502D01*
G01X324226D01*
G02Y1590878I0J-1502D01*
G01X320826D01*
G37*
G36*
G01X332886D02*
G02Y1593882I0J1502D01*
G01X336286D01*
G02Y1590878I0J-1502D01*
G01X332886D01*
G37*
G36*
G01X344946D02*
G02Y1593882I0J1502D01*
G01X348346D01*
G02Y1590878I0J-1502D01*
G01X344946D01*
G37*
G36*
G01X357006D02*
G02Y1593882I0J1502D01*
G01X360406D01*
G02Y1590878I0J-1502D01*
G01X357006D01*
G37*
G36*
G01X369066D02*
G02Y1593882I0J1502D01*
G01X372466D01*
G02Y1590878I0J-1502D01*
G01X369066D01*
G37*
G36*
G01X452339D02*
G02Y1593882I0J1502D01*
G01X455739D01*
G02Y1590878I0J-1502D01*
G01X452339D01*
G37*
G36*
G01X464399D02*
G02Y1593882I0J1502D01*
G01X467799D01*
G02Y1590878I0J-1502D01*
G01X464399D01*
G37*
G36*
G01X476459D02*
G02Y1593882I0J1502D01*
G01X479859D01*
G02Y1590878I0J-1502D01*
G01X476459D01*
G37*
G36*
G01X488519D02*
G02Y1593882I0J1502D01*
G01X491919D01*
G02Y1590878I0J-1502D01*
G01X488519D01*
G37*
G36*
G01X500579D02*
G02Y1593882I0J1502D01*
G01X503979D01*
G02Y1590878I0J-1502D01*
G01X500579D01*
G37*
G36*
G01X512639D02*
G02Y1593882I0J1502D01*
G01X516039D01*
G02Y1590878I0J-1502D01*
G01X512639D01*
G37*
G36*
G01X524699D02*
G02Y1593882I0J1502D01*
G01X528099D01*
G02Y1590878I0J-1502D01*
G01X524699D01*
G37*
G36*
G01X536759D02*
G02Y1593882I0J1502D01*
G01X540159D01*
G02Y1590878I0J-1502D01*
G01X536759D01*
G37*
G36*
G01X548819D02*
G02Y1593882I0J1502D01*
G01X552219D01*
G02Y1590878I0J-1502D01*
G01X548819D01*
G37*
G36*
G01X560879D02*
G02Y1593882I0J1502D01*
G01X564279D01*
G02Y1590878I0J-1502D01*
G01X560879D01*
G37*
G36*
G01X572939D02*
G02Y1593882I0J1502D01*
G01X576339D01*
G02Y1590878I0J-1502D01*
G01X572939D01*
G37*
G36*
G01X584999D02*
G02Y1593882I0J1502D01*
G01X588399D01*
G02Y1590878I0J-1502D01*
G01X584999D01*
G37*
G36*
G01X597059D02*
G02Y1593882I0J1502D01*
G01X600459D01*
G02Y1590878I0J-1502D01*
G01X597059D01*
G37*
G36*
G01X609119D02*
G02Y1593882I0J1502D01*
G01X612519D01*
G02Y1590878I0J-1502D01*
G01X609119D01*
G37*
G36*
G01X621179D02*
G02Y1593882I0J1502D01*
G01X624579D01*
G02Y1590878I0J-1502D01*
G01X621179D01*
G37*
G36*
G01X633239D02*
G02Y1593882I0J1502D01*
G01X636639D01*
G02Y1590878I0J-1502D01*
G01X633239D01*
G37*
G36*
G01X422069Y1593930D02*
G02Y1596936I0J1503D01*
G01X425469D01*
G02Y1593930I0J-1503D01*
G01X422069D01*
G37*
G36*
G01X409929Y1595939D02*
G02X412054Y1598064I1063J1062D01*
G01X414459Y1595660D01*
G02X414899Y1594597I-1064J-1063D01*
G02X413396Y1593094I-1503J0D01*
G02X412333Y1593534I0J1504D01*
G01X409929Y1595939D01*
G37*
G36*
G01X194196Y1600878D02*
G02Y1603882I0J1502D01*
G01X197596D01*
G02Y1600878I0J-1502D01*
G01X194196D01*
G37*
G36*
G01X206256D02*
G02Y1603882I0J1502D01*
G01X209656D01*
G02Y1600878I0J-1502D01*
G01X206256D01*
G37*
G36*
G01X218316D02*
G02Y1603882I0J1502D01*
G01X221716D01*
G02Y1600878I0J-1502D01*
G01X218316D01*
G37*
G36*
G01X230376D02*
G02Y1603882I0J1502D01*
G01X233776D01*
G02Y1600878I0J-1502D01*
G01X230376D01*
G37*
G36*
G01X242436D02*
G02Y1603882I0J1502D01*
G01X245836D01*
G02Y1600878I0J-1502D01*
G01X242436D01*
G37*
G36*
G01X254496D02*
G02Y1603882I0J1502D01*
G01X257896D01*
G02Y1600878I0J-1502D01*
G01X254496D01*
G37*
G36*
G01X266556D02*
G02Y1603882I0J1502D01*
G01X269956D01*
G02Y1600878I0J-1502D01*
G01X266556D01*
G37*
G36*
G01X278616D02*
G02Y1603882I0J1502D01*
G01X282016D01*
G02Y1600878I0J-1502D01*
G01X278616D01*
G37*
G36*
G01X290676D02*
G02Y1603882I0J1502D01*
G01X294076D01*
G02Y1600878I0J-1502D01*
G01X290676D01*
G37*
G36*
G01X302736D02*
G02Y1603882I0J1502D01*
G01X306136D01*
G02Y1600878I0J-1502D01*
G01X302736D01*
G37*
G36*
G01X314796D02*
G02Y1603882I0J1502D01*
G01X318196D01*
G02Y1600878I0J-1502D01*
G01X314796D01*
G37*
G36*
G01X326856D02*
G02Y1603882I0J1502D01*
G01X330256D01*
G02Y1600878I0J-1502D01*
G01X326856D01*
G37*
G36*
G01X338916D02*
G02Y1603882I0J1502D01*
G01X342316D01*
G02Y1600878I0J-1502D01*
G01X338916D01*
G37*
G36*
G01X350976D02*
G02Y1603882I0J1502D01*
G01X354376D01*
G02Y1600878I0J-1502D01*
G01X350976D01*
G37*
G36*
G01X363036D02*
G02Y1603882I0J1502D01*
G01X366436D01*
G02Y1600878I0J-1502D01*
G01X363036D01*
G37*
G36*
G01X375096D02*
G02Y1603882I0J1502D01*
G01X378496D01*
G02Y1600878I0J-1502D01*
G01X375096D01*
G37*
G36*
G01X458369D02*
G02Y1603882I0J1502D01*
G01X461769D01*
G02Y1600878I0J-1502D01*
G01X458369D01*
G37*
G36*
G01X470429D02*
G02Y1603882I0J1502D01*
G01X473829D01*
G02Y1600878I0J-1502D01*
G01X470429D01*
G37*
G36*
G01X482489D02*
G02Y1603882I0J1502D01*
G01X485889D01*
G02Y1600878I0J-1502D01*
G01X482489D01*
G37*
G36*
G01X494549D02*
G02Y1603882I0J1502D01*
G01X497949D01*
G02Y1600878I0J-1502D01*
G01X494549D01*
G37*
G36*
G01X506609D02*
G02Y1603882I0J1502D01*
G01X510009D01*
G02Y1600878I0J-1502D01*
G01X506609D01*
G37*
G36*
G01X518669D02*
G02Y1603882I0J1502D01*
G01X522069D01*
G02Y1600878I0J-1502D01*
G01X518669D01*
G37*
G36*
G01X530729D02*
G02Y1603882I0J1502D01*
G01X534129D01*
G02Y1600878I0J-1502D01*
G01X530729D01*
G37*
G36*
G01X542789D02*
G02Y1603882I0J1502D01*
G01X546189D01*
G02Y1600878I0J-1502D01*
G01X542789D01*
G37*
G36*
G01X554849D02*
G02Y1603882I0J1502D01*
G01X558249D01*
G02Y1600878I0J-1502D01*
G01X554849D01*
G37*
G36*
G01X566909D02*
G02Y1603882I0J1502D01*
G01X570309D01*
G02Y1600878I0J-1502D01*
G01X566909D01*
G37*
G36*
G01X578969D02*
G02Y1603882I0J1502D01*
G01X582369D01*
G02Y1600878I0J-1502D01*
G01X578969D01*
G37*
G36*
G01X591029D02*
G02Y1603882I0J1502D01*
G01X594429D01*
G02Y1600878I0J-1502D01*
G01X591029D01*
G37*
G36*
G01X603089D02*
G02Y1603882I0J1502D01*
G01X606489D01*
G02Y1600878I0J-1502D01*
G01X603089D01*
G37*
G36*
G01X615149D02*
G02Y1603882I0J1502D01*
G01X618549D01*
G02Y1600878I0J-1502D01*
G01X615149D01*
G37*
G36*
G01X627209D02*
G02Y1603882I0J1502D01*
G01X630609D01*
G02Y1600878I0J-1502D01*
G01X627209D01*
G37*
G36*
G01X639269D02*
G02Y1603882I0J1502D01*
G01X642669D01*
G02Y1600878I0J-1502D01*
G01X639269D01*
G37*
G36*
G01X1113847Y1603052D02*
G02Y1606056I0J1502D01*
G01X1117247D01*
G02Y1603052I0J-1502D01*
G01X1113847D01*
G37*
G36*
G01X789969Y1609735D02*
G03X790131I81J183D01*
G02X791550Y1610036I1421J-3202D01*
G02X795052Y1606533I-1J-3503D01*
G01Y1606531D01*
G02X794752Y1605114I-3502J1D01*
G03Y1604952I183J-81D01*
G02X795052Y1603533I-3202J-1418D01*
G02X794752Y1602114I-3502J-1D01*
G03Y1601952I183J-81D01*
G02X795052Y1600533I-3202J-1418D01*
G02X794752Y1599114I-3502J-1D01*
G03Y1598952I183J-81D01*
G02X795052Y1597533I-3202J-1418D01*
G02X794752Y1596114I-3502J-1D01*
G03Y1595952I183J-81D01*
G02X795052Y1594533I-3202J-1418D01*
G02X792832Y1591273I-3503J-1D01*
G01X792777Y1591252D01*
X792709Y1591159D01*
X792681Y1590740D01*
G03X792783Y1590552I200J-13D01*
G02X794580Y1587493I-1705J-3059D01*
G02X793656Y1585123I-3503J1D01*
G03X793603Y1584988I147J-136D01*
G01Y1584868D01*
G03X793656Y1584733I200J1D01*
G02X794580Y1582363I-2579J-2371D01*
G02X793656Y1579993I-3503J1D01*
G03X793603Y1579858I147J-136D01*
G01Y1579738D01*
G03X793656Y1579603I200J1D01*
G02X794580Y1577233I-2579J-2371D01*
G02X791077Y1573730I-3503J0D01*
G02X788609Y1574748I1J3503D01*
G01X788608Y1574749D01*
G03X788468Y1574806I-140J-143D01*
G01X788186D01*
G03X788046Y1574749I0J-200D01*
G01X788045Y1574748D01*
G02X785577Y1573730I-2469J2485D01*
G02X783064Y1574793I0J3502D01*
G03X782920Y1574854I-144J-139D01*
G01X782634D01*
G03X782490Y1574793I0J-200D01*
G02X779977Y1573730I-2513J2439D01*
G02X776474Y1577233I0J3503D01*
G02X777398Y1579603I3503J-1D01*
G03X777451Y1579738I-147J136D01*
G01Y1579858D01*
G03X777398Y1579993I-200J-1D01*
G02X776474Y1582363I2579J2371D01*
G02X777398Y1584733I3503J-1D01*
G03X777451Y1584868I-147J136D01*
G01Y1584988D01*
G03X777398Y1585123I-200J-1D01*
G02X776474Y1587493I2579J2371D01*
G02X778288Y1590561I3503J-1D01*
G03X778391Y1590748I-97J175D01*
G01X778370Y1591109D01*
G03X778244Y1591283I-200J-12D01*
G02X778131Y1591331I1313J3247D01*
G03X777969I-81J-183D01*
G02X776550Y1591030I-1421J3202D01*
G02X773048Y1594533I1J3503D01*
G01Y1594535D01*
G02X773348Y1595952I3502J-1D01*
G03Y1596114I-183J81D01*
G02X773048Y1597533I3202J1418D01*
G02X773348Y1598952I3502J1D01*
G03Y1599114I-183J81D01*
G02X773048Y1600533I3202J1418D01*
G02X773348Y1601952I3502J1D01*
G03Y1602114I-183J81D01*
G02X773048Y1603533I3202J1418D01*
G02X773348Y1604952I3502J1D01*
G03Y1605114I-183J81D01*
G02X773048Y1606533I3202J1418D01*
G02X776550Y1610036I3502J1D01*
G02X777969Y1609735I-2J-3503D01*
G03X778131I81J183D01*
G02X779550Y1610036I1421J-3202D01*
G02X780969Y1609735I-2J-3503D01*
G03X781131I81J183D01*
G02X782550Y1610036I1421J-3202D01*
G02X783969Y1609735I-2J-3503D01*
G03X784131I81J183D01*
G02X785550Y1610036I1421J-3202D01*
G02X786969Y1609735I-2J-3503D01*
G03X787131I81J183D01*
G02X788550Y1610036I1421J-3202D01*
G02X789969Y1609735I-2J-3503D01*
G37*
G36*
G01X834969D02*
G03X835131I81J183D01*
G02X836550Y1610036I1421J-3202D01*
G02X840052Y1606533I-1J-3503D01*
G01Y1606531D01*
G02X839752Y1605114I-3502J1D01*
G03Y1604952I183J-81D01*
G02X840052Y1603535I-3202J-1418D01*
G01Y1603533D01*
G02X837161Y1600084I-3503J0D01*
G03X836999Y1599922I35J-197D01*
G02X836752Y1599114I-3449J612D01*
G03Y1598952I183J-81D01*
G02X837052Y1597533I-3202J-1418D01*
G02X836752Y1596114I-3502J-1D01*
G03Y1595952I183J-81D01*
G02X837052Y1594533I-3202J-1418D01*
G02X834832Y1591273I-3503J-1D01*
G01X834777Y1591252D01*
X834709Y1591159D01*
X834681Y1590740D01*
G03X834783Y1590552I200J-13D01*
G02X836580Y1587493I-1705J-3059D01*
G02X835656Y1585123I-3503J1D01*
G03X835603Y1584988I147J-136D01*
G01Y1584868D01*
G03X835656Y1584733I200J1D01*
G02X836580Y1582363I-2579J-2371D01*
G02X835656Y1579993I-3503J1D01*
G03X835603Y1579858I147J-136D01*
G01Y1579738D01*
G03X835656Y1579603I200J1D01*
G02X836580Y1577233I-2579J-2371D01*
G02X833077Y1573730I-3503J0D01*
G02X830609Y1574748I1J3503D01*
G01X830608Y1574749D01*
G03X830468Y1574806I-140J-143D01*
G01X830186D01*
G03X830046Y1574749I0J-200D01*
G01X830045Y1574748D01*
G02X827577Y1573730I-2469J2485D01*
G02X825064Y1574793I0J3502D01*
G03X824920Y1574854I-144J-139D01*
G01X824634D01*
G03X824490Y1574793I0J-200D01*
G02X821977Y1573730I-2513J2439D01*
G02X818474Y1577233I0J3503D01*
G02X819398Y1579603I3503J-1D01*
G03X819451Y1579738I-147J136D01*
G01Y1579858D01*
G03X819398Y1579993I-200J-1D01*
G02X818474Y1582363I2579J2371D01*
G02X819398Y1584733I3503J-1D01*
G03X819451Y1584868I-147J136D01*
G01Y1584988D01*
G03X819398Y1585123I-200J-1D01*
G02X818474Y1587493I2579J2371D01*
G02X820288Y1590561I3503J-1D01*
G03X820391Y1590748I-97J175D01*
G01X820370Y1591109D01*
G03X820244Y1591283I-200J-12D01*
G02X818048Y1594533I1307J3250D01*
G01Y1594535D01*
G02X818348Y1595952I3502J-1D01*
G03Y1596114I-183J81D01*
G02X818048Y1597533I3202J1418D01*
G02X818348Y1598952I3502J1D01*
G03Y1599114I-183J81D01*
G02X818101Y1599922I3202J1420D01*
G03X817939Y1600084I-197J-35D01*
G02X815101Y1602922I611J3449D01*
G03X814939Y1603084I-197J-35D01*
G02X812048Y1606533I612J3449D01*
G01Y1606535D01*
G02X815550Y1610036I3502J-1D01*
G02X816969Y1609735I-2J-3503D01*
G03X817131I81J183D01*
G02X818550Y1610036I1421J-3202D01*
G02X819969Y1609735I-2J-3503D01*
G03X820131I81J183D01*
G02X821550Y1610036I1421J-3202D01*
G02X822969Y1609735I-2J-3503D01*
G03X823131I81J183D01*
G02X824550Y1610036I1421J-3202D01*
G02X825969Y1609735I-2J-3503D01*
G03X826131I81J183D01*
G02X827550Y1610036I1421J-3202D01*
G02X828969Y1609735I-2J-3503D01*
G03X829131I81J183D01*
G02X830550Y1610036I1421J-3202D01*
G02X831969Y1609735I-2J-3503D01*
G03X832131I81J183D01*
G02X833550Y1610036I1421J-3202D01*
G02X834969Y1609735I-2J-3503D01*
G37*
G36*
G01X876969D02*
G03X877131I81J183D01*
G02X878550Y1610036I1421J-3202D01*
G02X882052Y1606533I-1J-3503D01*
G01Y1606531D01*
G02X881752Y1605114I-3502J1D01*
G03Y1604952I183J-81D01*
G02X882052Y1603535I-3202J-1418D01*
G01Y1603533D01*
G02X879161Y1600084I-3503J0D01*
G03X878999Y1599922I35J-197D01*
G02X878752Y1599114I-3449J612D01*
G03Y1598952I183J-81D01*
G02X879052Y1597533I-3202J-1418D01*
G02X878752Y1596114I-3502J-1D01*
G03Y1595952I183J-81D01*
G02X879052Y1594533I-3202J-1418D01*
G02X876832Y1591273I-3503J-1D01*
G01X876777Y1591252D01*
X876709Y1591159D01*
X876681Y1590740D01*
G03X876783Y1590552I200J-13D01*
G02X878580Y1587493I-1705J-3059D01*
G02X877656Y1585123I-3503J1D01*
G03X877603Y1584988I147J-136D01*
G01Y1584868D01*
G03X877656Y1584733I200J1D01*
G02X878580Y1582363I-2579J-2371D01*
G02X877656Y1579993I-3503J1D01*
G03X877603Y1579858I147J-136D01*
G01Y1579738D01*
G03X877656Y1579603I200J1D01*
G02X878580Y1577233I-2579J-2371D01*
G02X875077Y1573730I-3503J0D01*
G02X872609Y1574748I1J3503D01*
G01X872608Y1574749D01*
G03X872468Y1574806I-140J-143D01*
G01X872186D01*
G03X872046Y1574749I0J-200D01*
G01X872045Y1574748D01*
G02X869577Y1573730I-2469J2485D01*
G02X867064Y1574793I0J3502D01*
G03X866920Y1574854I-144J-139D01*
G01X866634D01*
G03X866490Y1574793I0J-200D01*
G02X863977Y1573730I-2513J2439D01*
G02X860474Y1577233I0J3503D01*
G02X861398Y1579603I3503J-1D01*
G03X861451Y1579738I-147J136D01*
G01Y1579858D01*
G03X861398Y1579993I-200J-1D01*
G02X860474Y1582363I2579J2371D01*
G02X861398Y1584733I3503J-1D01*
G03X861451Y1584868I-147J136D01*
G01Y1584988D01*
G03X861398Y1585123I-200J-1D01*
G02X860474Y1587493I2579J2371D01*
G02X862288Y1590561I3503J-1D01*
G03X862391Y1590748I-97J175D01*
G01X862370Y1591109D01*
G03X862244Y1591283I-200J-12D01*
G02X860048Y1594533I1307J3250D01*
G01Y1594535D01*
G02X860348Y1595952I3502J-1D01*
G03Y1596114I-183J81D01*
G02X860048Y1597533I3202J1418D01*
G02X860348Y1598952I3502J1D01*
G03Y1599114I-183J81D01*
G02X860101Y1599922I3202J1420D01*
G03X859939Y1600084I-197J-35D01*
G02X857101Y1602922I611J3449D01*
G03X856939Y1603084I-197J-35D01*
G02X854048Y1606533I612J3449D01*
G01Y1606535D01*
G02X857550Y1610036I3502J-1D01*
G02X858969Y1609735I-2J-3503D01*
G03X859131I81J183D01*
G02X860550Y1610036I1421J-3202D01*
G02X861969Y1609735I-2J-3503D01*
G03X862131I81J183D01*
G02X863550Y1610036I1421J-3202D01*
G02X864969Y1609735I-2J-3503D01*
G03X865131I81J183D01*
G02X866550Y1610036I1421J-3202D01*
G02X867969Y1609735I-2J-3503D01*
G03X868131I81J183D01*
G02X869550Y1610036I1421J-3202D01*
G02X870969Y1609735I-2J-3503D01*
G03X871131I81J183D01*
G02X872550Y1610036I1421J-3202D01*
G02X873969Y1609735I-2J-3503D01*
G03X874131I81J183D01*
G02X875550Y1610036I1421J-3202D01*
G02X876969Y1609735I-2J-3503D01*
G37*
G36*
G01X918969D02*
G03X919131I81J183D01*
G02X920550Y1610036I1421J-3202D01*
G02X924052Y1606533I-1J-3503D01*
G01Y1606531D01*
G02X923752Y1605114I-3502J1D01*
G03Y1604952I183J-81D01*
G02X924052Y1603535I-3202J-1418D01*
G01Y1603533D01*
G02X921161Y1600084I-3503J0D01*
G03X920999Y1599922I35J-197D01*
G02X920752Y1599114I-3449J612D01*
G03Y1598952I183J-81D01*
G02X921052Y1597533I-3202J-1418D01*
G02X920752Y1596114I-3502J-1D01*
G03Y1595952I183J-81D01*
G02X921052Y1594533I-3202J-1418D01*
G02X918832Y1591273I-3503J-1D01*
G01X918777Y1591252D01*
X918709Y1591159D01*
X918681Y1590740D01*
G03X918783Y1590552I200J-13D01*
G02X920580Y1587493I-1705J-3059D01*
G02X919656Y1585123I-3503J1D01*
G03X919603Y1584988I147J-136D01*
G01Y1584868D01*
G03X919656Y1584733I200J1D01*
G02X920580Y1582363I-2579J-2371D01*
G02X919656Y1579993I-3503J1D01*
G03X919603Y1579858I147J-136D01*
G01Y1579738D01*
G03X919656Y1579603I200J1D01*
G02X920580Y1577233I-2579J-2371D01*
G02X917077Y1573730I-3503J0D01*
G02X914609Y1574748I1J3503D01*
G01X914608Y1574749D01*
G03X914468Y1574806I-140J-143D01*
G01X914186D01*
G03X914046Y1574749I0J-200D01*
G01X914045Y1574748D01*
G02X911577Y1573730I-2469J2485D01*
G02X909064Y1574793I0J3502D01*
G03X908920Y1574854I-144J-139D01*
G01X908634D01*
G03X908490Y1574793I0J-200D01*
G02X905977Y1573730I-2513J2439D01*
G02X902474Y1577233I0J3503D01*
G02X903398Y1579603I3503J-1D01*
G03X903451Y1579738I-147J136D01*
G01Y1579858D01*
G03X903398Y1579993I-200J-1D01*
G02X902474Y1582363I2579J2371D01*
G02X903398Y1584733I3503J-1D01*
G03X903451Y1584868I-147J136D01*
G01Y1584988D01*
G03X903398Y1585123I-200J-1D01*
G02X902474Y1587493I2579J2371D01*
G02X904288Y1590561I3503J-1D01*
G03X904391Y1590748I-97J175D01*
G01X904370Y1591109D01*
G03X904244Y1591283I-200J-12D01*
G02X902048Y1594533I1307J3250D01*
G01Y1594535D01*
G02X902348Y1595952I3502J-1D01*
G03Y1596114I-183J81D01*
G02X902048Y1597533I3202J1418D01*
G02X902348Y1598952I3502J1D01*
G03Y1599114I-183J81D01*
G02X902101Y1599922I3202J1420D01*
G03X901939Y1600084I-197J-35D01*
G02X899101Y1602922I611J3449D01*
G03X898939Y1603084I-197J-35D01*
G02X896048Y1606533I612J3449D01*
G01Y1606535D01*
G02X899550Y1610036I3502J-1D01*
G02X900969Y1609735I-2J-3503D01*
G03X901131I81J183D01*
G02X902550Y1610036I1421J-3202D01*
G02X903969Y1609735I-2J-3503D01*
G03X904131I81J183D01*
G02X905550Y1610036I1421J-3202D01*
G02X906969Y1609735I-2J-3503D01*
G03X907131I81J183D01*
G02X908550Y1610036I1421J-3202D01*
G02X909969Y1609735I-2J-3503D01*
G03X910131I81J183D01*
G02X911550Y1610036I1421J-3202D01*
G02X912969Y1609735I-2J-3503D01*
G03X913131I81J183D01*
G02X914550Y1610036I1421J-3202D01*
G02X915969Y1609735I-2J-3503D01*
G03X916131I81J183D01*
G02X917550Y1610036I1421J-3202D01*
G02X918969Y1609735I-2J-3503D01*
G37*
G36*
G01X744417Y1609865D02*
G03X744579I81J183D01*
G02X745998Y1610166I1421J-3202D01*
G02X749500Y1606663I-1J-3503D01*
G01Y1606661D01*
G02X749200Y1605244I-3502J1D01*
G03Y1605082I183J-81D01*
G02X749500Y1603663I-3202J-1418D01*
G02X749157Y1602149I-3502J-2D01*
G03Y1601977I180J-86D01*
G02X749500Y1600463I-3159J-1512D01*
G02X749200Y1599044I-3502J-1D01*
G03Y1598882I183J-81D01*
G02X749500Y1597463I-3202J-1418D01*
G02X749200Y1596044I-3502J-1D01*
G03Y1595882I183J-81D01*
G02X749500Y1594463I-3202J-1418D01*
G02X745998Y1590960I-3502J-1D01*
G02X744579Y1591261I2J3503D01*
G03X744417I-81J-183D01*
G02X742998Y1590960I-1421J3202D01*
G02X741579Y1591261I2J3503D01*
G03X741417I-81J-183D01*
G02X740970Y1591098I-1421J3201D01*
G01X740913Y1591082D01*
X740837Y1590996D01*
X740770Y1590580D01*
G03X740855Y1590383I198J-32D01*
G02X742382Y1587491I-1975J-2892D01*
G02X741459Y1585121I-3504J0D01*
G03X741406Y1584986I147J-136D01*
G01Y1584866D01*
G03X741459Y1584731I200J1D01*
G02Y1579991I-2580J-2370D01*
G03X741406Y1579856I147J-136D01*
G01Y1579736D01*
G03X741459Y1579601I200J1D01*
G02X742382Y1577231I-2581J-2370D01*
G01Y1577229D01*
G02X738880Y1573728I-3502J1D01*
G02X736412Y1574746I1J3503D01*
G01X736411Y1574747D01*
G03X736271Y1574804I-140J-143D01*
G01X735989D01*
G03X735849Y1574747I0J-200D01*
G01X735848Y1574746D01*
G02X733380Y1573728I-2469J2485D01*
G02X730867Y1574791I0J3502D01*
G03X730723Y1574852I-144J-139D01*
G01X730437D01*
G03X730293Y1574791I0J-200D01*
G02X727780Y1573728I-2513J2439D01*
G02X724278Y1577231I1J3503D01*
G02X725201Y1579601I3504J0D01*
G03X725254Y1579736I-147J136D01*
G01Y1579856D01*
G03X725201Y1579991I-200J-1D01*
G02Y1584731I2580J2370D01*
G03X725254Y1584866I-147J136D01*
G01Y1584986D01*
G03X725201Y1585121I-200J-1D01*
G02X724278Y1587491I2581J2370D01*
G01Y1587493D01*
G02X727780Y1590994I3502J-1D01*
G02X730293Y1589931I0J-3502D01*
G03X730437Y1589870I144J139D01*
G01X730723D01*
G03X730867Y1589931I0J200D01*
G02X731217Y1590246I2513J-2440D01*
G03X731283Y1590468I-123J157D01*
G01X731161Y1590826D01*
G03X730973Y1590961I-189J-65D01*
G02X727496Y1594463I25J3502D01*
G01Y1594465D01*
G02X727796Y1595882I3502J-1D01*
G03Y1596044I-183J81D01*
G02X727496Y1597463I3202J1418D01*
G02X727796Y1598882I3502J1D01*
G03Y1599044I-183J81D01*
G02X727496Y1600463I3202J1418D01*
G02X727839Y1601977I3502J2D01*
G03Y1602149I-180J86D01*
G02X727496Y1603663I3159J1512D01*
G02X727796Y1605082I3502J1D01*
G03Y1605244I-183J81D01*
G02X727496Y1606663I3202J1418D01*
G02X730998Y1610166I3502J1D01*
G02X732417Y1609865I-2J-3503D01*
G03X732579I81J183D01*
G02X733998Y1610166I1421J-3202D01*
G02X735417Y1609865I-2J-3503D01*
G03X735579I81J183D01*
G02X736998Y1610166I1421J-3202D01*
G02X738417Y1609865I-2J-3503D01*
G03X738579I81J183D01*
G02X739998Y1610166I1421J-3202D01*
G02X741417Y1609865I-2J-3503D01*
G03X741579I81J183D01*
G02X742998Y1610166I1421J-3202D01*
G02X744417Y1609865I-2J-3503D01*
G37*
G36*
G01X194196Y1612790D02*
G02Y1615794I0J1502D01*
G01X197596D01*
G02Y1612790I0J-1502D01*
G01X194196D01*
G37*
G36*
G01X206256D02*
G02Y1615794I0J1502D01*
G01X209656D01*
G02Y1612790I0J-1502D01*
G01X206256D01*
G37*
G36*
G01X218316D02*
G02Y1615794I0J1502D01*
G01X221716D01*
G02Y1612790I0J-1502D01*
G01X218316D01*
G37*
G36*
G01X230376D02*
G02Y1615794I0J1502D01*
G01X233776D01*
G02Y1612790I0J-1502D01*
G01X230376D01*
G37*
G36*
G01X242436D02*
G02Y1615794I0J1502D01*
G01X245836D01*
G02Y1612790I0J-1502D01*
G01X242436D01*
G37*
G36*
G01X254496D02*
G02Y1615794I0J1502D01*
G01X257896D01*
G02Y1612790I0J-1502D01*
G01X254496D01*
G37*
G36*
G01X266556D02*
G02Y1615794I0J1502D01*
G01X269956D01*
G02Y1612790I0J-1502D01*
G01X266556D01*
G37*
G36*
G01X278616D02*
G02Y1615794I0J1502D01*
G01X282016D01*
G02Y1612790I0J-1502D01*
G01X278616D01*
G37*
G36*
G01X290676D02*
G02Y1615794I0J1502D01*
G01X294076D01*
G02Y1612790I0J-1502D01*
G01X290676D01*
G37*
G36*
G01X302736D02*
G02Y1615794I0J1502D01*
G01X306136D01*
G02Y1612790I0J-1502D01*
G01X302736D01*
G37*
G36*
G01X314796D02*
G02Y1615794I0J1502D01*
G01X318196D01*
G02Y1612790I0J-1502D01*
G01X314796D01*
G37*
G36*
G01X326856D02*
G02Y1615794I0J1502D01*
G01X330256D01*
G02Y1612790I0J-1502D01*
G01X326856D01*
G37*
G36*
G01X338916D02*
G02Y1615794I0J1502D01*
G01X342316D01*
G02Y1612790I0J-1502D01*
G01X338916D01*
G37*
G36*
G01X350976D02*
G02Y1615794I0J1502D01*
G01X354376D01*
G02Y1612790I0J-1502D01*
G01X350976D01*
G37*
G36*
G01X363036D02*
G02Y1615794I0J1502D01*
G01X366436D01*
G02Y1612790I0J-1502D01*
G01X363036D01*
G37*
G36*
G01X375096D02*
G02Y1615794I0J1502D01*
G01X378496D01*
G02Y1612790I0J-1502D01*
G01X375096D01*
G37*
G36*
G01X458369D02*
G02Y1615794I0J1502D01*
G01X461769D01*
G02Y1612790I0J-1502D01*
G01X458369D01*
G37*
G36*
G01X470429D02*
G02Y1615794I0J1502D01*
G01X473829D01*
G02Y1612790I0J-1502D01*
G01X470429D01*
G37*
G36*
G01X482489D02*
G02Y1615794I0J1502D01*
G01X485889D01*
G02Y1612790I0J-1502D01*
G01X482489D01*
G37*
G36*
G01X494549D02*
G02Y1615794I0J1502D01*
G01X497949D01*
G02Y1612790I0J-1502D01*
G01X494549D01*
G37*
G36*
G01X506609D02*
G02Y1615794I0J1502D01*
G01X510009D01*
G02Y1612790I0J-1502D01*
G01X506609D01*
G37*
G36*
G01X518669D02*
G02Y1615794I0J1502D01*
G01X522069D01*
G02Y1612790I0J-1502D01*
G01X518669D01*
G37*
G36*
G01X530729D02*
G02Y1615794I0J1502D01*
G01X534129D01*
G02Y1612790I0J-1502D01*
G01X530729D01*
G37*
G36*
G01X542789D02*
G02Y1615794I0J1502D01*
G01X546189D01*
G02Y1612790I0J-1502D01*
G01X542789D01*
G37*
G36*
G01X554849D02*
G02Y1615794I0J1502D01*
G01X558249D01*
G02Y1612790I0J-1502D01*
G01X554849D01*
G37*
G36*
G01X566909D02*
G02Y1615794I0J1502D01*
G01X570309D01*
G02Y1612790I0J-1502D01*
G01X566909D01*
G37*
G36*
G01X578969D02*
G02Y1615794I0J1502D01*
G01X582369D01*
G02Y1612790I0J-1502D01*
G01X578969D01*
G37*
G36*
G01X591029D02*
G02Y1615794I0J1502D01*
G01X594429D01*
G02Y1612790I0J-1502D01*
G01X591029D01*
G37*
G36*
G01X603089D02*
G02Y1615794I0J1502D01*
G01X606489D01*
G02Y1612790I0J-1502D01*
G01X603089D01*
G37*
G36*
G01X615149D02*
G02Y1615794I0J1502D01*
G01X618549D01*
G02Y1612790I0J-1502D01*
G01X615149D01*
G37*
G36*
G01X627209D02*
G02Y1615794I0J1502D01*
G01X630609D01*
G02Y1612790I0J-1502D01*
G01X627209D01*
G37*
G36*
G01X639269D02*
G02Y1615794I0J1502D01*
G01X642669D01*
G02Y1612790I0J-1502D01*
G01X639269D01*
G37*
G36*
G01X188166Y1622790D02*
G02Y1625794I0J1502D01*
G01X191566D01*
G02Y1622790I0J-1502D01*
G01X188166D01*
G37*
G36*
G01X200226D02*
G02Y1625794I0J1502D01*
G01X203626D01*
G02Y1622790I0J-1502D01*
G01X200226D01*
G37*
G36*
G01X212286D02*
G02Y1625794I0J1502D01*
G01X215686D01*
G02Y1622790I0J-1502D01*
G01X212286D01*
G37*
G36*
G01X224346D02*
G02Y1625794I0J1502D01*
G01X227746D01*
G02Y1622790I0J-1502D01*
G01X224346D01*
G37*
G36*
G01X236406D02*
G02Y1625794I0J1502D01*
G01X239806D01*
G02Y1622790I0J-1502D01*
G01X236406D01*
G37*
G36*
G01X248466D02*
G02Y1625794I0J1502D01*
G01X251866D01*
G02Y1622790I0J-1502D01*
G01X248466D01*
G37*
G36*
G01X260526D02*
G02Y1625794I0J1502D01*
G01X263926D01*
G02Y1622790I0J-1502D01*
G01X260526D01*
G37*
G36*
G01X272586D02*
G02Y1625794I0J1502D01*
G01X275986D01*
G02Y1622790I0J-1502D01*
G01X272586D01*
G37*
G36*
G01X284646D02*
G02Y1625794I0J1502D01*
G01X288046D01*
G02Y1622790I0J-1502D01*
G01X284646D01*
G37*
G36*
G01X296706D02*
G02Y1625794I0J1502D01*
G01X300106D01*
G02Y1622790I0J-1502D01*
G01X296706D01*
G37*
G36*
G01X308766D02*
G02Y1625794I0J1502D01*
G01X312166D01*
G02Y1622790I0J-1502D01*
G01X308766D01*
G37*
G36*
G01X320826D02*
G02Y1625794I0J1502D01*
G01X324226D01*
G02Y1622790I0J-1502D01*
G01X320826D01*
G37*
G36*
G01X332886D02*
G02Y1625794I0J1502D01*
G01X336286D01*
G02Y1622790I0J-1502D01*
G01X332886D01*
G37*
G36*
G01X344946D02*
G02Y1625794I0J1502D01*
G01X348346D01*
G02Y1622790I0J-1502D01*
G01X344946D01*
G37*
G36*
G01X357006D02*
G02Y1625794I0J1502D01*
G01X360406D01*
G02Y1622790I0J-1502D01*
G01X357006D01*
G37*
G36*
G01X369066D02*
G02Y1625794I0J1502D01*
G01X372466D01*
G02Y1622790I0J-1502D01*
G01X369066D01*
G37*
G36*
G01X452339D02*
G02Y1625794I0J1502D01*
G01X455739D01*
G02Y1622790I0J-1502D01*
G01X452339D01*
G37*
G36*
G01X464399D02*
G02Y1625794I0J1502D01*
G01X467799D01*
G02Y1622790I0J-1502D01*
G01X464399D01*
G37*
G36*
G01X476459D02*
G02Y1625794I0J1502D01*
G01X479859D01*
G02Y1622790I0J-1502D01*
G01X476459D01*
G37*
G36*
G01X488519D02*
G02Y1625794I0J1502D01*
G01X491919D01*
G02Y1622790I0J-1502D01*
G01X488519D01*
G37*
G36*
G01X500579D02*
G02Y1625794I0J1502D01*
G01X503979D01*
G02Y1622790I0J-1502D01*
G01X500579D01*
G37*
G36*
G01X512639D02*
G02Y1625794I0J1502D01*
G01X516039D01*
G02Y1622790I0J-1502D01*
G01X512639D01*
G37*
G36*
G01X524699D02*
G02Y1625794I0J1502D01*
G01X528099D01*
G02Y1622790I0J-1502D01*
G01X524699D01*
G37*
G36*
G01X536759D02*
G02Y1625794I0J1502D01*
G01X540159D01*
G02Y1622790I0J-1502D01*
G01X536759D01*
G37*
G36*
G01X548819D02*
G02Y1625794I0J1502D01*
G01X552219D01*
G02Y1622790I0J-1502D01*
G01X548819D01*
G37*
G36*
G01X560879D02*
G02Y1625794I0J1502D01*
G01X564279D01*
G02Y1622790I0J-1502D01*
G01X560879D01*
G37*
G36*
G01X572939D02*
G02Y1625794I0J1502D01*
G01X576339D01*
G02Y1622790I0J-1502D01*
G01X572939D01*
G37*
G36*
G01X584999D02*
G02Y1625794I0J1502D01*
G01X588399D01*
G02Y1622790I0J-1502D01*
G01X584999D01*
G37*
G36*
G01X597059D02*
G02Y1625794I0J1502D01*
G01X600459D01*
G02Y1622790I0J-1502D01*
G01X597059D01*
G37*
G36*
G01X609119D02*
G02Y1625794I0J1502D01*
G01X612519D01*
G02Y1622790I0J-1502D01*
G01X609119D01*
G37*
G36*
G01X621179D02*
G02Y1625794I0J1502D01*
G01X624579D01*
G02Y1622790I0J-1502D01*
G01X621179D01*
G37*
G36*
G01X633239D02*
G02Y1625794I0J1502D01*
G01X636639D01*
G02Y1622790I0J-1502D01*
G01X633239D01*
G37*
G36*
G01X1196039Y1623878D02*
G02Y1626882I0J1502D01*
G01X1199439D01*
G02Y1623878I0J-1502D01*
G01X1196039D01*
G37*
G36*
G01X1208099D02*
G02Y1626882I0J1502D01*
G01X1211499D01*
G02Y1623878I0J-1502D01*
G01X1208099D01*
G37*
G36*
G01X1220159D02*
G02Y1626882I0J1502D01*
G01X1223559D01*
G02Y1623878I0J-1502D01*
G01X1220159D01*
G37*
G36*
G01X1232219D02*
G02Y1626882I0J1502D01*
G01X1235619D01*
G02Y1623878I0J-1502D01*
G01X1232219D01*
G37*
G36*
G01X1244279D02*
G02Y1626882I0J1502D01*
G01X1247679D01*
G02Y1623878I0J-1502D01*
G01X1244279D01*
G37*
G36*
G01X1256339D02*
G02Y1626882I0J1502D01*
G01X1259739D01*
G02Y1623878I0J-1502D01*
G01X1256339D01*
G37*
G36*
G01X1268399D02*
G02Y1626882I0J1502D01*
G01X1271799D01*
G02Y1623878I0J-1502D01*
G01X1268399D01*
G37*
G36*
G01X1280459D02*
G02Y1626882I0J1502D01*
G01X1283859D01*
G02Y1623878I0J-1502D01*
G01X1280459D01*
G37*
G36*
G01X1292519D02*
G02Y1626882I0J1502D01*
G01X1295919D01*
G02Y1623878I0J-1502D01*
G01X1292519D01*
G37*
G36*
G01X1304579D02*
G02Y1626882I0J1502D01*
G01X1307979D01*
G02Y1623878I0J-1502D01*
G01X1304579D01*
G37*
G36*
G01X1316639D02*
G02Y1626882I0J1502D01*
G01X1320039D01*
G02Y1623878I0J-1502D01*
G01X1316639D01*
G37*
G36*
G01X1328699D02*
G02Y1626882I0J1502D01*
G01X1332099D01*
G02Y1623878I0J-1502D01*
G01X1328699D01*
G37*
G36*
G01X1340759D02*
G02Y1626882I0J1502D01*
G01X1344159D01*
G02Y1623878I0J-1502D01*
G01X1340759D01*
G37*
G36*
G01X1352819D02*
G02Y1626882I0J1502D01*
G01X1356219D01*
G02Y1623878I0J-1502D01*
G01X1352819D01*
G37*
G36*
G01X1364879D02*
G02Y1626882I0J1502D01*
G01X1368279D01*
G02Y1623878I0J-1502D01*
G01X1364879D01*
G37*
G36*
G01X1376939D02*
G02Y1626882I0J1502D01*
G01X1380339D01*
G02Y1623878I0J-1502D01*
G01X1376939D01*
G37*
G36*
G01X1460213D02*
G02Y1626882I0J1502D01*
G01X1463613D01*
G02Y1623878I0J-1502D01*
G01X1460213D01*
G37*
G36*
G01X1472273D02*
G02Y1626882I0J1502D01*
G01X1475673D01*
G02Y1623878I0J-1502D01*
G01X1472273D01*
G37*
G36*
G01X1484333D02*
G02Y1626882I0J1502D01*
G01X1487733D01*
G02Y1623878I0J-1502D01*
G01X1484333D01*
G37*
G36*
G01X1496393D02*
G02Y1626882I0J1502D01*
G01X1499793D01*
G02Y1623878I0J-1502D01*
G01X1496393D01*
G37*
G36*
G01X1508453D02*
G02Y1626882I0J1502D01*
G01X1511853D01*
G02Y1623878I0J-1502D01*
G01X1508453D01*
G37*
G36*
G01X1520513D02*
G02Y1626882I0J1502D01*
G01X1523913D01*
G02Y1623878I0J-1502D01*
G01X1520513D01*
G37*
G36*
G01X1532573D02*
G02Y1626882I0J1502D01*
G01X1535973D01*
G02Y1623878I0J-1502D01*
G01X1532573D01*
G37*
G36*
G01X1544633D02*
G02Y1626882I0J1502D01*
G01X1548033D01*
G02Y1623878I0J-1502D01*
G01X1544633D01*
G37*
G36*
G01X1556693D02*
G02Y1626882I0J1502D01*
G01X1560093D01*
G02Y1623878I0J-1502D01*
G01X1556693D01*
G37*
G36*
G01X1568753D02*
G02Y1626882I0J1502D01*
G01X1572153D01*
G02Y1623878I0J-1502D01*
G01X1568753D01*
G37*
G36*
G01X1580813D02*
G02Y1626882I0J1502D01*
G01X1584213D01*
G02Y1623878I0J-1502D01*
G01X1580813D01*
G37*
G36*
G01X1592873D02*
G02Y1626882I0J1502D01*
G01X1596273D01*
G02Y1623878I0J-1502D01*
G01X1592873D01*
G37*
G36*
G01X1604933D02*
G02Y1626882I0J1502D01*
G01X1608333D01*
G02Y1623878I0J-1502D01*
G01X1604933D01*
G37*
G36*
G01X1616993D02*
G02Y1626882I0J1502D01*
G01X1620393D01*
G02Y1623878I0J-1502D01*
G01X1616993D01*
G37*
G36*
G01X1629053D02*
G02Y1626882I0J1502D01*
G01X1632453D01*
G02Y1623878I0J-1502D01*
G01X1629053D01*
G37*
G36*
G01X1641113D02*
G02Y1626882I0J1502D01*
G01X1644513D01*
G02Y1623878I0J-1502D01*
G01X1641113D01*
G37*
G36*
G01X417365Y1626192D02*
G02Y1629198I0J1503D01*
G01X420765D01*
G02Y1626192I0J-1503D01*
G01X417365D01*
G37*
G36*
G01X1202069Y1633878D02*
G02Y1636882I0J1502D01*
G01X1205469D01*
G02Y1633878I0J-1502D01*
G01X1202069D01*
G37*
G36*
G01X1214129D02*
G02Y1636882I0J1502D01*
G01X1217529D01*
G02Y1633878I0J-1502D01*
G01X1214129D01*
G37*
G36*
G01X1226189D02*
G02Y1636882I0J1502D01*
G01X1229589D01*
G02Y1633878I0J-1502D01*
G01X1226189D01*
G37*
G36*
G01X1238249D02*
G02Y1636882I0J1502D01*
G01X1241649D01*
G02Y1633878I0J-1502D01*
G01X1238249D01*
G37*
G36*
G01X1250309D02*
G02Y1636882I0J1502D01*
G01X1253709D01*
G02Y1633878I0J-1502D01*
G01X1250309D01*
G37*
G36*
G01X1262369D02*
G02Y1636882I0J1502D01*
G01X1265769D01*
G02Y1633878I0J-1502D01*
G01X1262369D01*
G37*
G36*
G01X1274429D02*
G02Y1636882I0J1502D01*
G01X1277829D01*
G02Y1633878I0J-1502D01*
G01X1274429D01*
G37*
G36*
G01X1286489D02*
G02Y1636882I0J1502D01*
G01X1289889D01*
G02Y1633878I0J-1502D01*
G01X1286489D01*
G37*
G36*
G01X1298549D02*
G02Y1636882I0J1502D01*
G01X1301949D01*
G02Y1633878I0J-1502D01*
G01X1298549D01*
G37*
G36*
G01X1310609D02*
G02Y1636882I0J1502D01*
G01X1314009D01*
G02Y1633878I0J-1502D01*
G01X1310609D01*
G37*
G36*
G01X1322669D02*
G02Y1636882I0J1502D01*
G01X1326069D01*
G02Y1633878I0J-1502D01*
G01X1322669D01*
G37*
G36*
G01X1334729D02*
G02Y1636882I0J1502D01*
G01X1338129D01*
G02Y1633878I0J-1502D01*
G01X1334729D01*
G37*
G36*
G01X1346789D02*
G02Y1636882I0J1502D01*
G01X1350189D01*
G02Y1633878I0J-1502D01*
G01X1346789D01*
G37*
G36*
G01X1358849D02*
G02Y1636882I0J1502D01*
G01X1362249D01*
G02Y1633878I0J-1502D01*
G01X1358849D01*
G37*
G36*
G01X1370909D02*
G02Y1636882I0J1502D01*
G01X1374309D01*
G02Y1633878I0J-1502D01*
G01X1370909D01*
G37*
G36*
G01X1382969D02*
G02Y1636882I0J1502D01*
G01X1386369D01*
G02Y1633878I0J-1502D01*
G01X1382969D01*
G37*
G36*
G01X1466243D02*
G02Y1636882I0J1502D01*
G01X1469643D01*
G02Y1633878I0J-1502D01*
G01X1466243D01*
G37*
G36*
G01X1478303D02*
G02Y1636882I0J1502D01*
G01X1481703D01*
G02Y1633878I0J-1502D01*
G01X1478303D01*
G37*
G36*
G01X1490363D02*
G02Y1636882I0J1502D01*
G01X1493763D01*
G02Y1633878I0J-1502D01*
G01X1490363D01*
G37*
G36*
G01X1502423D02*
G02Y1636882I0J1502D01*
G01X1505823D01*
G02Y1633878I0J-1502D01*
G01X1502423D01*
G37*
G36*
G01X1514483D02*
G02Y1636882I0J1502D01*
G01X1517883D01*
G02Y1633878I0J-1502D01*
G01X1514483D01*
G37*
G36*
G01X1526543D02*
G02Y1636882I0J1502D01*
G01X1529943D01*
G02Y1633878I0J-1502D01*
G01X1526543D01*
G37*
G36*
G01X1538603D02*
G02Y1636882I0J1502D01*
G01X1542003D01*
G02Y1633878I0J-1502D01*
G01X1538603D01*
G37*
G36*
G01X1550663D02*
G02Y1636882I0J1502D01*
G01X1554063D01*
G02Y1633878I0J-1502D01*
G01X1550663D01*
G37*
G36*
G01X1562723D02*
G02Y1636882I0J1502D01*
G01X1566123D01*
G02Y1633878I0J-1502D01*
G01X1562723D01*
G37*
G36*
G01X1574783D02*
G02Y1636882I0J1502D01*
G01X1578183D01*
G02Y1633878I0J-1502D01*
G01X1574783D01*
G37*
G36*
G01X1586843D02*
G02Y1636882I0J1502D01*
G01X1590243D01*
G02Y1633878I0J-1502D01*
G01X1586843D01*
G37*
G36*
G01X1598903D02*
G02Y1636882I0J1502D01*
G01X1602303D01*
G02Y1633878I0J-1502D01*
G01X1598903D01*
G37*
G36*
G01X1610963D02*
G02Y1636882I0J1502D01*
G01X1614363D01*
G02Y1633878I0J-1502D01*
G01X1610963D01*
G37*
G36*
G01X1623023D02*
G02Y1636882I0J1502D01*
G01X1626423D01*
G02Y1633878I0J-1502D01*
G01X1623023D01*
G37*
G36*
G01X1635083D02*
G02Y1636882I0J1502D01*
G01X1638483D01*
G02Y1633878I0J-1502D01*
G01X1635083D01*
G37*
G36*
G01X1647143D02*
G02Y1636882I0J1502D01*
G01X1650543D01*
G02Y1633878I0J-1502D01*
G01X1647143D01*
G37*
G36*
G01X1202069Y1645790D02*
G02Y1648794I0J1502D01*
G01X1205469D01*
G02Y1645790I0J-1502D01*
G01X1202069D01*
G37*
G36*
G01X1214129D02*
G02Y1648794I0J1502D01*
G01X1217529D01*
G02Y1645790I0J-1502D01*
G01X1214129D01*
G37*
G36*
G01X1226189D02*
G02Y1648794I0J1502D01*
G01X1229589D01*
G02Y1645790I0J-1502D01*
G01X1226189D01*
G37*
G36*
G01X1238249D02*
G02Y1648794I0J1502D01*
G01X1241649D01*
G02Y1645790I0J-1502D01*
G01X1238249D01*
G37*
G36*
G01X1250309D02*
G02Y1648794I0J1502D01*
G01X1253709D01*
G02Y1645790I0J-1502D01*
G01X1250309D01*
G37*
G36*
G01X1262369D02*
G02Y1648794I0J1502D01*
G01X1265769D01*
G02Y1645790I0J-1502D01*
G01X1262369D01*
G37*
G36*
G01X1274429D02*
G02Y1648794I0J1502D01*
G01X1277829D01*
G02Y1645790I0J-1502D01*
G01X1274429D01*
G37*
G36*
G01X1286489D02*
G02Y1648794I0J1502D01*
G01X1289889D01*
G02Y1645790I0J-1502D01*
G01X1286489D01*
G37*
G36*
G01X1298549D02*
G02Y1648794I0J1502D01*
G01X1301949D01*
G02Y1645790I0J-1502D01*
G01X1298549D01*
G37*
G36*
G01X1310609D02*
G02Y1648794I0J1502D01*
G01X1314009D01*
G02Y1645790I0J-1502D01*
G01X1310609D01*
G37*
G36*
G01X1322669D02*
G02Y1648794I0J1502D01*
G01X1326069D01*
G02Y1645790I0J-1502D01*
G01X1322669D01*
G37*
G36*
G01X1334729D02*
G02Y1648794I0J1502D01*
G01X1338129D01*
G02Y1645790I0J-1502D01*
G01X1334729D01*
G37*
G36*
G01X1346789D02*
G02Y1648794I0J1502D01*
G01X1350189D01*
G02Y1645790I0J-1502D01*
G01X1346789D01*
G37*
G36*
G01X1358849D02*
G02Y1648794I0J1502D01*
G01X1362249D01*
G02Y1645790I0J-1502D01*
G01X1358849D01*
G37*
G36*
G01X1370909D02*
G02Y1648794I0J1502D01*
G01X1374309D01*
G02Y1645790I0J-1502D01*
G01X1370909D01*
G37*
G36*
G01X1382969D02*
G02Y1648794I0J1502D01*
G01X1386369D01*
G02Y1645790I0J-1502D01*
G01X1382969D01*
G37*
G36*
G01X1466243D02*
G02Y1648794I0J1502D01*
G01X1469643D01*
G02Y1645790I0J-1502D01*
G01X1466243D01*
G37*
G36*
G01X1478303D02*
G02Y1648794I0J1502D01*
G01X1481703D01*
G02Y1645790I0J-1502D01*
G01X1478303D01*
G37*
G36*
G01X1490363D02*
G02Y1648794I0J1502D01*
G01X1493763D01*
G02Y1645790I0J-1502D01*
G01X1490363D01*
G37*
G36*
G01X1502423D02*
G02Y1648794I0J1502D01*
G01X1505823D01*
G02Y1645790I0J-1502D01*
G01X1502423D01*
G37*
G36*
G01X1514483D02*
G02Y1648794I0J1502D01*
G01X1517883D01*
G02Y1645790I0J-1502D01*
G01X1514483D01*
G37*
G36*
G01X1526543D02*
G02Y1648794I0J1502D01*
G01X1529943D01*
G02Y1645790I0J-1502D01*
G01X1526543D01*
G37*
G36*
G01X1538603D02*
G02Y1648794I0J1502D01*
G01X1542003D01*
G02Y1645790I0J-1502D01*
G01X1538603D01*
G37*
G36*
G01X1550663D02*
G02Y1648794I0J1502D01*
G01X1554063D01*
G02Y1645790I0J-1502D01*
G01X1550663D01*
G37*
G36*
G01X1562723D02*
G02Y1648794I0J1502D01*
G01X1566123D01*
G02Y1645790I0J-1502D01*
G01X1562723D01*
G37*
G36*
G01X1574783D02*
G02Y1648794I0J1502D01*
G01X1578183D01*
G02Y1645790I0J-1502D01*
G01X1574783D01*
G37*
G36*
G01X1586843D02*
G02Y1648794I0J1502D01*
G01X1590243D01*
G02Y1645790I0J-1502D01*
G01X1586843D01*
G37*
G36*
G01X1598903D02*
G02Y1648794I0J1502D01*
G01X1602303D01*
G02Y1645790I0J-1502D01*
G01X1598903D01*
G37*
G36*
G01X1610963D02*
G02Y1648794I0J1502D01*
G01X1614363D01*
G02Y1645790I0J-1502D01*
G01X1610963D01*
G37*
G36*
G01X1623023D02*
G02Y1648794I0J1502D01*
G01X1626423D01*
G02Y1645790I0J-1502D01*
G01X1623023D01*
G37*
G36*
G01X1635083D02*
G02Y1648794I0J1502D01*
G01X1638483D01*
G02Y1645790I0J-1502D01*
G01X1635083D01*
G37*
G36*
G01X1647143D02*
G02Y1648794I0J1502D01*
G01X1650543D01*
G02Y1645790I0J-1502D01*
G01X1647143D01*
G37*
G36*
G01X228902Y1656537D02*
G02X229205Y1656840I303J0D01*
G01X232905D01*
G02X233208Y1656537I0J-303D01*
G01Y1646531D01*
G02X232905Y1646228I-303J0D01*
G01X229205D01*
G02X228902Y1646531I0J303D01*
G01Y1656537D01*
G37*
G36*
G01X276146D02*
G02X276449Y1656840I303J0D01*
G01X280149D01*
G02X280452Y1656537I0J-303D01*
G01Y1646531D01*
G02X280149Y1646228I-303J0D01*
G01X276449D01*
G02X276146Y1646531I0J303D01*
G01Y1656537D01*
G37*
G36*
G01X382478Y1657961D02*
G02X382681Y1658164I203J0D01*
G01X401967D01*
G02X402170Y1657961I0J-203D01*
G01Y1631213D01*
G02X401967Y1631010I-203J0D01*
G01X382681D01*
G02X382478Y1631213I0J203D01*
G01Y1657961D01*
G37*
G36*
G01X1196039Y1655790D02*
G02Y1658794I0J1502D01*
G01X1199439D01*
G02Y1655790I0J-1502D01*
G01X1196039D01*
G37*
G36*
G01X1208099D02*
G02Y1658794I0J1502D01*
G01X1211499D01*
G02Y1655790I0J-1502D01*
G01X1208099D01*
G37*
G36*
G01X1220159D02*
G02Y1658794I0J1502D01*
G01X1223559D01*
G02Y1655790I0J-1502D01*
G01X1220159D01*
G37*
G36*
G01X1232219D02*
G02Y1658794I0J1502D01*
G01X1235619D01*
G02Y1655790I0J-1502D01*
G01X1232219D01*
G37*
G36*
G01X1244279D02*
G02Y1658794I0J1502D01*
G01X1247679D01*
G02Y1655790I0J-1502D01*
G01X1244279D01*
G37*
G36*
G01X1256339D02*
G02Y1658794I0J1502D01*
G01X1259739D01*
G02Y1655790I0J-1502D01*
G01X1256339D01*
G37*
G36*
G01X1268399D02*
G02Y1658794I0J1502D01*
G01X1271799D01*
G02Y1655790I0J-1502D01*
G01X1268399D01*
G37*
G36*
G01X1280459D02*
G02Y1658794I0J1502D01*
G01X1283859D01*
G02Y1655790I0J-1502D01*
G01X1280459D01*
G37*
G36*
G01X1292519D02*
G02Y1658794I0J1502D01*
G01X1295919D01*
G02Y1655790I0J-1502D01*
G01X1292519D01*
G37*
G36*
G01X1304579D02*
G02Y1658794I0J1502D01*
G01X1307979D01*
G02Y1655790I0J-1502D01*
G01X1304579D01*
G37*
G36*
G01X1316639D02*
G02Y1658794I0J1502D01*
G01X1320039D01*
G02Y1655790I0J-1502D01*
G01X1316639D01*
G37*
G36*
G01X1328699D02*
G02Y1658794I0J1502D01*
G01X1332099D01*
G02Y1655790I0J-1502D01*
G01X1328699D01*
G37*
G36*
G01X1340759D02*
G02Y1658794I0J1502D01*
G01X1344159D01*
G02Y1655790I0J-1502D01*
G01X1340759D01*
G37*
G36*
G01X1352819D02*
G02Y1658794I0J1502D01*
G01X1356219D01*
G02Y1655790I0J-1502D01*
G01X1352819D01*
G37*
G36*
G01X1364879D02*
G02Y1658794I0J1502D01*
G01X1368279D01*
G02Y1655790I0J-1502D01*
G01X1364879D01*
G37*
G36*
G01X1376939D02*
G02Y1658794I0J1502D01*
G01X1380339D01*
G02Y1655790I0J-1502D01*
G01X1376939D01*
G37*
G36*
G01X1460213D02*
G02Y1658794I0J1502D01*
G01X1463613D01*
G02Y1655790I0J-1502D01*
G01X1460213D01*
G37*
G36*
G01X1472273D02*
G02Y1658794I0J1502D01*
G01X1475673D01*
G02Y1655790I0J-1502D01*
G01X1472273D01*
G37*
G36*
G01X1484333D02*
G02Y1658794I0J1502D01*
G01X1487733D01*
G02Y1655790I0J-1502D01*
G01X1484333D01*
G37*
G36*
G01X1496393D02*
G02Y1658794I0J1502D01*
G01X1499793D01*
G02Y1655790I0J-1502D01*
G01X1496393D01*
G37*
G36*
G01X1508453D02*
G02Y1658794I0J1502D01*
G01X1511853D01*
G02Y1655790I0J-1502D01*
G01X1508453D01*
G37*
G36*
G01X1520513D02*
G02Y1658794I0J1502D01*
G01X1523913D01*
G02Y1655790I0J-1502D01*
G01X1520513D01*
G37*
G36*
G01X1532573D02*
G02Y1658794I0J1502D01*
G01X1535973D01*
G02Y1655790I0J-1502D01*
G01X1532573D01*
G37*
G36*
G01X1544633D02*
G02Y1658794I0J1502D01*
G01X1548033D01*
G02Y1655790I0J-1502D01*
G01X1544633D01*
G37*
G36*
G01X1556693D02*
G02Y1658794I0J1502D01*
G01X1560093D01*
G02Y1655790I0J-1502D01*
G01X1556693D01*
G37*
G36*
G01X1568753D02*
G02Y1658794I0J1502D01*
G01X1572153D01*
G02Y1655790I0J-1502D01*
G01X1568753D01*
G37*
G36*
G01X1580813D02*
G02Y1658794I0J1502D01*
G01X1584213D01*
G02Y1655790I0J-1502D01*
G01X1580813D01*
G37*
G36*
G01X1592873D02*
G02Y1658794I0J1502D01*
G01X1596273D01*
G02Y1655790I0J-1502D01*
G01X1592873D01*
G37*
G36*
G01X1604933D02*
G02Y1658794I0J1502D01*
G01X1608333D01*
G02Y1655790I0J-1502D01*
G01X1604933D01*
G37*
G36*
G01X1616993D02*
G02Y1658794I0J1502D01*
G01X1620393D01*
G02Y1655790I0J-1502D01*
G01X1616993D01*
G37*
G36*
G01X1629053D02*
G02Y1658794I0J1502D01*
G01X1632453D01*
G02Y1655790I0J-1502D01*
G01X1629053D01*
G37*
G36*
G01X1641113D02*
G02Y1658794I0J1502D01*
G01X1644513D01*
G02Y1655790I0J-1502D01*
G01X1641113D01*
G37*
G36*
G01X236776Y1660474D02*
G02X237079Y1660776I303J-1D01*
G01X240781D01*
G02X241082Y1660474I-1J-302D01*
G01Y1650468D01*
G02X240779Y1650166I-303J1D01*
G01X237077D01*
G02X236776Y1650468I1J302D01*
G01Y1660474D01*
G37*
G36*
G01X268272D02*
G02X268575Y1660776I303J-1D01*
G01X272277D01*
G02X272578Y1660474I-1J-302D01*
G01Y1650468D01*
G02X272275Y1650166I-303J1D01*
G01X268573D01*
G02X268272Y1650468I1J302D01*
G01Y1660474D01*
G37*
G36*
G01X284020D02*
G02X284323Y1660776I303J-1D01*
G01X288025D01*
G02X288326Y1660474I-1J-302D01*
G01Y1650468D01*
G02X288023Y1650166I-303J1D01*
G01X284321D01*
G02X284020Y1650468I1J302D01*
G01Y1660474D01*
G37*
G36*
G01X109073Y1658732D02*
G02Y1661738I0J1503D01*
G01X112473D01*
G02Y1658732I0J-1503D01*
G01X109073D01*
G37*
G36*
G01X1125784Y1661202D02*
G02Y1664208I0J1503D01*
G01X1129184D01*
G02Y1661202I0J-1503D01*
G01X1125784D01*
G37*
G36*
G01X1438232Y1664144D02*
G02X1438436Y1664348I204J0D01*
G01X1457722D01*
G02X1457926Y1664144I0J-204D01*
G01Y1658186D01*
X1457330D01*
G03X1457154Y1658019I22J-199D01*
G01Y1656621D01*
G03X1457330Y1656454I198J32D01*
G01X1457926D01*
Y1637396D01*
G02X1457722Y1637192I-204J0D01*
G01X1438436D01*
G02X1438232Y1637396I0J204D01*
G01Y1664144D01*
G37*
G36*
G01X154111Y1662430D02*
G02Y1665436I0J1503D01*
G01X157511D01*
G02Y1662430I0J-1503D01*
G01X154111D01*
G37*
G36*
G01X228902Y1670711D02*
G02X229205Y1671014I303J0D01*
G01X232905D01*
G02X233208Y1670711I0J-303D01*
G01Y1660705D01*
G02X232905Y1660402I-303J0D01*
G01X229205D01*
G02X228902Y1660705I0J303D01*
G01Y1670711D01*
G37*
G36*
G01X244650D02*
G02X244953Y1671014I303J0D01*
G01X248653D01*
G02X248956Y1670711I0J-303D01*
G01Y1660705D01*
G02X248653Y1660402I-303J0D01*
G01X244953D01*
G02X244650Y1660705I0J303D01*
G01Y1670711D01*
G37*
G36*
G01X276146D02*
G02X276449Y1671014I303J0D01*
G01X280149D01*
G02X280452Y1670711I0J-303D01*
G01Y1660705D01*
G02X280149Y1660402I-303J0D01*
G01X276449D01*
G02X276146Y1660705I0J303D01*
G01Y1670711D01*
G37*
G36*
G01X252524Y1674648D02*
G02X252827Y1674950I303J-1D01*
G01X256529D01*
G02X256830Y1674648I-1J-302D01*
G01Y1664642D01*
G02X256527Y1664340I-303J1D01*
G01X252825D01*
G02X252524Y1664642I1J302D01*
G01Y1674648D01*
G37*
G36*
G01X268272D02*
G02X268575Y1674950I303J-1D01*
G01X272277D01*
G02X272578Y1674648I-1J-302D01*
G01Y1664642D01*
G02X272275Y1664340I-303J1D01*
G01X268573D01*
G02X268272Y1664642I1J302D01*
G01Y1674648D01*
G37*
G36*
G01X284020D02*
G02X284323Y1674950I303J-1D01*
G01X288025D01*
G02X288326Y1674648I-1J-302D01*
G01Y1664642D01*
G02X288023Y1664340I-303J1D01*
G01X284321D01*
G02X284020Y1664642I1J302D01*
G01Y1674648D01*
G37*
G36*
G01X154010Y1675308D02*
G02Y1678314I0J1503D01*
G01X157410D01*
G02Y1675308I0J-1503D01*
G01X154010D01*
G37*
G36*
G01X228902Y1684884D02*
G02X229205Y1685186I303J-1D01*
G01X232907D01*
G02X233208Y1684884I-1J-302D01*
G01Y1674878D01*
G02X232905Y1674576I-303J1D01*
G01X229203D01*
G02X228902Y1674878I1J302D01*
G01Y1684884D01*
G37*
G36*
G01X244650D02*
G02X244953Y1685186I303J-1D01*
G01X248655D01*
G02X248956Y1684884I-1J-302D01*
G01Y1674878D01*
G02X248653Y1674576I-303J1D01*
G01X244951D01*
G02X244650Y1674878I1J302D01*
G01Y1684884D01*
G37*
G36*
G01X260398D02*
G02X260701Y1685186I303J-1D01*
G01X264403D01*
G02X264704Y1684884I-1J-302D01*
G01Y1674878D01*
G02X264401Y1674576I-303J1D01*
G01X260699D01*
G02X260398Y1674878I1J302D01*
G01Y1684884D01*
G37*
G36*
G01X276146D02*
G02X276449Y1685186I303J-1D01*
G01X280151D01*
G02X280452Y1684884I-1J-302D01*
G01Y1674878D01*
G02X280149Y1674576I-303J1D01*
G01X276447D01*
G02X276146Y1674878I1J302D01*
G01Y1684884D01*
G37*
G36*
G01X295832D02*
G02X296134Y1685186I302J0D01*
G01X299834D01*
G02X300136Y1684884I0J-302D01*
G01Y1674878D01*
G02X299834Y1674576I-302J0D01*
G01X296134D01*
G02X295832Y1674878I0J302D01*
G01Y1684884D01*
G37*
G36*
G01X311580D02*
G02X311882Y1685186I302J0D01*
G01X315582D01*
G02X315884Y1684884I0J-302D01*
G01Y1674878D01*
G02X315582Y1674576I-302J0D01*
G01X311882D01*
G02X311580Y1674878I0J302D01*
G01Y1684884D01*
G37*
G36*
G01X327328D02*
G02X327630Y1685186I302J0D01*
G01X331330D01*
G02X331632Y1684884I0J-302D01*
G01Y1674878D01*
G02X331330Y1674576I-302J0D01*
G01X327630D01*
G02X327328Y1674878I0J302D01*
G01Y1684884D01*
G37*
G36*
G01X343076D02*
G02X343378Y1685186I302J0D01*
G01X347078D01*
G02X347380Y1684884I0J-302D01*
G01Y1674878D01*
G02X347078Y1674576I-302J0D01*
G01X343378D01*
G02X343076Y1674878I0J302D01*
G01Y1684884D01*
G37*
G36*
G01X493076D02*
G02X493378Y1685186I302J0D01*
G01X497078D01*
G02X497380Y1684884I0J-302D01*
G01Y1674878D01*
G02X497078Y1674576I-302J0D01*
G01X493378D01*
G02X493076Y1674878I0J302D01*
G01Y1684884D01*
G37*
G36*
G01X508824D02*
G02X509126Y1685186I302J0D01*
G01X512826D01*
G02X513128Y1684884I0J-302D01*
G01Y1674878D01*
G02X512826Y1674576I-302J0D01*
G01X509126D01*
G02X508824Y1674878I0J302D01*
G01Y1684884D01*
G37*
G36*
G01X524572D02*
G02X524874Y1685186I302J0D01*
G01X528574D01*
G02X528876Y1684884I0J-302D01*
G01Y1674878D01*
G02X528574Y1674576I-302J0D01*
G01X524874D01*
G02X524572Y1674878I0J302D01*
G01Y1684884D01*
G37*
G36*
G01X540320D02*
G02X540622Y1685186I302J0D01*
G01X544322D01*
G02X544624Y1684884I0J-302D01*
G01Y1674878D01*
G02X544322Y1674576I-302J0D01*
G01X540622D01*
G02X540320Y1674878I0J302D01*
G01Y1684884D01*
G37*
G36*
G01X560004D02*
G02X560307Y1685186I303J-1D01*
G01X564009D01*
G02X564310Y1684884I-1J-302D01*
G01Y1674878D01*
G02X564007Y1674576I-303J1D01*
G01X560305D01*
G02X560004Y1674878I1J302D01*
G01Y1684884D01*
G37*
G36*
G01X575752D02*
G02X576055Y1685186I303J-1D01*
G01X579757D01*
G02X580058Y1684884I-1J-302D01*
G01Y1674878D01*
G02X579755Y1674576I-303J1D01*
G01X576053D01*
G02X575752Y1674878I1J302D01*
G01Y1684884D01*
G37*
G36*
G01X591500D02*
G02X591803Y1685186I303J-1D01*
G01X595505D01*
G02X595806Y1684884I-1J-302D01*
G01Y1674878D01*
G02X595503Y1674576I-303J1D01*
G01X591801D01*
G02X591500Y1674878I1J302D01*
G01Y1684884D01*
G37*
G36*
G01X607248D02*
G02X607551Y1685186I303J-1D01*
G01X611253D01*
G02X611554Y1684884I-1J-302D01*
G01Y1674878D01*
G02X611251Y1674576I-303J1D01*
G01X607549D01*
G02X607248Y1674878I1J302D01*
G01Y1684884D01*
G37*
G36*
G01X1236776D02*
G02X1237079Y1685186I303J-1D01*
G01X1240781D01*
G02X1241082Y1684884I-1J-302D01*
G01Y1674878D01*
G02X1240779Y1674576I-303J1D01*
G01X1237077D01*
G02X1236776Y1674878I1J302D01*
G01Y1684884D01*
G37*
G36*
G01X1252524D02*
G02X1252827Y1685186I303J-1D01*
G01X1256529D01*
G02X1256830Y1684884I-1J-302D01*
G01Y1674878D01*
G02X1256527Y1674576I-303J1D01*
G01X1252825D01*
G02X1252524Y1674878I1J302D01*
G01Y1684884D01*
G37*
G36*
G01X1268272D02*
G02X1268575Y1685186I303J-1D01*
G01X1272277D01*
G02X1272578Y1684884I-1J-302D01*
G01Y1674878D01*
G02X1272275Y1674576I-303J1D01*
G01X1268573D01*
G02X1268272Y1674878I1J302D01*
G01Y1684884D01*
G37*
G36*
G01X1284020D02*
G02X1284323Y1685186I303J-1D01*
G01X1288025D01*
G02X1288326Y1684884I-1J-302D01*
G01Y1674878D01*
G02X1288023Y1674576I-303J1D01*
G01X1284321D01*
G02X1284020Y1674878I1J302D01*
G01Y1684884D01*
G37*
G36*
G01X1303706D02*
G02X1304008Y1685186I302J0D01*
G01X1307708D01*
G02X1308010Y1684884I0J-302D01*
G01Y1674878D01*
G02X1307708Y1674576I-302J0D01*
G01X1304008D01*
G02X1303706Y1674878I0J302D01*
G01Y1684884D01*
G37*
G36*
G01X1319454D02*
G02X1319756Y1685186I302J0D01*
G01X1323456D01*
G02X1323758Y1684884I0J-302D01*
G01Y1674878D01*
G02X1323456Y1674576I-302J0D01*
G01X1319756D01*
G02X1319454Y1674878I0J302D01*
G01Y1684884D01*
G37*
G36*
G01X1335202D02*
G02X1335504Y1685186I302J0D01*
G01X1339204D01*
G02X1339506Y1684884I0J-302D01*
G01Y1674878D01*
G02X1339204Y1674576I-302J0D01*
G01X1335504D01*
G02X1335202Y1674878I0J302D01*
G01Y1684884D01*
G37*
G36*
G01X1350950D02*
G02X1351252Y1685186I302J0D01*
G01X1354952D01*
G02X1355254Y1684884I0J-302D01*
G01Y1674878D01*
G02X1354952Y1674576I-302J0D01*
G01X1351252D01*
G02X1350950Y1674878I0J302D01*
G01Y1684884D01*
G37*
G36*
G01X1500950Y1684885D02*
G02X1501252Y1685188I302J1D01*
G01X1504952D01*
G02X1505254Y1684885I-1J-303D01*
G01Y1674879D01*
G02X1504952Y1674576I-302J-1D01*
G01X1501252D01*
G02X1500950Y1674879I1J303D01*
G01Y1684885D01*
G37*
G36*
G01X1516698D02*
G02X1517000Y1685188I302J1D01*
G01X1520700D01*
G02X1521002Y1684885I-1J-303D01*
G01Y1674879D01*
G02X1520700Y1674576I-302J-1D01*
G01X1517000D01*
G02X1516698Y1674879I1J303D01*
G01Y1684885D01*
G37*
G36*
G01X1532446D02*
G02X1532748Y1685188I302J1D01*
G01X1536448D01*
G02X1536750Y1684885I-1J-303D01*
G01Y1674879D01*
G02X1536448Y1674576I-302J-1D01*
G01X1532748D01*
G02X1532446Y1674879I1J303D01*
G01Y1684885D01*
G37*
G36*
G01X1548194D02*
G02X1548496Y1685188I302J1D01*
G01X1552196D01*
G02X1552498Y1684885I-1J-303D01*
G01Y1674879D01*
G02X1552196Y1674576I-302J-1D01*
G01X1548496D01*
G02X1548194Y1674879I1J303D01*
G01Y1684885D01*
G37*
G36*
G01X1567878D02*
G02X1568181Y1685188I303J0D01*
G01X1571881D01*
G02X1572184Y1684885I0J-303D01*
G01Y1674879D01*
G02X1571881Y1674576I-303J0D01*
G01X1568181D01*
G02X1567878Y1674879I0J303D01*
G01Y1684885D01*
G37*
G36*
G01X1583626D02*
G02X1583929Y1685188I303J0D01*
G01X1587629D01*
G02X1587932Y1684885I0J-303D01*
G01Y1674879D01*
G02X1587629Y1674576I-303J0D01*
G01X1583929D01*
G02X1583626Y1674879I0J303D01*
G01Y1684885D01*
G37*
G36*
G01X1599374D02*
G02X1599677Y1685188I303J0D01*
G01X1603377D01*
G02X1603680Y1684885I0J-303D01*
G01Y1674879D01*
G02X1603377Y1674576I-303J0D01*
G01X1599677D01*
G02X1599374Y1674879I0J303D01*
G01Y1684885D01*
G37*
G36*
G01X1615122D02*
G02X1615425Y1685188I303J0D01*
G01X1619125D01*
G02X1619428Y1684885I0J-303D01*
G01Y1674879D01*
G02X1619125Y1674576I-303J0D01*
G01X1615425D01*
G02X1615122Y1674879I0J303D01*
G01Y1684885D01*
G37*
G36*
G01X107569Y1684260D02*
G02Y1687266I0J1503D01*
G01X110969D01*
G02Y1684260I0J-1503D01*
G01X107569D01*
G37*
G36*
G01X236776Y1688821D02*
G02X237079Y1689124I303J0D01*
G01X240779D01*
G02X241082Y1688821I0J-303D01*
G01Y1678815D01*
G02X240779Y1678512I-303J0D01*
G01X237079D01*
G02X236776Y1678815I0J303D01*
G01Y1688821D01*
G37*
G36*
G01X252524D02*
G02X252827Y1689124I303J0D01*
G01X256527D01*
G02X256830Y1688821I0J-303D01*
G01Y1678815D01*
G02X256527Y1678512I-303J0D01*
G01X252827D01*
G02X252524Y1678815I0J303D01*
G01Y1688821D01*
G37*
G36*
G01X268272D02*
G02X268575Y1689124I303J0D01*
G01X272275D01*
G02X272578Y1688821I0J-303D01*
G01Y1678815D01*
G02X272275Y1678512I-303J0D01*
G01X268575D01*
G02X268272Y1678815I0J303D01*
G01Y1688821D01*
G37*
G36*
G01X284020D02*
G02X284323Y1689124I303J0D01*
G01X288023D01*
G02X288326Y1688821I0J-303D01*
G01Y1678815D01*
G02X288023Y1678512I-303J0D01*
G01X284323D01*
G02X284020Y1678815I0J303D01*
G01Y1688821D01*
G37*
G36*
G01X303706D02*
G02X304008Y1689124I302J1D01*
G01X307708D01*
G02X308010Y1688821I-1J-303D01*
G01Y1678815D01*
G02X307708Y1678512I-302J-1D01*
G01X304008D01*
G02X303706Y1678815I1J303D01*
G01Y1688821D01*
G37*
G36*
G01X319454D02*
G02X319756Y1689124I302J1D01*
G01X323456D01*
G02X323758Y1688821I-1J-303D01*
G01Y1678815D01*
G02X323456Y1678512I-302J-1D01*
G01X319756D01*
G02X319454Y1678815I1J303D01*
G01Y1688821D01*
G37*
G36*
G01X335202D02*
G02X335504Y1689124I302J1D01*
G01X339204D01*
G02X339506Y1688821I-1J-303D01*
G01Y1678815D01*
G02X339204Y1678512I-302J-1D01*
G01X335504D01*
G02X335202Y1678815I1J303D01*
G01Y1688821D01*
G37*
G36*
G01X350950D02*
G02X351252Y1689124I302J1D01*
G01X354952D01*
G02X355254Y1688821I-1J-303D01*
G01Y1678815D01*
G02X354952Y1678512I-302J-1D01*
G01X351252D01*
G02X350950Y1678815I1J303D01*
G01Y1688821D01*
G37*
G36*
G01X500950D02*
G02X501252Y1689124I302J1D01*
G01X504952D01*
G02X505254Y1688821I-1J-303D01*
G01Y1678815D01*
G02X504952Y1678512I-302J-1D01*
G01X501252D01*
G02X500950Y1678815I1J303D01*
G01Y1688821D01*
G37*
G36*
G01X516698D02*
G02X517000Y1689124I302J1D01*
G01X520700D01*
G02X521002Y1688821I-1J-303D01*
G01Y1678815D01*
G02X520700Y1678512I-302J-1D01*
G01X517000D01*
G02X516698Y1678815I1J303D01*
G01Y1688821D01*
G37*
G36*
G01X532446D02*
G02X532748Y1689124I302J1D01*
G01X536448D01*
G02X536750Y1688821I-1J-303D01*
G01Y1678815D01*
G02X536448Y1678512I-302J-1D01*
G01X532748D01*
G02X532446Y1678815I1J303D01*
G01Y1688821D01*
G37*
G36*
G01X548194D02*
G02X548496Y1689124I302J1D01*
G01X552196D01*
G02X552498Y1688821I-1J-303D01*
G01Y1678815D01*
G02X552196Y1678512I-302J-1D01*
G01X548496D01*
G02X548194Y1678815I1J303D01*
G01Y1688821D01*
G37*
G36*
G01X567878D02*
G02X568181Y1689124I303J0D01*
G01X571881D01*
G02X572184Y1688821I0J-303D01*
G01Y1678815D01*
G02X571881Y1678512I-303J0D01*
G01X568181D01*
G02X567878Y1678815I0J303D01*
G01Y1688821D01*
G37*
G36*
G01X583626D02*
G02X583929Y1689124I303J0D01*
G01X587629D01*
G02X587932Y1688821I0J-303D01*
G01Y1678815D01*
G02X587629Y1678512I-303J0D01*
G01X583929D01*
G02X583626Y1678815I0J303D01*
G01Y1688821D01*
G37*
G36*
G01X599374D02*
G02X599677Y1689124I303J0D01*
G01X603377D01*
G02X603680Y1688821I0J-303D01*
G01Y1678815D01*
G02X603377Y1678512I-303J0D01*
G01X599677D01*
G02X599374Y1678815I0J303D01*
G01Y1688821D01*
G37*
G36*
G01X615122D02*
G02X615425Y1689124I303J0D01*
G01X619125D01*
G02X619428Y1688821I0J-303D01*
G01Y1678815D01*
G02X619125Y1678512I-303J0D01*
G01X615425D01*
G02X615122Y1678815I0J303D01*
G01Y1688821D01*
G37*
G36*
G01X1244650D02*
G02X1244953Y1689124I303J0D01*
G01X1248653D01*
G02X1248956Y1688821I0J-303D01*
G01Y1678815D01*
G02X1248653Y1678512I-303J0D01*
G01X1244953D01*
G02X1244650Y1678815I0J303D01*
G01Y1688821D01*
G37*
G36*
G01X1260398D02*
G02X1260701Y1689124I303J0D01*
G01X1264401D01*
G02X1264704Y1688821I0J-303D01*
G01Y1678815D01*
G02X1264401Y1678512I-303J0D01*
G01X1260701D01*
G02X1260398Y1678815I0J303D01*
G01Y1688821D01*
G37*
G36*
G01X1276146D02*
G02X1276449Y1689124I303J0D01*
G01X1280149D01*
G02X1280452Y1688821I0J-303D01*
G01Y1678815D01*
G02X1280149Y1678512I-303J0D01*
G01X1276449D01*
G02X1276146Y1678815I0J303D01*
G01Y1688821D01*
G37*
G36*
G01X1291894D02*
G02X1292197Y1689124I303J0D01*
G01X1295897D01*
G02X1296200Y1688821I0J-303D01*
G01Y1678815D01*
G02X1295897Y1678512I-303J0D01*
G01X1292197D01*
G02X1291894Y1678815I0J303D01*
G01Y1688821D01*
G37*
G36*
G01X1311580D02*
G02X1311882Y1689124I302J1D01*
G01X1315582D01*
G02X1315884Y1688821I-1J-303D01*
G01Y1678815D01*
G02X1315582Y1678512I-302J-1D01*
G01X1311882D01*
G02X1311580Y1678815I1J303D01*
G01Y1688821D01*
G37*
G36*
G01X1327328D02*
G02X1327630Y1689124I302J1D01*
G01X1331330D01*
G02X1331632Y1688821I-1J-303D01*
G01Y1678815D01*
G02X1331330Y1678512I-302J-1D01*
G01X1327630D01*
G02X1327328Y1678815I1J303D01*
G01Y1688821D01*
G37*
G36*
G01X1343076D02*
G02X1343378Y1689124I302J1D01*
G01X1347078D01*
G02X1347380Y1688821I-1J-303D01*
G01Y1678815D01*
G02X1347078Y1678512I-302J-1D01*
G01X1343378D01*
G02X1343076Y1678815I1J303D01*
G01Y1688821D01*
G37*
G36*
G01X1358824D02*
G02X1359126Y1689124I302J1D01*
G01X1362826D01*
G02X1363128Y1688821I-1J-303D01*
G01Y1678815D01*
G02X1362826Y1678512I-302J-1D01*
G01X1359126D01*
G02X1358824Y1678815I1J303D01*
G01Y1688821D01*
G37*
G36*
G01X1508824Y1688822D02*
G02X1509126Y1689124I302J0D01*
G01X1512826D01*
G02X1513128Y1688822I0J-302D01*
G01Y1678816D01*
G02X1512826Y1678514I-302J0D01*
G01X1509126D01*
G02X1508824Y1678816I0J302D01*
G01Y1688822D01*
G37*
G36*
G01X1524572D02*
G02X1524874Y1689124I302J0D01*
G01X1528574D01*
G02X1528876Y1688822I0J-302D01*
G01Y1678816D01*
G02X1528574Y1678514I-302J0D01*
G01X1524874D01*
G02X1524572Y1678816I0J302D01*
G01Y1688822D01*
G37*
G36*
G01X1540320D02*
G02X1540622Y1689124I302J0D01*
G01X1544322D01*
G02X1544624Y1688822I0J-302D01*
G01Y1678816D01*
G02X1544322Y1678514I-302J0D01*
G01X1540622D01*
G02X1540320Y1678816I0J302D01*
G01Y1688822D01*
G37*
G36*
G01X1556068D02*
G02X1556370Y1689124I302J0D01*
G01X1560070D01*
G02X1560372Y1688822I0J-302D01*
G01Y1678816D01*
G02X1560070Y1678514I-302J0D01*
G01X1556370D01*
G02X1556068Y1678816I0J302D01*
G01Y1688822D01*
G37*
G36*
G01X1575752D02*
G02X1576055Y1689124I303J-1D01*
G01X1579757D01*
G02X1580058Y1688822I-1J-302D01*
G01Y1678816D01*
G02X1579755Y1678514I-303J1D01*
G01X1576053D01*
G02X1575752Y1678816I1J302D01*
G01Y1688822D01*
G37*
G36*
G01X1591500D02*
G02X1591803Y1689124I303J-1D01*
G01X1595505D01*
G02X1595806Y1688822I-1J-302D01*
G01Y1678816D01*
G02X1595503Y1678514I-303J1D01*
G01X1591801D01*
G02X1591500Y1678816I1J302D01*
G01Y1688822D01*
G37*
G36*
G01X1607248D02*
G02X1607551Y1689124I303J-1D01*
G01X1611253D01*
G02X1611554Y1688822I-1J-302D01*
G01Y1678816D01*
G02X1611251Y1678514I-303J1D01*
G01X1607549D01*
G02X1607248Y1678816I1J302D01*
G01Y1688822D01*
G37*
G36*
G01X1622996D02*
G02X1623299Y1689124I303J-1D01*
G01X1627001D01*
G02X1627302Y1688822I-1J-302D01*
G01Y1678816D01*
G02X1626999Y1678514I-303J1D01*
G01X1623297D01*
G02X1622996Y1678816I1J302D01*
G01Y1688822D01*
G37*
G36*
G01X228902Y1699057D02*
G02X229205Y1699360I303J0D01*
G01X232905D01*
G02X233208Y1699057I0J-303D01*
G01Y1689051D01*
G02X232905Y1688748I-303J0D01*
G01X229205D01*
G02X228902Y1689051I0J303D01*
G01Y1691915D01*
G02X228934Y1692048I302J-2D01*
G01Y1692050D01*
X229853Y1693924D01*
G03Y1694186I-267J131D01*
G01X228934Y1696060D01*
Y1696062D01*
G02X228902Y1696195I270J135D01*
G01Y1699057D01*
G37*
G36*
G01X244650D02*
G02X244953Y1699360I303J0D01*
G01X248653D01*
G02X248956Y1699057I0J-303D01*
G01Y1689051D01*
G02X248653Y1688748I-303J0D01*
G01X244953D01*
G02X244650Y1689051I0J303D01*
G01Y1691915D01*
G02X244682Y1692048I302J-2D01*
G01Y1692050D01*
X245601Y1693924D01*
G03Y1694186I-267J131D01*
G01X244682Y1696060D01*
Y1696062D01*
G02X244650Y1696195I270J135D01*
G01Y1699057D01*
G37*
G36*
G01X260398D02*
G02X260701Y1699360I303J0D01*
G01X264401D01*
G02X264704Y1699057I0J-303D01*
G01Y1689051D01*
G02X264401Y1688748I-303J0D01*
G01X260701D01*
G02X260398Y1689051I0J303D01*
G01Y1691915D01*
G02X260430Y1692048I302J-2D01*
G01Y1692050D01*
X261349Y1693924D01*
G03Y1694186I-267J131D01*
G01X260430Y1696060D01*
Y1696062D01*
G02X260398Y1696195I270J135D01*
G01Y1699057D01*
G37*
G36*
G01X276146D02*
G02X276449Y1699360I303J0D01*
G01X280149D01*
G02X280452Y1699057I0J-303D01*
G01Y1689051D01*
G02X280149Y1688748I-303J0D01*
G01X276449D01*
G02X276146Y1689051I0J303D01*
G01Y1691915D01*
G02X276178Y1692048I302J-2D01*
G01Y1692050D01*
X277097Y1693924D01*
G03Y1694186I-267J131D01*
G01X276178Y1696060D01*
Y1696062D01*
G02X276146Y1696195I270J135D01*
G01Y1699057D01*
G37*
G36*
G01X295832D02*
G02X296134Y1699360I302J1D01*
G01X299834D01*
G02X300136Y1699057I-1J-303D01*
G01Y1689051D01*
G02X299834Y1688748I-302J-1D01*
G01X296134D01*
G02X295832Y1689051I1J303D01*
G01Y1691916D01*
G02X295863Y1692049I302J0D01*
G01X296782Y1693924D01*
G03Y1694186I-267J131D01*
G01X295863Y1696061D01*
G02X295832Y1696194I271J133D01*
G01Y1699057D01*
G37*
G36*
G01X311580D02*
G02X311882Y1699360I302J1D01*
G01X315582D01*
G02X315884Y1699057I-1J-303D01*
G01Y1689051D01*
G02X315582Y1688748I-302J-1D01*
G01X311882D01*
G02X311580Y1689051I1J303D01*
G01Y1691916D01*
G02X311611Y1692049I302J0D01*
G01X312530Y1693924D01*
G03Y1694186I-267J131D01*
G01X311611Y1696061D01*
G02X311580Y1696194I271J133D01*
G01Y1699057D01*
G37*
G36*
G01X327328D02*
G02X327630Y1699360I302J1D01*
G01X331330D01*
G02X331632Y1699057I-1J-303D01*
G01Y1689051D01*
G02X331330Y1688748I-302J-1D01*
G01X327630D01*
G02X327328Y1689051I1J303D01*
G01Y1691916D01*
G02X327359Y1692049I302J0D01*
G01X328278Y1693924D01*
G03Y1694186I-267J131D01*
G01X327359Y1696061D01*
G02X327328Y1696194I271J133D01*
G01Y1699057D01*
G37*
G36*
G01X343076D02*
G02X343378Y1699360I302J1D01*
G01X347078D01*
G02X347380Y1699057I-1J-303D01*
G01Y1689051D01*
G02X347078Y1688748I-302J-1D01*
G01X343378D01*
G02X343076Y1689051I1J303D01*
G01Y1691916D01*
G02X343107Y1692049I302J0D01*
G01X344026Y1693924D01*
G03Y1694186I-267J131D01*
G01X343107Y1696061D01*
G02X343076Y1696194I271J133D01*
G01Y1699057D01*
G37*
G36*
G01X493076D02*
G02X493378Y1699360I302J1D01*
G01X497078D01*
G02X497380Y1699057I-1J-303D01*
G01Y1689051D01*
G02X497078Y1688748I-302J-1D01*
G01X493378D01*
G02X493076Y1689051I1J303D01*
G01Y1691916D01*
G02X493107Y1692049I302J0D01*
G01X494026Y1693924D01*
G03Y1694186I-267J131D01*
G01X493107Y1696061D01*
G02X493076Y1696194I271J133D01*
G01Y1699057D01*
G37*
G36*
G01X508824D02*
G02X509126Y1699360I302J1D01*
G01X512826D01*
G02X513128Y1699057I-1J-303D01*
G01Y1689051D01*
G02X512826Y1688748I-302J-1D01*
G01X509126D01*
G02X508824Y1689051I1J303D01*
G01Y1691916D01*
G02X508855Y1692049I302J0D01*
G01X509774Y1693924D01*
G03Y1694186I-267J131D01*
G01X508855Y1696061D01*
G02X508824Y1696194I271J133D01*
G01Y1699057D01*
G37*
G36*
G01X524572D02*
G02X524874Y1699360I302J1D01*
G01X528574D01*
G02X528876Y1699057I-1J-303D01*
G01Y1689051D01*
G02X528574Y1688748I-302J-1D01*
G01X524874D01*
G02X524572Y1689051I1J303D01*
G01Y1691916D01*
G02X524603Y1692049I302J0D01*
G01X525522Y1693924D01*
G03Y1694186I-267J131D01*
G01X524603Y1696061D01*
G02X524572Y1696194I271J133D01*
G01Y1699057D01*
G37*
G36*
G01X540320D02*
G02X540622Y1699360I302J1D01*
G01X544322D01*
G02X544624Y1699057I-1J-303D01*
G01Y1689051D01*
G02X544322Y1688748I-302J-1D01*
G01X540622D01*
G02X540320Y1689051I1J303D01*
G01Y1691916D01*
G02X540351Y1692049I302J0D01*
G01X541270Y1693924D01*
G03Y1694186I-267J131D01*
G01X540351Y1696061D01*
G02X540320Y1696194I271J133D01*
G01Y1699057D01*
G37*
G36*
G01X560006D02*
G02X560308Y1699360I302J1D01*
G01X564008D01*
G02X564310Y1699057I-1J-303D01*
G01Y1689051D01*
G02X564008Y1688748I-302J-1D01*
G01X560308D01*
G02X560006Y1689051I1J303D01*
G01Y1691916D01*
G02X560037Y1692049I302J0D01*
G01X560956Y1693924D01*
G03Y1694186I-267J131D01*
G01X560037Y1696061D01*
G02X560006Y1696194I271J133D01*
G01Y1699057D01*
G37*
G36*
G01X575754D02*
G02X576056Y1699360I302J1D01*
G01X579756D01*
G02X580058Y1699057I-1J-303D01*
G01Y1689051D01*
G02X579756Y1688748I-302J-1D01*
G01X576056D01*
G02X575754Y1689051I1J303D01*
G01Y1691916D01*
G02X575785Y1692049I302J0D01*
G01X576704Y1693924D01*
G03Y1694186I-267J131D01*
G01X575785Y1696061D01*
G02X575754Y1696194I271J133D01*
G01Y1699057D01*
G37*
G36*
G01X591502D02*
G02X591804Y1699360I302J1D01*
G01X595504D01*
G02X595806Y1699057I-1J-303D01*
G01Y1689051D01*
G02X595504Y1688748I-302J-1D01*
G01X591804D01*
G02X591502Y1689051I1J303D01*
G01Y1691916D01*
G02X591533Y1692049I302J0D01*
G01X592452Y1693924D01*
G03Y1694186I-267J131D01*
G01X591533Y1696061D01*
G02X591502Y1696194I271J133D01*
G01Y1699057D01*
G37*
G36*
G01X607250D02*
G02X607552Y1699360I302J1D01*
G01X611252D01*
G02X611554Y1699057I-1J-303D01*
G01Y1689051D01*
G02X611252Y1688748I-302J-1D01*
G01X607552D01*
G02X607250Y1689051I1J303D01*
G01Y1691916D01*
G02X607281Y1692049I302J0D01*
G01X608200Y1693924D01*
G03Y1694186I-267J131D01*
G01X607281Y1696061D01*
G02X607250Y1696194I271J133D01*
G01Y1699057D01*
G37*
G36*
G01X1236776D02*
G02X1237078Y1699360I302J1D01*
G01X1240778D01*
G02X1241080Y1699057I-1J-303D01*
G01Y1689051D01*
G02X1240778Y1688748I-302J-1D01*
G01X1237078D01*
G02X1236776Y1689051I1J303D01*
G01Y1691916D01*
G02X1236807Y1692049I302J0D01*
G01X1237726Y1693924D01*
G03Y1694186I-267J131D01*
G01X1236807Y1696061D01*
G02X1236776Y1696194I271J133D01*
G01Y1699057D01*
G37*
G36*
G01X1252524D02*
G02X1252826Y1699360I302J1D01*
G01X1256526D01*
G02X1256828Y1699057I-1J-303D01*
G01Y1689051D01*
G02X1256526Y1688748I-302J-1D01*
G01X1252826D01*
G02X1252524Y1689051I1J303D01*
G01Y1691916D01*
G02X1252555Y1692049I302J0D01*
G01X1253474Y1693924D01*
G03Y1694186I-267J131D01*
G01X1252555Y1696061D01*
G02X1252524Y1696194I271J133D01*
G01Y1699057D01*
G37*
G36*
G01X1268272D02*
G02X1268574Y1699360I302J1D01*
G01X1272274D01*
G02X1272576Y1699057I-1J-303D01*
G01Y1689051D01*
G02X1272274Y1688748I-302J-1D01*
G01X1268574D01*
G02X1268272Y1689051I1J303D01*
G01Y1691916D01*
G02X1268303Y1692049I302J0D01*
G01X1269222Y1693924D01*
G03Y1694186I-267J131D01*
G01X1268303Y1696061D01*
G02X1268272Y1696194I271J133D01*
G01Y1699057D01*
G37*
G36*
G01X1284020D02*
G02X1284322Y1699360I302J1D01*
G01X1288022D01*
G02X1288324Y1699057I-1J-303D01*
G01Y1689051D01*
G02X1288022Y1688748I-302J-1D01*
G01X1284322D01*
G02X1284020Y1689051I1J303D01*
G01Y1691916D01*
G02X1284051Y1692049I302J0D01*
G01X1284970Y1693924D01*
G03Y1694186I-267J131D01*
G01X1284051Y1696061D01*
G02X1284020Y1696194I271J133D01*
G01Y1699057D01*
G37*
G36*
G01X1303706D02*
G02X1304008Y1699360I302J1D01*
G01X1307708D01*
G02X1308010Y1699057I-1J-303D01*
G01Y1689051D01*
G02X1307708Y1688748I-302J-1D01*
G01X1304008D01*
G02X1303706Y1689051I1J303D01*
G01Y1691916D01*
G02X1303737Y1692049I302J0D01*
G01X1304656Y1693924D01*
G03Y1694186I-267J131D01*
G01X1303737Y1696061D01*
G02X1303706Y1696194I271J133D01*
G01Y1699057D01*
G37*
G36*
G01X1319454D02*
G02X1319756Y1699360I302J1D01*
G01X1323456D01*
G02X1323758Y1699057I-1J-303D01*
G01Y1689051D01*
G02X1323456Y1688748I-302J-1D01*
G01X1319756D01*
G02X1319454Y1689051I1J303D01*
G01Y1691916D01*
G02X1319485Y1692049I302J0D01*
G01X1320404Y1693924D01*
G03Y1694186I-267J131D01*
G01X1319485Y1696061D01*
G02X1319454Y1696194I271J133D01*
G01Y1699057D01*
G37*
G36*
G01X1335202D02*
G02X1335504Y1699360I302J1D01*
G01X1339204D01*
G02X1339506Y1699057I-1J-303D01*
G01Y1689051D01*
G02X1339204Y1688748I-302J-1D01*
G01X1335504D01*
G02X1335202Y1689051I1J303D01*
G01Y1691916D01*
G02X1335233Y1692049I302J0D01*
G01X1336152Y1693924D01*
G03Y1694186I-267J131D01*
G01X1335233Y1696061D01*
G02X1335202Y1696194I271J133D01*
G01Y1699057D01*
G37*
G36*
G01X1350950D02*
G02X1351252Y1699360I302J1D01*
G01X1354952D01*
G02X1355254Y1699057I-1J-303D01*
G01Y1689051D01*
G02X1354952Y1688748I-302J-1D01*
G01X1351252D01*
G02X1350950Y1689051I1J303D01*
G01Y1691916D01*
G02X1350981Y1692049I302J0D01*
G01X1351900Y1693924D01*
G03Y1694186I-267J131D01*
G01X1350981Y1696061D01*
G02X1350950Y1696194I271J133D01*
G01Y1699057D01*
G37*
G36*
G01X1500950D02*
G02X1501252Y1699360I302J1D01*
G01X1504952D01*
G02X1505254Y1699057I-1J-303D01*
G01Y1689051D01*
G02X1504952Y1688748I-302J-1D01*
G01X1501252D01*
G02X1500950Y1689051I1J303D01*
G01Y1691916D01*
G02X1500981Y1692049I302J0D01*
G01X1501900Y1693924D01*
G03Y1694186I-267J131D01*
G01X1500981Y1696061D01*
G02X1500950Y1696194I271J133D01*
G01Y1699057D01*
G37*
G36*
G01X1516698D02*
G02X1517000Y1699360I302J1D01*
G01X1520700D01*
G02X1521002Y1699057I-1J-303D01*
G01Y1689051D01*
G02X1520700Y1688748I-302J-1D01*
G01X1517000D01*
G02X1516698Y1689051I1J303D01*
G01Y1691916D01*
G02X1516729Y1692049I302J0D01*
G01X1517648Y1693924D01*
G03Y1694186I-267J131D01*
G01X1516729Y1696061D01*
G02X1516698Y1696194I271J133D01*
G01Y1699057D01*
G37*
G36*
G01X1532446D02*
G02X1532748Y1699360I302J1D01*
G01X1536448D01*
G02X1536750Y1699057I-1J-303D01*
G01Y1689051D01*
G02X1536448Y1688748I-302J-1D01*
G01X1532748D01*
G02X1532446Y1689051I1J303D01*
G01Y1691916D01*
G02X1532477Y1692049I302J0D01*
G01X1533396Y1693924D01*
G03Y1694186I-267J131D01*
G01X1532477Y1696061D01*
G02X1532446Y1696194I271J133D01*
G01Y1699057D01*
G37*
G36*
G01X1548194D02*
G02X1548496Y1699360I302J1D01*
G01X1552196D01*
G02X1552498Y1699057I-1J-303D01*
G01Y1689051D01*
G02X1552196Y1688748I-302J-1D01*
G01X1548496D01*
G02X1548194Y1689051I1J303D01*
G01Y1691916D01*
G02X1548225Y1692049I302J0D01*
G01X1549144Y1693924D01*
G03Y1694186I-267J131D01*
G01X1548225Y1696061D01*
G02X1548194Y1696194I271J133D01*
G01Y1699057D01*
G37*
G36*
G01X1567880D02*
G02X1568182Y1699360I302J1D01*
G01X1571882D01*
G02X1572184Y1699057I-1J-303D01*
G01Y1689051D01*
G02X1571882Y1688748I-302J-1D01*
G01X1568182D01*
G02X1567880Y1689051I1J303D01*
G01Y1691916D01*
G02X1567911Y1692049I302J0D01*
G01X1568830Y1693924D01*
G03Y1694186I-267J131D01*
G01X1567911Y1696061D01*
G02X1567880Y1696194I271J133D01*
G01Y1699057D01*
G37*
G36*
G01X1583628D02*
G02X1583930Y1699360I302J1D01*
G01X1587630D01*
G02X1587932Y1699057I-1J-303D01*
G01Y1689051D01*
G02X1587630Y1688748I-302J-1D01*
G01X1583930D01*
G02X1583628Y1689051I1J303D01*
G01Y1691916D01*
G02X1583659Y1692049I302J0D01*
G01X1584578Y1693924D01*
G03Y1694186I-267J131D01*
G01X1583659Y1696061D01*
G02X1583628Y1696194I271J133D01*
G01Y1699057D01*
G37*
G36*
G01X1599376D02*
G02X1599678Y1699360I302J1D01*
G01X1603378D01*
G02X1603680Y1699057I-1J-303D01*
G01Y1689051D01*
G02X1603378Y1688748I-302J-1D01*
G01X1599678D01*
G02X1599376Y1689051I1J303D01*
G01Y1691916D01*
G02X1599407Y1692049I302J0D01*
G01X1600326Y1693924D01*
G03Y1694186I-267J131D01*
G01X1599407Y1696061D01*
G02X1599376Y1696194I271J133D01*
G01Y1699057D01*
G37*
G36*
G01X1615124D02*
G02X1615426Y1699360I302J1D01*
G01X1619126D01*
G02X1619428Y1699057I-1J-303D01*
G01Y1689051D01*
G02X1619126Y1688748I-302J-1D01*
G01X1615426D01*
G02X1615124Y1689051I1J303D01*
G01Y1691916D01*
G02X1615155Y1692049I302J0D01*
G01X1616074Y1693924D01*
G03Y1694186I-267J131D01*
G01X1615155Y1696061D01*
G02X1615124Y1696194I271J133D01*
G01Y1699057D01*
G37*
G36*
G01X236776Y1702994D02*
G02X237079Y1703296I303J-1D01*
G01X240781D01*
G02X241082Y1702994I-1J-302D01*
G01Y1692988D01*
G02X240779Y1692686I-303J1D01*
G01X237077D01*
G02X236776Y1692988I1J302D01*
G01Y1695852D01*
G02X236808Y1695985I302J-2D01*
G01Y1695987D01*
X237727Y1697861D01*
G03Y1698123I-267J131D01*
G01X236808Y1699997D01*
Y1699999D01*
G02X236776Y1700132I270J135D01*
G01Y1702994D01*
G37*
G36*
G01X252524D02*
G02X252827Y1703296I303J-1D01*
G01X256529D01*
G02X256830Y1702994I-1J-302D01*
G01Y1692988D01*
G02X256527Y1692686I-303J1D01*
G01X252825D01*
G02X252524Y1692988I1J302D01*
G01Y1695852D01*
G02X252556Y1695985I302J-2D01*
G01Y1695987D01*
X253475Y1697861D01*
G03Y1698123I-267J131D01*
G01X252556Y1699997D01*
Y1699999D01*
G02X252524Y1700132I270J135D01*
G01Y1702994D01*
G37*
G36*
G01X268272D02*
G02X268575Y1703296I303J-1D01*
G01X272277D01*
G02X272578Y1702994I-1J-302D01*
G01Y1692988D01*
G02X272275Y1692686I-303J1D01*
G01X268573D01*
G02X268272Y1692988I1J302D01*
G01Y1695852D01*
G02X268304Y1695985I302J-2D01*
G01Y1695987D01*
X269223Y1697861D01*
G03Y1698123I-267J131D01*
G01X268304Y1699997D01*
Y1699999D01*
G02X268272Y1700132I270J135D01*
G01Y1702994D01*
G37*
G36*
G01X284020D02*
G02X284323Y1703296I303J-1D01*
G01X288025D01*
G02X288326Y1702994I-1J-302D01*
G01Y1692988D01*
G02X288023Y1692686I-303J1D01*
G01X284321D01*
G02X284020Y1692988I1J302D01*
G01Y1695852D01*
G02X284052Y1695985I302J-2D01*
G01Y1695987D01*
X284971Y1697861D01*
G03Y1698123I-267J131D01*
G01X284052Y1699997D01*
Y1699999D01*
G02X284020Y1700132I270J135D01*
G01Y1702994D01*
G37*
G36*
G01X303706D02*
G02X304008Y1703296I302J0D01*
G01X307708D01*
G02X308010Y1702994I0J-302D01*
G01Y1692988D01*
G02X307708Y1692686I-302J0D01*
G01X304008D01*
G02X303706Y1692988I0J302D01*
G01Y1695853D01*
G02X303737Y1695986I302J0D01*
G01X304656Y1697861D01*
G03Y1698123I-267J131D01*
G01X303737Y1699998D01*
G02X303706Y1700131I271J133D01*
G01Y1702994D01*
G37*
G36*
G01X319454D02*
G02X319756Y1703296I302J0D01*
G01X323456D01*
G02X323758Y1702994I0J-302D01*
G01Y1692988D01*
G02X323456Y1692686I-302J0D01*
G01X319756D01*
G02X319454Y1692988I0J302D01*
G01Y1695853D01*
G02X319485Y1695986I302J0D01*
G01X320404Y1697861D01*
G03Y1698123I-267J131D01*
G01X319485Y1699998D01*
G02X319454Y1700131I271J133D01*
G01Y1702994D01*
G37*
G36*
G01X335202D02*
G02X335504Y1703296I302J0D01*
G01X339204D01*
G02X339506Y1702994I0J-302D01*
G01Y1692988D01*
G02X339204Y1692686I-302J0D01*
G01X335504D01*
G02X335202Y1692988I0J302D01*
G01Y1695853D01*
G02X335233Y1695986I302J0D01*
G01X336152Y1697861D01*
G03Y1698123I-267J131D01*
G01X335233Y1699998D01*
G02X335202Y1700131I271J133D01*
G01Y1702994D01*
G37*
G36*
G01X350950D02*
G02X351252Y1703296I302J0D01*
G01X354952D01*
G02X355254Y1702994I0J-302D01*
G01Y1692988D01*
G02X354952Y1692686I-302J0D01*
G01X351252D01*
G02X350950Y1692988I0J302D01*
G01Y1695853D01*
G02X350981Y1695986I302J0D01*
G01X351900Y1697861D01*
G03Y1698123I-267J131D01*
G01X350981Y1699998D01*
G02X350950Y1700131I271J133D01*
G01Y1702994D01*
G37*
G36*
G01X500950D02*
G02X501252Y1703296I302J0D01*
G01X504952D01*
G02X505254Y1702994I0J-302D01*
G01Y1692988D01*
G02X504952Y1692686I-302J0D01*
G01X501252D01*
G02X500950Y1692988I0J302D01*
G01Y1695853D01*
G02X500981Y1695986I302J0D01*
G01X501900Y1697861D01*
G03Y1698123I-267J131D01*
G01X500981Y1699998D01*
G02X500950Y1700131I271J133D01*
G01Y1702994D01*
G37*
G36*
G01X516698D02*
G02X517000Y1703296I302J0D01*
G01X520700D01*
G02X521002Y1702994I0J-302D01*
G01Y1692988D01*
G02X520700Y1692686I-302J0D01*
G01X517000D01*
G02X516698Y1692988I0J302D01*
G01Y1695853D01*
G02X516729Y1695986I302J0D01*
G01X517648Y1697861D01*
G03Y1698123I-267J131D01*
G01X516729Y1699998D01*
G02X516698Y1700131I271J133D01*
G01Y1702994D01*
G37*
G36*
G01X532446D02*
G02X532748Y1703296I302J0D01*
G01X536448D01*
G02X536750Y1702994I0J-302D01*
G01Y1692988D01*
G02X536448Y1692686I-302J0D01*
G01X532748D01*
G02X532446Y1692988I0J302D01*
G01Y1695853D01*
G02X532477Y1695986I302J0D01*
G01X533396Y1697861D01*
G03Y1698123I-267J131D01*
G01X532477Y1699998D01*
G02X532446Y1700131I271J133D01*
G01Y1702994D01*
G37*
G36*
G01X548194D02*
G02X548496Y1703296I302J0D01*
G01X552196D01*
G02X552498Y1702994I0J-302D01*
G01Y1692988D01*
G02X552196Y1692686I-302J0D01*
G01X548496D01*
G02X548194Y1692988I0J302D01*
G01Y1695853D01*
G02X548225Y1695986I302J0D01*
G01X549144Y1697861D01*
G03Y1698123I-267J131D01*
G01X548225Y1699998D01*
G02X548194Y1700131I271J133D01*
G01Y1702994D01*
G37*
G36*
G01X567880D02*
G02X568182Y1703296I302J0D01*
G01X571882D01*
G02X572184Y1702994I0J-302D01*
G01Y1692988D01*
G02X571882Y1692686I-302J0D01*
G01X568182D01*
G02X567880Y1692988I0J302D01*
G01Y1695853D01*
G02X567911Y1695986I302J0D01*
G01X568830Y1697861D01*
G03Y1698123I-267J131D01*
G01X567911Y1699998D01*
G02X567880Y1700131I271J133D01*
G01Y1702994D01*
G37*
G36*
G01X583628D02*
G02X583930Y1703296I302J0D01*
G01X587630D01*
G02X587932Y1702994I0J-302D01*
G01Y1692988D01*
G02X587630Y1692686I-302J0D01*
G01X583930D01*
G02X583628Y1692988I0J302D01*
G01Y1695853D01*
G02X583659Y1695986I302J0D01*
G01X584578Y1697861D01*
G03Y1698123I-267J131D01*
G01X583659Y1699998D01*
G02X583628Y1700131I271J133D01*
G01Y1702994D01*
G37*
G36*
G01X599376D02*
G02X599678Y1703296I302J0D01*
G01X603378D01*
G02X603680Y1702994I0J-302D01*
G01Y1692988D01*
G02X603378Y1692686I-302J0D01*
G01X599678D01*
G02X599376Y1692988I0J302D01*
G01Y1695853D01*
G02X599407Y1695986I302J0D01*
G01X600326Y1697861D01*
G03Y1698123I-267J131D01*
G01X599407Y1699998D01*
G02X599376Y1700131I271J133D01*
G01Y1702994D01*
G37*
G36*
G01X615124D02*
G02X615426Y1703296I302J0D01*
G01X619126D01*
G02X619428Y1702994I0J-302D01*
G01Y1692988D01*
G02X619126Y1692686I-302J0D01*
G01X615426D01*
G02X615124Y1692988I0J302D01*
G01Y1695853D01*
G02X615155Y1695986I302J0D01*
G01X616074Y1697861D01*
G03Y1698123I-267J131D01*
G01X615155Y1699998D01*
G02X615124Y1700131I271J133D01*
G01Y1702994D01*
G37*
G36*
G01X1244650D02*
G02X1244952Y1703296I302J0D01*
G01X1248652D01*
G02X1248954Y1702994I0J-302D01*
G01Y1692988D01*
G02X1248652Y1692686I-302J0D01*
G01X1244952D01*
G02X1244650Y1692988I0J302D01*
G01Y1695853D01*
G02X1244681Y1695986I302J0D01*
G01X1245600Y1697861D01*
G03Y1698123I-267J131D01*
G01X1244681Y1699998D01*
G02X1244650Y1700131I271J133D01*
G01Y1702994D01*
G37*
G36*
G01X1260398D02*
G02X1260700Y1703296I302J0D01*
G01X1264400D01*
G02X1264702Y1702994I0J-302D01*
G01Y1692988D01*
G02X1264400Y1692686I-302J0D01*
G01X1260700D01*
G02X1260398Y1692988I0J302D01*
G01Y1695853D01*
G02X1260429Y1695986I302J0D01*
G01X1261348Y1697861D01*
G03Y1698123I-267J131D01*
G01X1260429Y1699998D01*
G02X1260398Y1700131I271J133D01*
G01Y1702994D01*
G37*
G36*
G01X1276146D02*
G02X1276448Y1703296I302J0D01*
G01X1280148D01*
G02X1280450Y1702994I0J-302D01*
G01Y1692988D01*
G02X1280148Y1692686I-302J0D01*
G01X1276448D01*
G02X1276146Y1692988I0J302D01*
G01Y1695853D01*
G02X1276177Y1695986I302J0D01*
G01X1277096Y1697861D01*
G03Y1698123I-267J131D01*
G01X1276177Y1699998D01*
G02X1276146Y1700131I271J133D01*
G01Y1702994D01*
G37*
G36*
G01X1291894D02*
G02X1292196Y1703296I302J0D01*
G01X1295896D01*
G02X1296198Y1702994I0J-302D01*
G01Y1692988D01*
G02X1295896Y1692686I-302J0D01*
G01X1292196D01*
G02X1291894Y1692988I0J302D01*
G01Y1695853D01*
G02X1291925Y1695986I302J0D01*
G01X1292844Y1697861D01*
G03Y1698123I-267J131D01*
G01X1291925Y1699998D01*
G02X1291894Y1700131I271J133D01*
G01Y1702994D01*
G37*
G36*
G01X1311580D02*
G02X1311882Y1703296I302J0D01*
G01X1315582D01*
G02X1315884Y1702994I0J-302D01*
G01Y1692988D01*
G02X1315582Y1692686I-302J0D01*
G01X1311882D01*
G02X1311580Y1692988I0J302D01*
G01Y1695853D01*
G02X1311611Y1695986I302J0D01*
G01X1312530Y1697861D01*
G03Y1698123I-267J131D01*
G01X1311611Y1699998D01*
G02X1311580Y1700131I271J133D01*
G01Y1702994D01*
G37*
G36*
G01X1327328D02*
G02X1327630Y1703296I302J0D01*
G01X1331330D01*
G02X1331632Y1702994I0J-302D01*
G01Y1692988D01*
G02X1331330Y1692686I-302J0D01*
G01X1327630D01*
G02X1327328Y1692988I0J302D01*
G01Y1695853D01*
G02X1327359Y1695986I302J0D01*
G01X1328278Y1697861D01*
G03Y1698123I-267J131D01*
G01X1327359Y1699998D01*
G02X1327328Y1700131I271J133D01*
G01Y1702994D01*
G37*
G36*
G01X1343076D02*
G02X1343378Y1703296I302J0D01*
G01X1347078D01*
G02X1347380Y1702994I0J-302D01*
G01Y1692988D01*
G02X1347078Y1692686I-302J0D01*
G01X1343378D01*
G02X1343076Y1692988I0J302D01*
G01Y1695853D01*
G02X1343107Y1695986I302J0D01*
G01X1344026Y1697861D01*
G03Y1698123I-267J131D01*
G01X1343107Y1699998D01*
G02X1343076Y1700131I271J133D01*
G01Y1702994D01*
G37*
G36*
G01X1358824D02*
G02X1359126Y1703296I302J0D01*
G01X1362826D01*
G02X1363128Y1702994I0J-302D01*
G01Y1692988D01*
G02X1362826Y1692686I-302J0D01*
G01X1359126D01*
G02X1358824Y1692988I0J302D01*
G01Y1695853D01*
G02X1358855Y1695986I302J0D01*
G01X1359774Y1697861D01*
G03Y1698123I-267J131D01*
G01X1358855Y1699998D01*
G02X1358824Y1700131I271J133D01*
G01Y1702994D01*
G37*
G36*
G01X1508824D02*
G02X1509126Y1703296I302J0D01*
G01X1512826D01*
G02X1513128Y1702994I0J-302D01*
G01Y1692988D01*
G02X1512826Y1692686I-302J0D01*
G01X1509126D01*
G02X1508824Y1692988I0J302D01*
G01Y1695853D01*
G02X1508855Y1695986I302J0D01*
G01X1509774Y1697861D01*
G03Y1698123I-267J131D01*
G01X1508855Y1699998D01*
G02X1508824Y1700131I271J133D01*
G01Y1702994D01*
G37*
G36*
G01X1524572D02*
G02X1524874Y1703296I302J0D01*
G01X1528574D01*
G02X1528876Y1702994I0J-302D01*
G01Y1692988D01*
G02X1528574Y1692686I-302J0D01*
G01X1524874D01*
G02X1524572Y1692988I0J302D01*
G01Y1695853D01*
G02X1524603Y1695986I302J0D01*
G01X1525522Y1697861D01*
G03Y1698123I-267J131D01*
G01X1524603Y1699998D01*
G02X1524572Y1700131I271J133D01*
G01Y1702994D01*
G37*
G36*
G01X1540320D02*
G02X1540622Y1703296I302J0D01*
G01X1544322D01*
G02X1544624Y1702994I0J-302D01*
G01Y1692988D01*
G02X1544322Y1692686I-302J0D01*
G01X1540622D01*
G02X1540320Y1692988I0J302D01*
G01Y1695853D01*
G02X1540351Y1695986I302J0D01*
G01X1541270Y1697861D01*
G03Y1698123I-267J131D01*
G01X1540351Y1699998D01*
G02X1540320Y1700131I271J133D01*
G01Y1702994D01*
G37*
G36*
G01X1556068D02*
G02X1556370Y1703296I302J0D01*
G01X1560070D01*
G02X1560372Y1702994I0J-302D01*
G01Y1692988D01*
G02X1560070Y1692686I-302J0D01*
G01X1556370D01*
G02X1556068Y1692988I0J302D01*
G01Y1695853D01*
G02X1556099Y1695986I302J0D01*
G01X1557018Y1697861D01*
G03Y1698123I-267J131D01*
G01X1556099Y1699998D01*
G02X1556068Y1700131I271J133D01*
G01Y1702994D01*
G37*
G36*
G01X1575754D02*
G02X1576056Y1703296I302J0D01*
G01X1579756D01*
G02X1580058Y1702994I0J-302D01*
G01Y1692988D01*
G02X1579756Y1692686I-302J0D01*
G01X1576056D01*
G02X1575754Y1692988I0J302D01*
G01Y1695853D01*
G02X1575785Y1695986I302J0D01*
G01X1576704Y1697861D01*
G03Y1698123I-267J131D01*
G01X1575785Y1699998D01*
G02X1575754Y1700131I271J133D01*
G01Y1702994D01*
G37*
G36*
G01X1591502D02*
G02X1591804Y1703296I302J0D01*
G01X1595504D01*
G02X1595806Y1702994I0J-302D01*
G01Y1692988D01*
G02X1595504Y1692686I-302J0D01*
G01X1591804D01*
G02X1591502Y1692988I0J302D01*
G01Y1695853D01*
G02X1591533Y1695986I302J0D01*
G01X1592452Y1697861D01*
G03Y1698123I-267J131D01*
G01X1591533Y1699998D01*
G02X1591502Y1700131I271J133D01*
G01Y1702994D01*
G37*
G36*
G01X1607250D02*
G02X1607552Y1703296I302J0D01*
G01X1611252D01*
G02X1611554Y1702994I0J-302D01*
G01Y1692988D01*
G02X1611252Y1692686I-302J0D01*
G01X1607552D01*
G02X1607250Y1692988I0J302D01*
G01Y1695853D01*
G02X1607281Y1695986I302J0D01*
G01X1608200Y1697861D01*
G03Y1698123I-267J131D01*
G01X1607281Y1699998D01*
G02X1607250Y1700131I271J133D01*
G01Y1702994D01*
G37*
G36*
G01X1622998D02*
G02X1623300Y1703296I302J0D01*
G01X1627000D01*
G02X1627302Y1702994I0J-302D01*
G01Y1692988D01*
G02X1627000Y1692686I-302J0D01*
G01X1623300D01*
G02X1622998Y1692988I0J302D01*
G01Y1695853D01*
G02X1623029Y1695986I302J0D01*
G01X1623948Y1697861D01*
G03Y1698123I-267J131D01*
G01X1623029Y1699998D01*
G02X1622998Y1700131I271J133D01*
G01Y1702994D01*
G37*
G36*
G01X228902Y1713230D02*
G02X229205Y1713532I303J-1D01*
G01X232907D01*
G02X233208Y1713230I-1J-302D01*
G01Y1703224D01*
G02X232905Y1702922I-303J1D01*
G01X229203D01*
G02X228902Y1703224I1J302D01*
G01Y1706088D01*
G02X228934Y1706221I302J-2D01*
G01Y1706223D01*
X229853Y1708097D01*
G03Y1708359I-267J131D01*
G01X228934Y1710233D01*
Y1710235D01*
G02X228902Y1710368I270J135D01*
G01Y1713230D01*
G37*
G36*
G01X244650D02*
G02X244953Y1713532I303J-1D01*
G01X248655D01*
G02X248956Y1713230I-1J-302D01*
G01Y1703224D01*
G02X248653Y1702922I-303J1D01*
G01X244951D01*
G02X244650Y1703224I1J302D01*
G01Y1706088D01*
G02X244682Y1706221I302J-2D01*
G01Y1706223D01*
X245601Y1708097D01*
G03Y1708359I-267J131D01*
G01X244682Y1710233D01*
Y1710235D01*
G02X244650Y1710368I270J135D01*
G01Y1713230D01*
G37*
G36*
G01X260398D02*
G02X260701Y1713532I303J-1D01*
G01X264403D01*
G02X264704Y1713230I-1J-302D01*
G01Y1703224D01*
G02X264401Y1702922I-303J1D01*
G01X260699D01*
G02X260398Y1703224I1J302D01*
G01Y1706088D01*
G02X260430Y1706221I302J-2D01*
G01Y1706223D01*
X261349Y1708097D01*
G03Y1708359I-267J131D01*
G01X260430Y1710233D01*
Y1710235D01*
G02X260398Y1710368I270J135D01*
G01Y1713230D01*
G37*
G36*
G01X276146D02*
G02X276449Y1713532I303J-1D01*
G01X280151D01*
G02X280452Y1713230I-1J-302D01*
G01Y1703224D01*
G02X280149Y1702922I-303J1D01*
G01X276447D01*
G02X276146Y1703224I1J302D01*
G01Y1706088D01*
G02X276178Y1706221I302J-2D01*
G01Y1706223D01*
X277097Y1708097D01*
G03Y1708359I-267J131D01*
G01X276178Y1710233D01*
Y1710235D01*
G02X276146Y1710368I270J135D01*
G01Y1713230D01*
G37*
G36*
G01X295832D02*
G02X296134Y1713532I302J0D01*
G01X299834D01*
G02X300136Y1713230I0J-302D01*
G01Y1703224D01*
G02X299834Y1702922I-302J0D01*
G01X296134D01*
G02X295832Y1703224I0J302D01*
G01Y1706089D01*
G02X295863Y1706222I302J0D01*
G01X296782Y1708097D01*
G03Y1708359I-267J131D01*
G01X295863Y1710234D01*
G02X295832Y1710367I271J133D01*
G01Y1713230D01*
G37*
G36*
G01X311580D02*
G02X311882Y1713532I302J0D01*
G01X315582D01*
G02X315884Y1713230I0J-302D01*
G01Y1703224D01*
G02X315582Y1702922I-302J0D01*
G01X311882D01*
G02X311580Y1703224I0J302D01*
G01Y1706089D01*
G02X311611Y1706222I302J0D01*
G01X312530Y1708097D01*
G03Y1708359I-267J131D01*
G01X311611Y1710234D01*
G02X311580Y1710367I271J133D01*
G01Y1713230D01*
G37*
G36*
G01X327328D02*
G02X327630Y1713532I302J0D01*
G01X331330D01*
G02X331632Y1713230I0J-302D01*
G01Y1703224D01*
G02X331330Y1702922I-302J0D01*
G01X327630D01*
G02X327328Y1703224I0J302D01*
G01Y1706089D01*
G02X327359Y1706222I302J0D01*
G01X328278Y1708097D01*
G03Y1708359I-267J131D01*
G01X327359Y1710234D01*
G02X327328Y1710367I271J133D01*
G01Y1713230D01*
G37*
G36*
G01X343076D02*
G02X343378Y1713532I302J0D01*
G01X347078D01*
G02X347380Y1713230I0J-302D01*
G01Y1703224D01*
G02X347078Y1702922I-302J0D01*
G01X343378D01*
G02X343076Y1703224I0J302D01*
G01Y1706089D01*
G02X343107Y1706222I302J0D01*
G01X344026Y1708097D01*
G03Y1708359I-267J131D01*
G01X343107Y1710234D01*
G02X343076Y1710367I271J133D01*
G01Y1713230D01*
G37*
G36*
G01X493076D02*
G02X493378Y1713532I302J0D01*
G01X497078D01*
G02X497380Y1713230I0J-302D01*
G01Y1703224D01*
G02X497078Y1702922I-302J0D01*
G01X493378D01*
G02X493076Y1703224I0J302D01*
G01Y1706089D01*
G02X493107Y1706222I302J0D01*
G01X494026Y1708097D01*
G03Y1708359I-267J131D01*
G01X493107Y1710234D01*
G02X493076Y1710367I271J133D01*
G01Y1713230D01*
G37*
G36*
G01X508824D02*
G02X509126Y1713532I302J0D01*
G01X512826D01*
G02X513128Y1713230I0J-302D01*
G01Y1703224D01*
G02X512826Y1702922I-302J0D01*
G01X509126D01*
G02X508824Y1703224I0J302D01*
G01Y1706089D01*
G02X508855Y1706222I302J0D01*
G01X509774Y1708097D01*
G03Y1708359I-267J131D01*
G01X508855Y1710234D01*
G02X508824Y1710367I271J133D01*
G01Y1713230D01*
G37*
G36*
G01X524572D02*
G02X524874Y1713532I302J0D01*
G01X528574D01*
G02X528876Y1713230I0J-302D01*
G01Y1703224D01*
G02X528574Y1702922I-302J0D01*
G01X524874D01*
G02X524572Y1703224I0J302D01*
G01Y1706089D01*
G02X524603Y1706222I302J0D01*
G01X525522Y1708097D01*
G03Y1708359I-267J131D01*
G01X524603Y1710234D01*
G02X524572Y1710367I271J133D01*
G01Y1713230D01*
G37*
G36*
G01X540320D02*
G02X540622Y1713532I302J0D01*
G01X544322D01*
G02X544624Y1713230I0J-302D01*
G01Y1703224D01*
G02X544322Y1702922I-302J0D01*
G01X540622D01*
G02X540320Y1703224I0J302D01*
G01Y1706089D01*
G02X540351Y1706222I302J0D01*
G01X541270Y1708097D01*
G03Y1708359I-267J131D01*
G01X540351Y1710234D01*
G02X540320Y1710367I271J133D01*
G01Y1713230D01*
G37*
G36*
G01X560004D02*
G02X560307Y1713532I303J-1D01*
G01X564009D01*
G02X564310Y1713230I-1J-302D01*
G01Y1703224D01*
G02X564007Y1702922I-303J1D01*
G01X560305D01*
G02X560004Y1703224I1J302D01*
G01Y1706088D01*
G02X560036Y1706221I302J-2D01*
G01Y1706223D01*
X560955Y1708097D01*
G03Y1708359I-267J131D01*
G01X560036Y1710233D01*
Y1710235D01*
G02X560004Y1710368I270J135D01*
G01Y1713230D01*
G37*
G36*
G01X575752D02*
G02X576055Y1713532I303J-1D01*
G01X579757D01*
G02X580058Y1713230I-1J-302D01*
G01Y1703224D01*
G02X579755Y1702922I-303J1D01*
G01X576053D01*
G02X575752Y1703224I1J302D01*
G01Y1706088D01*
G02X575784Y1706221I302J-2D01*
G01Y1706223D01*
X576703Y1708097D01*
G03Y1708359I-267J131D01*
G01X575784Y1710233D01*
Y1710235D01*
G02X575752Y1710368I270J135D01*
G01Y1713230D01*
G37*
G36*
G01X591500D02*
G02X591803Y1713532I303J-1D01*
G01X595505D01*
G02X595806Y1713230I-1J-302D01*
G01Y1703224D01*
G02X595503Y1702922I-303J1D01*
G01X591801D01*
G02X591500Y1703224I1J302D01*
G01Y1706088D01*
G02X591532Y1706221I302J-2D01*
G01Y1706223D01*
X592451Y1708097D01*
G03Y1708359I-267J131D01*
G01X591532Y1710233D01*
Y1710235D01*
G02X591500Y1710368I270J135D01*
G01Y1713230D01*
G37*
G36*
G01X607248D02*
G02X607551Y1713532I303J-1D01*
G01X611253D01*
G02X611554Y1713230I-1J-302D01*
G01Y1703224D01*
G02X611251Y1702922I-303J1D01*
G01X607549D01*
G02X607248Y1703224I1J302D01*
G01Y1706088D01*
G02X607280Y1706221I302J-2D01*
G01Y1706223D01*
X608199Y1708097D01*
G03Y1708359I-267J131D01*
G01X607280Y1710233D01*
Y1710235D01*
G02X607248Y1710368I270J135D01*
G01Y1713230D01*
G37*
G36*
G01X1236776D02*
G02X1237079Y1713532I303J-1D01*
G01X1240781D01*
G02X1241082Y1713230I-1J-302D01*
G01Y1703224D01*
G02X1240779Y1702922I-303J1D01*
G01X1237077D01*
G02X1236776Y1703224I1J302D01*
G01Y1706088D01*
G02X1236808Y1706221I302J-2D01*
G01Y1706223D01*
X1237727Y1708097D01*
G03Y1708359I-267J131D01*
G01X1236808Y1710233D01*
Y1710235D01*
G02X1236776Y1710368I270J135D01*
G01Y1713230D01*
G37*
G36*
G01X1252524D02*
G02X1252827Y1713532I303J-1D01*
G01X1256529D01*
G02X1256830Y1713230I-1J-302D01*
G01Y1703224D01*
G02X1256527Y1702922I-303J1D01*
G01X1252825D01*
G02X1252524Y1703224I1J302D01*
G01Y1706088D01*
G02X1252556Y1706221I302J-2D01*
G01Y1706223D01*
X1253475Y1708097D01*
G03Y1708359I-267J131D01*
G01X1252556Y1710233D01*
Y1710235D01*
G02X1252524Y1710368I270J135D01*
G01Y1713230D01*
G37*
G36*
G01X1268272D02*
G02X1268575Y1713532I303J-1D01*
G01X1272277D01*
G02X1272578Y1713230I-1J-302D01*
G01Y1703224D01*
G02X1272275Y1702922I-303J1D01*
G01X1268573D01*
G02X1268272Y1703224I1J302D01*
G01Y1706088D01*
G02X1268304Y1706221I302J-2D01*
G01Y1706223D01*
X1269223Y1708097D01*
G03Y1708359I-267J131D01*
G01X1268304Y1710233D01*
Y1710235D01*
G02X1268272Y1710368I270J135D01*
G01Y1713230D01*
G37*
G36*
G01X1284020D02*
G02X1284323Y1713532I303J-1D01*
G01X1288025D01*
G02X1288326Y1713230I-1J-302D01*
G01Y1703224D01*
G02X1288023Y1702922I-303J1D01*
G01X1284321D01*
G02X1284020Y1703224I1J302D01*
G01Y1706088D01*
G02X1284052Y1706221I302J-2D01*
G01Y1706223D01*
X1284971Y1708097D01*
G03Y1708359I-267J131D01*
G01X1284052Y1710233D01*
Y1710235D01*
G02X1284020Y1710368I270J135D01*
G01Y1713230D01*
G37*
G36*
G01X1303706D02*
G02X1304008Y1713532I302J0D01*
G01X1307708D01*
G02X1308010Y1713230I0J-302D01*
G01Y1703224D01*
G02X1307708Y1702922I-302J0D01*
G01X1304008D01*
G02X1303706Y1703224I0J302D01*
G01Y1706089D01*
G02X1303737Y1706222I302J0D01*
G01X1304656Y1708097D01*
G03Y1708359I-267J131D01*
G01X1303737Y1710234D01*
G02X1303706Y1710367I271J133D01*
G01Y1713230D01*
G37*
G36*
G01X1319454D02*
G02X1319756Y1713532I302J0D01*
G01X1323456D01*
G02X1323758Y1713230I0J-302D01*
G01Y1703224D01*
G02X1323456Y1702922I-302J0D01*
G01X1319756D01*
G02X1319454Y1703224I0J302D01*
G01Y1706089D01*
G02X1319485Y1706222I302J0D01*
G01X1320404Y1708097D01*
G03Y1708359I-267J131D01*
G01X1319485Y1710234D01*
G02X1319454Y1710367I271J133D01*
G01Y1713230D01*
G37*
G36*
G01X1335202D02*
G02X1335504Y1713532I302J0D01*
G01X1339204D01*
G02X1339506Y1713230I0J-302D01*
G01Y1703224D01*
G02X1339204Y1702922I-302J0D01*
G01X1335504D01*
G02X1335202Y1703224I0J302D01*
G01Y1706089D01*
G02X1335233Y1706222I302J0D01*
G01X1336152Y1708097D01*
G03Y1708359I-267J131D01*
G01X1335233Y1710234D01*
G02X1335202Y1710367I271J133D01*
G01Y1713230D01*
G37*
G36*
G01X1350950D02*
G02X1351252Y1713532I302J0D01*
G01X1354952D01*
G02X1355254Y1713230I0J-302D01*
G01Y1703224D01*
G02X1354952Y1702922I-302J0D01*
G01X1351252D01*
G02X1350950Y1703224I0J302D01*
G01Y1706089D01*
G02X1350981Y1706222I302J0D01*
G01X1351900Y1708097D01*
G03Y1708359I-267J131D01*
G01X1350981Y1710234D01*
G02X1350950Y1710367I271J133D01*
G01Y1713230D01*
G37*
G36*
G01X1500950D02*
G02X1501252Y1713532I302J0D01*
G01X1504952D01*
G02X1505254Y1713230I0J-302D01*
G01Y1703224D01*
G02X1504952Y1702922I-302J0D01*
G01X1501252D01*
G02X1500950Y1703224I0J302D01*
G01Y1706089D01*
G02X1500981Y1706222I302J0D01*
G01X1501900Y1708097D01*
G03Y1708359I-267J131D01*
G01X1500981Y1710234D01*
G02X1500950Y1710367I271J133D01*
G01Y1713230D01*
G37*
G36*
G01X1516698D02*
G02X1517000Y1713532I302J0D01*
G01X1520700D01*
G02X1521002Y1713230I0J-302D01*
G01Y1703224D01*
G02X1520700Y1702922I-302J0D01*
G01X1517000D01*
G02X1516698Y1703224I0J302D01*
G01Y1706089D01*
G02X1516729Y1706222I302J0D01*
G01X1517648Y1708097D01*
G03Y1708359I-267J131D01*
G01X1516729Y1710234D01*
G02X1516698Y1710367I271J133D01*
G01Y1713230D01*
G37*
G36*
G01X1532446D02*
G02X1532748Y1713532I302J0D01*
G01X1536448D01*
G02X1536750Y1713230I0J-302D01*
G01Y1703224D01*
G02X1536448Y1702922I-302J0D01*
G01X1532748D01*
G02X1532446Y1703224I0J302D01*
G01Y1706089D01*
G02X1532477Y1706222I302J0D01*
G01X1533396Y1708097D01*
G03Y1708359I-267J131D01*
G01X1532477Y1710234D01*
G02X1532446Y1710367I271J133D01*
G01Y1713230D01*
G37*
G36*
G01X1548194D02*
G02X1548496Y1713532I302J0D01*
G01X1552196D01*
G02X1552498Y1713230I0J-302D01*
G01Y1703224D01*
G02X1552196Y1702922I-302J0D01*
G01X1548496D01*
G02X1548194Y1703224I0J302D01*
G01Y1706089D01*
G02X1548225Y1706222I302J0D01*
G01X1549144Y1708097D01*
G03Y1708359I-267J131D01*
G01X1548225Y1710234D01*
G02X1548194Y1710367I271J133D01*
G01Y1713230D01*
G37*
G36*
G01X1567878D02*
G02X1568181Y1713532I303J-1D01*
G01X1571883D01*
G02X1572184Y1713230I-1J-302D01*
G01Y1703224D01*
G02X1571881Y1702922I-303J1D01*
G01X1568179D01*
G02X1567878Y1703224I1J302D01*
G01Y1706088D01*
G02X1567910Y1706221I302J-2D01*
G01Y1706223D01*
X1568829Y1708097D01*
G03Y1708359I-267J131D01*
G01X1567910Y1710233D01*
Y1710235D01*
G02X1567878Y1710368I270J135D01*
G01Y1713230D01*
G37*
G36*
G01X1583626D02*
G02X1583929Y1713532I303J-1D01*
G01X1587631D01*
G02X1587932Y1713230I-1J-302D01*
G01Y1703224D01*
G02X1587629Y1702922I-303J1D01*
G01X1583927D01*
G02X1583626Y1703224I1J302D01*
G01Y1706088D01*
G02X1583658Y1706221I302J-2D01*
G01Y1706223D01*
X1584577Y1708097D01*
G03Y1708359I-267J131D01*
G01X1583658Y1710233D01*
Y1710235D01*
G02X1583626Y1710368I270J135D01*
G01Y1713230D01*
G37*
G36*
G01X1599374D02*
G02X1599677Y1713532I303J-1D01*
G01X1603379D01*
G02X1603680Y1713230I-1J-302D01*
G01Y1703224D01*
G02X1603377Y1702922I-303J1D01*
G01X1599675D01*
G02X1599374Y1703224I1J302D01*
G01Y1706088D01*
G02X1599406Y1706221I302J-2D01*
G01Y1706223D01*
X1600325Y1708097D01*
G03Y1708359I-267J131D01*
G01X1599406Y1710233D01*
Y1710235D01*
G02X1599374Y1710368I270J135D01*
G01Y1713230D01*
G37*
G36*
G01X1615122D02*
G02X1615425Y1713532I303J-1D01*
G01X1619127D01*
G02X1619428Y1713230I-1J-302D01*
G01Y1703224D01*
G02X1619125Y1702922I-303J1D01*
G01X1615423D01*
G02X1615122Y1703224I1J302D01*
G01Y1706088D01*
G02X1615154Y1706221I302J-2D01*
G01Y1706223D01*
X1616073Y1708097D01*
G03Y1708359I-267J131D01*
G01X1615154Y1710233D01*
Y1710235D01*
G02X1615122Y1710368I270J135D01*
G01Y1713230D01*
G37*
G36*
G01X236776Y1717167D02*
G02X237079Y1717470I303J0D01*
G01X240779D01*
G02X241082Y1717167I0J-303D01*
G01Y1707161D01*
G02X240779Y1706858I-303J0D01*
G01X237079D01*
G02X236776Y1707161I0J303D01*
G01Y1710025D01*
G02X236808Y1710158I302J-2D01*
G01Y1710160D01*
X237727Y1712034D01*
G03Y1712296I-267J131D01*
G01X236808Y1714170D01*
Y1714172D01*
G02X236776Y1714305I270J135D01*
G01Y1717167D01*
G37*
G36*
G01X252524D02*
G02X252827Y1717470I303J0D01*
G01X256527D01*
G02X256830Y1717167I0J-303D01*
G01Y1707161D01*
G02X256527Y1706858I-303J0D01*
G01X252827D01*
G02X252524Y1707161I0J303D01*
G01Y1710025D01*
G02X252556Y1710158I302J-2D01*
G01Y1710160D01*
X253475Y1712034D01*
G03Y1712296I-267J131D01*
G01X252556Y1714170D01*
Y1714172D01*
G02X252524Y1714305I270J135D01*
G01Y1717167D01*
G37*
G36*
G01X268272D02*
G02X268575Y1717470I303J0D01*
G01X272275D01*
G02X272578Y1717167I0J-303D01*
G01Y1707161D01*
G02X272275Y1706858I-303J0D01*
G01X268575D01*
G02X268272Y1707161I0J303D01*
G01Y1710025D01*
G02X268304Y1710158I302J-2D01*
G01Y1710160D01*
X269223Y1712034D01*
G03Y1712296I-267J131D01*
G01X268304Y1714170D01*
Y1714172D01*
G02X268272Y1714305I270J135D01*
G01Y1717167D01*
G37*
G36*
G01X284020D02*
G02X284323Y1717470I303J0D01*
G01X288023D01*
G02X288326Y1717167I0J-303D01*
G01Y1707161D01*
G02X288023Y1706858I-303J0D01*
G01X284323D01*
G02X284020Y1707161I0J303D01*
G01Y1710025D01*
G02X284052Y1710158I302J-2D01*
G01Y1710160D01*
X284971Y1712034D01*
G03Y1712296I-267J131D01*
G01X284052Y1714170D01*
Y1714172D01*
G02X284020Y1714305I270J135D01*
G01Y1717167D01*
G37*
G36*
G01X303706D02*
G02X304008Y1717470I302J1D01*
G01X307708D01*
G02X308010Y1717167I-1J-303D01*
G01Y1707161D01*
G02X307708Y1706858I-302J-1D01*
G01X304008D01*
G02X303706Y1707161I1J303D01*
G01Y1710026D01*
G02X303737Y1710159I302J0D01*
G01X304656Y1712034D01*
G03Y1712296I-267J131D01*
G01X303737Y1714171D01*
G02X303706Y1714304I271J133D01*
G01Y1717167D01*
G37*
G36*
G01X319454D02*
G02X319756Y1717470I302J1D01*
G01X323456D01*
G02X323758Y1717167I-1J-303D01*
G01Y1707161D01*
G02X323456Y1706858I-302J-1D01*
G01X319756D01*
G02X319454Y1707161I1J303D01*
G01Y1710026D01*
G02X319485Y1710159I302J0D01*
G01X320404Y1712034D01*
G03Y1712296I-267J131D01*
G01X319485Y1714171D01*
G02X319454Y1714304I271J133D01*
G01Y1717167D01*
G37*
G36*
G01X335202D02*
G02X335504Y1717470I302J1D01*
G01X339204D01*
G02X339506Y1717167I-1J-303D01*
G01Y1707161D01*
G02X339204Y1706858I-302J-1D01*
G01X335504D01*
G02X335202Y1707161I1J303D01*
G01Y1710026D01*
G02X335233Y1710159I302J0D01*
G01X336152Y1712034D01*
G03Y1712296I-267J131D01*
G01X335233Y1714171D01*
G02X335202Y1714304I271J133D01*
G01Y1717167D01*
G37*
G36*
G01X350950D02*
G02X351252Y1717470I302J1D01*
G01X354952D01*
G02X355254Y1717167I-1J-303D01*
G01Y1707161D01*
G02X354952Y1706858I-302J-1D01*
G01X351252D01*
G02X350950Y1707161I1J303D01*
G01Y1710026D01*
G02X350981Y1710159I302J0D01*
G01X351900Y1712034D01*
G03Y1712296I-267J131D01*
G01X350981Y1714171D01*
G02X350950Y1714304I271J133D01*
G01Y1717167D01*
G37*
G36*
G01X500950D02*
G02X501252Y1717470I302J1D01*
G01X504952D01*
G02X505254Y1717167I-1J-303D01*
G01Y1707161D01*
G02X504952Y1706858I-302J-1D01*
G01X501252D01*
G02X500950Y1707161I1J303D01*
G01Y1710026D01*
G02X500981Y1710159I302J0D01*
G01X501900Y1712034D01*
G03Y1712296I-267J131D01*
G01X500981Y1714171D01*
G02X500950Y1714304I271J133D01*
G01Y1717167D01*
G37*
G36*
G01X516698D02*
G02X517000Y1717470I302J1D01*
G01X520700D01*
G02X521002Y1717167I-1J-303D01*
G01Y1707161D01*
G02X520700Y1706858I-302J-1D01*
G01X517000D01*
G02X516698Y1707161I1J303D01*
G01Y1710026D01*
G02X516729Y1710159I302J0D01*
G01X517648Y1712034D01*
G03Y1712296I-267J131D01*
G01X516729Y1714171D01*
G02X516698Y1714304I271J133D01*
G01Y1717167D01*
G37*
G36*
G01X532446D02*
G02X532748Y1717470I302J1D01*
G01X536448D01*
G02X536750Y1717167I-1J-303D01*
G01Y1707161D01*
G02X536448Y1706858I-302J-1D01*
G01X532748D01*
G02X532446Y1707161I1J303D01*
G01Y1710026D01*
G02X532477Y1710159I302J0D01*
G01X533396Y1712034D01*
G03Y1712296I-267J131D01*
G01X532477Y1714171D01*
G02X532446Y1714304I271J133D01*
G01Y1717167D01*
G37*
G36*
G01X548194D02*
G02X548496Y1717470I302J1D01*
G01X552196D01*
G02X552498Y1717167I-1J-303D01*
G01Y1707161D01*
G02X552196Y1706858I-302J-1D01*
G01X548496D01*
G02X548194Y1707161I1J303D01*
G01Y1710026D01*
G02X548225Y1710159I302J0D01*
G01X549144Y1712034D01*
G03Y1712296I-267J131D01*
G01X548225Y1714171D01*
G02X548194Y1714304I271J133D01*
G01Y1717167D01*
G37*
G36*
G01X567878D02*
G02X568181Y1717470I303J0D01*
G01X571881D01*
G02X572184Y1717167I0J-303D01*
G01Y1707161D01*
G02X571881Y1706858I-303J0D01*
G01X568181D01*
G02X567878Y1707161I0J303D01*
G01Y1710025D01*
G02X567910Y1710158I302J-2D01*
G01Y1710160D01*
X568829Y1712034D01*
G03Y1712296I-267J131D01*
G01X567910Y1714170D01*
Y1714172D01*
G02X567878Y1714305I270J135D01*
G01Y1717167D01*
G37*
G36*
G01X583626D02*
G02X583929Y1717470I303J0D01*
G01X587629D01*
G02X587932Y1717167I0J-303D01*
G01Y1707161D01*
G02X587629Y1706858I-303J0D01*
G01X583929D01*
G02X583626Y1707161I0J303D01*
G01Y1710025D01*
G02X583658Y1710158I302J-2D01*
G01Y1710160D01*
X584577Y1712034D01*
G03Y1712296I-267J131D01*
G01X583658Y1714170D01*
Y1714172D01*
G02X583626Y1714305I270J135D01*
G01Y1717167D01*
G37*
G36*
G01X599374D02*
G02X599677Y1717470I303J0D01*
G01X603377D01*
G02X603680Y1717167I0J-303D01*
G01Y1707161D01*
G02X603377Y1706858I-303J0D01*
G01X599677D01*
G02X599374Y1707161I0J303D01*
G01Y1710025D01*
G02X599406Y1710158I302J-2D01*
G01Y1710160D01*
X600325Y1712034D01*
G03Y1712296I-267J131D01*
G01X599406Y1714170D01*
Y1714172D01*
G02X599374Y1714305I270J135D01*
G01Y1717167D01*
G37*
G36*
G01X615122D02*
G02X615425Y1717470I303J0D01*
G01X619125D01*
G02X619428Y1717167I0J-303D01*
G01Y1707161D01*
G02X619125Y1706858I-303J0D01*
G01X615425D01*
G02X615122Y1707161I0J303D01*
G01Y1710025D01*
G02X615154Y1710158I302J-2D01*
G01Y1710160D01*
X616073Y1712034D01*
G03Y1712296I-267J131D01*
G01X615154Y1714170D01*
Y1714172D01*
G02X615122Y1714305I270J135D01*
G01Y1717167D01*
G37*
G36*
G01X1244650D02*
G02X1244953Y1717470I303J0D01*
G01X1248653D01*
G02X1248956Y1717167I0J-303D01*
G01Y1707161D01*
G02X1248653Y1706858I-303J0D01*
G01X1244953D01*
G02X1244650Y1707161I0J303D01*
G01Y1710025D01*
G02X1244682Y1710158I302J-2D01*
G01Y1710160D01*
X1245601Y1712034D01*
G03Y1712296I-267J131D01*
G01X1244682Y1714170D01*
Y1714172D01*
G02X1244650Y1714305I270J135D01*
G01Y1717167D01*
G37*
G36*
G01X1260398D02*
G02X1260701Y1717470I303J0D01*
G01X1264401D01*
G02X1264704Y1717167I0J-303D01*
G01Y1707161D01*
G02X1264401Y1706858I-303J0D01*
G01X1260701D01*
G02X1260398Y1707161I0J303D01*
G01Y1710025D01*
G02X1260430Y1710158I302J-2D01*
G01Y1710160D01*
X1261349Y1712034D01*
G03Y1712296I-267J131D01*
G01X1260430Y1714170D01*
Y1714172D01*
G02X1260398Y1714305I270J135D01*
G01Y1717167D01*
G37*
G36*
G01X1291894D02*
G02X1292197Y1717470I303J0D01*
G01X1295897D01*
G02X1296200Y1717167I0J-303D01*
G01Y1707161D01*
G02X1295897Y1706858I-303J0D01*
G01X1292197D01*
G02X1291894Y1707161I0J303D01*
G01Y1710025D01*
G02X1291926Y1710158I302J-2D01*
G01Y1710160D01*
X1292845Y1712034D01*
G03Y1712296I-267J131D01*
G01X1291926Y1714170D01*
Y1714172D01*
G02X1291894Y1714305I270J135D01*
G01Y1717167D01*
G37*
G36*
G01X1311580D02*
G02X1311882Y1717470I302J1D01*
G01X1315582D01*
G02X1315884Y1717167I-1J-303D01*
G01Y1707161D01*
G02X1315582Y1706858I-302J-1D01*
G01X1311882D01*
G02X1311580Y1707161I1J303D01*
G01Y1710026D01*
G02X1311611Y1710159I302J0D01*
G01X1312530Y1712034D01*
G03Y1712296I-267J131D01*
G01X1311611Y1714171D01*
G02X1311580Y1714304I271J133D01*
G01Y1717167D01*
G37*
G36*
G01X1327328D02*
G02X1327630Y1717470I302J1D01*
G01X1331330D01*
G02X1331632Y1717167I-1J-303D01*
G01Y1707161D01*
G02X1331330Y1706858I-302J-1D01*
G01X1327630D01*
G02X1327328Y1707161I1J303D01*
G01Y1710026D01*
G02X1327359Y1710159I302J0D01*
G01X1328278Y1712034D01*
G03Y1712296I-267J131D01*
G01X1327359Y1714171D01*
G02X1327328Y1714304I271J133D01*
G01Y1717167D01*
G37*
G36*
G01X1343076D02*
G02X1343378Y1717470I302J1D01*
G01X1347078D01*
G02X1347380Y1717167I-1J-303D01*
G01Y1707161D01*
G02X1347078Y1706858I-302J-1D01*
G01X1343378D01*
G02X1343076Y1707161I1J303D01*
G01Y1710026D01*
G02X1343107Y1710159I302J0D01*
G01X1344026Y1712034D01*
G03Y1712296I-267J131D01*
G01X1343107Y1714171D01*
G02X1343076Y1714304I271J133D01*
G01Y1717167D01*
G37*
G36*
G01X1358824D02*
G02X1359126Y1717470I302J1D01*
G01X1362826D01*
G02X1363128Y1717167I-1J-303D01*
G01Y1707161D01*
G02X1362826Y1706858I-302J-1D01*
G01X1359126D01*
G02X1358824Y1707161I1J303D01*
G01Y1710026D01*
G02X1358855Y1710159I302J0D01*
G01X1359774Y1712034D01*
G03Y1712296I-267J131D01*
G01X1358855Y1714171D01*
G02X1358824Y1714304I271J133D01*
G01Y1717167D01*
G37*
G36*
G01X1508824D02*
G02X1509126Y1717470I302J1D01*
G01X1512826D01*
G02X1513128Y1717167I-1J-303D01*
G01Y1707161D01*
G02X1512826Y1706858I-302J-1D01*
G01X1509126D01*
G02X1508824Y1707161I1J303D01*
G01Y1710026D01*
G02X1508855Y1710159I302J0D01*
G01X1509774Y1712034D01*
G03Y1712296I-267J131D01*
G01X1508855Y1714171D01*
G02X1508824Y1714304I271J133D01*
G01Y1717167D01*
G37*
G36*
G01X1524572D02*
G02X1524874Y1717470I302J1D01*
G01X1528574D01*
G02X1528876Y1717167I-1J-303D01*
G01Y1707161D01*
G02X1528574Y1706858I-302J-1D01*
G01X1524874D01*
G02X1524572Y1707161I1J303D01*
G01Y1710026D01*
G02X1524603Y1710159I302J0D01*
G01X1525522Y1712034D01*
G03Y1712296I-267J131D01*
G01X1524603Y1714171D01*
G02X1524572Y1714304I271J133D01*
G01Y1717167D01*
G37*
G36*
G01X1540320D02*
G02X1540622Y1717470I302J1D01*
G01X1544322D01*
G02X1544624Y1717167I-1J-303D01*
G01Y1707161D01*
G02X1544322Y1706858I-302J-1D01*
G01X1540622D01*
G02X1540320Y1707161I1J303D01*
G01Y1710026D01*
G02X1540351Y1710159I302J0D01*
G01X1541270Y1712034D01*
G03Y1712296I-267J131D01*
G01X1540351Y1714171D01*
G02X1540320Y1714304I271J133D01*
G01Y1717167D01*
G37*
G36*
G01X1556068D02*
G02X1556370Y1717470I302J1D01*
G01X1560070D01*
G02X1560372Y1717167I-1J-303D01*
G01Y1707161D01*
G02X1560070Y1706858I-302J-1D01*
G01X1556370D01*
G02X1556068Y1707161I1J303D01*
G01Y1710026D01*
G02X1556099Y1710159I302J0D01*
G01X1557018Y1712034D01*
G03Y1712296I-267J131D01*
G01X1556099Y1714171D01*
G02X1556068Y1714304I271J133D01*
G01Y1717167D01*
G37*
G36*
G01X1575752D02*
G02X1576055Y1717470I303J0D01*
G01X1579755D01*
G02X1580058Y1717167I0J-303D01*
G01Y1707161D01*
G02X1579755Y1706858I-303J0D01*
G01X1576055D01*
G02X1575752Y1707161I0J303D01*
G01Y1710025D01*
G02X1575784Y1710158I302J-2D01*
G01Y1710160D01*
X1576703Y1712034D01*
G03Y1712296I-267J131D01*
G01X1575784Y1714170D01*
Y1714172D01*
G02X1575752Y1714305I270J135D01*
G01Y1717167D01*
G37*
G36*
G01X1591500D02*
G02X1591803Y1717470I303J0D01*
G01X1595503D01*
G02X1595806Y1717167I0J-303D01*
G01Y1707161D01*
G02X1595503Y1706858I-303J0D01*
G01X1591803D01*
G02X1591500Y1707161I0J303D01*
G01Y1710025D01*
G02X1591532Y1710158I302J-2D01*
G01Y1710160D01*
X1592451Y1712034D01*
G03Y1712296I-267J131D01*
G01X1591532Y1714170D01*
Y1714172D01*
G02X1591500Y1714305I270J135D01*
G01Y1717167D01*
G37*
G36*
G01X1607248D02*
G02X1607551Y1717470I303J0D01*
G01X1611251D01*
G02X1611554Y1717167I0J-303D01*
G01Y1707161D01*
G02X1611251Y1706858I-303J0D01*
G01X1607551D01*
G02X1607248Y1707161I0J303D01*
G01Y1710025D01*
G02X1607280Y1710158I302J-2D01*
G01Y1710160D01*
X1608199Y1712034D01*
G03Y1712296I-267J131D01*
G01X1607280Y1714170D01*
Y1714172D01*
G02X1607248Y1714305I270J135D01*
G01Y1717167D01*
G37*
G36*
G01X1622996D02*
G02X1623299Y1717470I303J0D01*
G01X1626999D01*
G02X1627302Y1717167I0J-303D01*
G01Y1707161D01*
G02X1626999Y1706858I-303J0D01*
G01X1623299D01*
G02X1622996Y1707161I0J303D01*
G01Y1710025D01*
G02X1623028Y1710158I302J-2D01*
G01Y1710160D01*
X1623947Y1712034D01*
G03Y1712296I-267J131D01*
G01X1623028Y1714170D01*
Y1714172D01*
G02X1622996Y1714305I270J135D01*
G01Y1717167D01*
G37*
G36*
G01X815268Y1720554D02*
G02X816152Y1720920I884J-885D01*
G01X901868D01*
G02X902752Y1720554I0J-1251D01*
G01X906384Y1716922D01*
G02X906750Y1716038I-885J-884D01*
G01Y1662730D01*
G03X906809Y1662588I200J0D01*
G01X925253Y1644144D01*
G03X925395Y1644085I142J141D01*
G01X1071615D01*
G02X1072499Y1643719I0J-1251D01*
G01X1104694Y1611524D01*
G02X1105060Y1610640I-885J-884D01*
G01Y1554972D01*
G02X1104267Y1553063I-2700J2D01*
G01X1102758Y1551554D01*
G02X1102734Y1551530I-1921J1897D01*
G01X1102705Y1551502D01*
X1102674Y1551429D01*
X1102672Y1551104D01*
G03X1102731Y1550962I200J0D01*
G01X1105128Y1548565D01*
G02X1105494Y1547681I-885J-884D01*
G01Y1546325D01*
G03X1105553Y1546183I200J0D01*
G01X1106834Y1544902D01*
G02X1107200Y1544018I-885J-884D01*
G01Y1528142D01*
G03X1107318Y1527960I200J0D01*
G02Y1525222I-618J-1369D01*
G03X1107200Y1525040I82J-182D01*
G01Y1512882D01*
G02X1106834Y1511998I-1251J0D01*
G01X1104042Y1509206D01*
G02X1103158Y1508840I-884J885D01*
G01X1082180D01*
G02X1081296Y1509206I0J1251D01*
G01X1079878Y1510624D01*
G03X1079731Y1510683I-142J-141D01*
G01X1079443Y1510676D01*
G03X1079300Y1510611I5J-200D01*
G02X1079205Y1510512I-1995J1819D01*
G01X1078341Y1509648D01*
G03X1078339Y1509646I140J-142D01*
G01X1078143Y1509442D01*
G02X1077714Y1509153I-898J870D01*
G01X1077169Y1508932D01*
G02X1076699Y1508840I-471J1158D01*
G01X943079D01*
G02X941170Y1509633I2J2700D01*
G01X939306Y1511497D01*
G03X939304Y1511499I-142J-140D01*
G01X939100Y1511695D01*
G02X938811Y1512124I870J898D01*
G01X938590Y1512669D01*
G02X938498Y1513139I1158J471D01*
G01Y1547259D01*
G02X939291Y1549168I2700J-2D01*
G01X939871Y1549749D01*
G03Y1550031I-142J141D01*
G01X939599Y1550303D01*
G02X939233Y1551187I885J884D01*
G01Y1598406D01*
G03X939174Y1598548I-200J0D01*
G01X923627Y1614095D01*
G03X923485Y1614154I-142J-141D01*
G01X903722D01*
G02X902838Y1614520I0J1251D01*
G01X892956Y1624402D01*
G03X892814Y1624461I-142J-141D01*
G01X770836D01*
G02X769952Y1624827I0J1251D01*
G01X766466Y1628313D01*
G02X766100Y1629197I885J884D01*
G01Y1656302D01*
G02X766893Y1658211I2700J-2D01*
G01X799393Y1690712D01*
G03X799410Y1690974I-142J141D01*
G01X799171Y1691289D01*
G03X798913Y1691342I-159J-121D01*
G02X791281Y1689340I-7632J13548D01*
G01X791280D01*
G02X806830Y1704890I0J15550D01*
G01Y1704889D01*
G02X804828Y1697257I-15550J0D01*
G01X804791Y1697191D01*
X804821Y1697045D01*
X805197Y1696760D01*
G03X805459Y1696778I121J160D01*
G01X808681Y1700000D01*
G03X808740Y1700142I-141J142D01*
G01Y1713508D01*
G02X809106Y1714392I1251J0D01*
G01X815268Y1720554D01*
G37*
G36*
G01X435748Y1712135D02*
G02X446338I5295J6330D01*
G01X446297Y1712101D01*
X446260Y1712004D01*
X446322Y1711612D01*
G03X446443Y1711458I198J31D01*
G02X455296Y1698268I-5399J-13190D01*
G02X426790I-14253J0D01*
G02X435643Y1711458I14252J0D01*
G01X435692Y1711478D01*
X435756Y1711560D01*
X435826Y1712004D01*
X435789Y1712101D01*
X435748Y1712135D01*
G37*
G36*
G01X1411142D02*
G02X1421732I5295J6330D01*
G01X1421691Y1712101D01*
X1421654Y1712004D01*
X1421716Y1711612D01*
G03X1421837Y1711458I198J31D01*
G02X1430690Y1698268I-5399J-13190D01*
G02X1402184I-14253J0D01*
G02X1402186Y1698468I14253J-43D01*
G01X1402185D01*
G02X1411037Y1711458I14252J-201D01*
G01X1411086Y1711478D01*
X1411150Y1711560D01*
X1411219Y1712004D01*
X1411182Y1712102D01*
X1411142Y1712135D01*
G37*
G36*
G01X228902Y1727404D02*
G02X229205Y1727706I303J-1D01*
G01X232907D01*
G02X233208Y1727404I-1J-302D01*
G01Y1717398D01*
G02X232905Y1717096I-303J1D01*
G01X229203D01*
G02X228902Y1717398I1J302D01*
G01Y1727404D01*
G37*
G36*
G01X244650D02*
G02X244953Y1727706I303J-1D01*
G01X248655D01*
G02X248956Y1727404I-1J-302D01*
G01Y1717398D01*
G02X248653Y1717096I-303J1D01*
G01X244951D01*
G02X244650Y1717398I1J302D01*
G01Y1727404D01*
G37*
G36*
G01X260398D02*
G02X260701Y1727706I303J-1D01*
G01X264403D01*
G02X264704Y1727404I-1J-302D01*
G01Y1717398D01*
G02X264401Y1717096I-303J1D01*
G01X260699D01*
G02X260398Y1717398I1J302D01*
G01Y1727404D01*
G37*
G36*
G01X276146D02*
G02X276449Y1727706I303J-1D01*
G01X280151D01*
G02X280452Y1727404I-1J-302D01*
G01Y1717398D01*
G02X280149Y1717096I-303J1D01*
G01X276447D01*
G02X276146Y1717398I1J302D01*
G01Y1727404D01*
G37*
G36*
G01X295832D02*
G02X296134Y1727706I302J0D01*
G01X299834D01*
G02X300136Y1727404I0J-302D01*
G01Y1717398D01*
G02X299834Y1717096I-302J0D01*
G01X296134D01*
G02X295832Y1717398I0J302D01*
G01Y1727404D01*
G37*
G36*
G01X311580D02*
G02X311882Y1727706I302J0D01*
G01X315582D01*
G02X315884Y1727404I0J-302D01*
G01Y1717398D01*
G02X315582Y1717096I-302J0D01*
G01X311882D01*
G02X311580Y1717398I0J302D01*
G01Y1727404D01*
G37*
G36*
G01X327328D02*
G02X327630Y1727706I302J0D01*
G01X331330D01*
G02X331632Y1727404I0J-302D01*
G01Y1717398D01*
G02X331330Y1717096I-302J0D01*
G01X327630D01*
G02X327328Y1717398I0J302D01*
G01Y1727404D01*
G37*
G36*
G01X343076D02*
G02X343378Y1727706I302J0D01*
G01X347078D01*
G02X347380Y1727404I0J-302D01*
G01Y1717398D01*
G02X347078Y1717096I-302J0D01*
G01X343378D01*
G02X343076Y1717398I0J302D01*
G01Y1727404D01*
G37*
G36*
G01X493074Y1727405D02*
G02X493377Y1727708I303J0D01*
G01X497077D01*
G02X497380Y1727405I0J-303D01*
G01Y1717399D01*
G02X497077Y1717096I-303J0D01*
G01X493377D01*
G02X493074Y1717399I0J303D01*
G01Y1727405D01*
G37*
G36*
G01X508822D02*
G02X509125Y1727708I303J0D01*
G01X512825D01*
G02X513128Y1727405I0J-303D01*
G01Y1717399D01*
G02X512825Y1717096I-303J0D01*
G01X509125D01*
G02X508822Y1717399I0J303D01*
G01Y1727405D01*
G37*
G36*
G01X524570D02*
G02X524873Y1727708I303J0D01*
G01X528573D01*
G02X528876Y1727405I0J-303D01*
G01Y1717399D01*
G02X528573Y1717096I-303J0D01*
G01X524873D01*
G02X524570Y1717399I0J303D01*
G01Y1727405D01*
G37*
G36*
G01X540318D02*
G02X540621Y1727708I303J0D01*
G01X544321D01*
G02X544624Y1727405I0J-303D01*
G01Y1717399D01*
G02X544321Y1717096I-303J0D01*
G01X540621D01*
G02X540318Y1717399I0J303D01*
G01Y1727405D01*
G37*
G36*
G01X560004D02*
G02X560307Y1727708I303J0D01*
G01X564007D01*
G02X564310Y1727405I0J-303D01*
G01Y1717399D01*
G02X564007Y1717096I-303J0D01*
G01X560307D01*
G02X560004Y1717399I0J303D01*
G01Y1727405D01*
G37*
G36*
G01X575752D02*
G02X576055Y1727708I303J0D01*
G01X579755D01*
G02X580058Y1727405I0J-303D01*
G01Y1717399D01*
G02X579755Y1717096I-303J0D01*
G01X576055D01*
G02X575752Y1717399I0J303D01*
G01Y1727405D01*
G37*
G36*
G01X591500D02*
G02X591803Y1727708I303J0D01*
G01X595503D01*
G02X595806Y1727405I0J-303D01*
G01Y1717399D01*
G02X595503Y1717096I-303J0D01*
G01X591803D01*
G02X591500Y1717399I0J303D01*
G01Y1727405D01*
G37*
G36*
G01X607248D02*
G02X607551Y1727708I303J0D01*
G01X611251D01*
G02X611554Y1727405I0J-303D01*
G01Y1717399D01*
G02X611251Y1717096I-303J0D01*
G01X607551D01*
G02X607248Y1717399I0J303D01*
G01Y1727405D01*
G37*
G36*
G01X1236774D02*
G02X1237077Y1727708I303J0D01*
G01X1240777D01*
G02X1241080Y1727405I0J-303D01*
G01Y1717399D01*
G02X1240777Y1717096I-303J0D01*
G01X1237077D01*
G02X1236774Y1717399I0J303D01*
G01Y1727405D01*
G37*
G36*
G01X1252522D02*
G02X1252825Y1727708I303J0D01*
G01X1256525D01*
G02X1256828Y1727405I0J-303D01*
G01Y1717399D01*
G02X1256525Y1717096I-303J0D01*
G01X1252825D01*
G02X1252522Y1717399I0J303D01*
G01Y1727405D01*
G37*
G36*
G01X1268270D02*
G02X1268573Y1727708I303J0D01*
G01X1272273D01*
G02X1272576Y1727405I0J-303D01*
G01Y1717399D01*
G02X1272273Y1717096I-303J0D01*
G01X1268573D01*
G02X1268270Y1717399I0J303D01*
G01Y1727405D01*
G37*
G36*
G01X1284018D02*
G02X1284321Y1727708I303J0D01*
G01X1288021D01*
G02X1288324Y1727405I0J-303D01*
G01Y1717399D01*
G02X1288021Y1717096I-303J0D01*
G01X1284321D01*
G02X1284018Y1717399I0J303D01*
G01Y1727405D01*
G37*
G36*
G01X1303704D02*
G02X1304007Y1727708I303J0D01*
G01X1307707D01*
G02X1308010Y1727405I0J-303D01*
G01Y1717399D01*
G02X1307707Y1717096I-303J0D01*
G01X1304007D01*
G02X1303704Y1717399I0J303D01*
G01Y1727405D01*
G37*
G36*
G01X1319452D02*
G02X1319755Y1727708I303J0D01*
G01X1323455D01*
G02X1323758Y1727405I0J-303D01*
G01Y1717399D01*
G02X1323455Y1717096I-303J0D01*
G01X1319755D01*
G02X1319452Y1717399I0J303D01*
G01Y1727405D01*
G37*
G36*
G01X1335200D02*
G02X1335503Y1727708I303J0D01*
G01X1339203D01*
G02X1339506Y1727405I0J-303D01*
G01Y1717399D01*
G02X1339203Y1717096I-303J0D01*
G01X1335503D01*
G02X1335200Y1717399I0J303D01*
G01Y1727405D01*
G37*
G36*
G01X1350948D02*
G02X1351251Y1727708I303J0D01*
G01X1354951D01*
G02X1355254Y1727405I0J-303D01*
G01Y1717399D01*
G02X1354951Y1717096I-303J0D01*
G01X1351251D01*
G02X1350948Y1717399I0J303D01*
G01Y1727405D01*
G37*
G36*
G01X1500948D02*
G02X1501251Y1727708I303J0D01*
G01X1504951D01*
G02X1505254Y1727405I0J-303D01*
G01Y1717399D01*
G02X1504951Y1717096I-303J0D01*
G01X1501251D01*
G02X1500948Y1717399I0J303D01*
G01Y1727405D01*
G37*
G36*
G01X1516696D02*
G02X1516999Y1727708I303J0D01*
G01X1520699D01*
G02X1521002Y1727405I0J-303D01*
G01Y1717399D01*
G02X1520699Y1717096I-303J0D01*
G01X1516999D01*
G02X1516696Y1717399I0J303D01*
G01Y1727405D01*
G37*
G36*
G01X1532444D02*
G02X1532747Y1727708I303J0D01*
G01X1536447D01*
G02X1536750Y1727405I0J-303D01*
G01Y1717399D01*
G02X1536447Y1717096I-303J0D01*
G01X1532747D01*
G02X1532444Y1717399I0J303D01*
G01Y1727405D01*
G37*
G36*
G01X1548192D02*
G02X1548495Y1727708I303J0D01*
G01X1552195D01*
G02X1552498Y1727405I0J-303D01*
G01Y1717399D01*
G02X1552195Y1717096I-303J0D01*
G01X1548495D01*
G02X1548192Y1717399I0J303D01*
G01Y1727405D01*
G37*
G36*
G01X1567878D02*
G02X1568181Y1727708I303J0D01*
G01X1571881D01*
G02X1572184Y1727405I0J-303D01*
G01Y1717399D01*
G02X1571881Y1717096I-303J0D01*
G01X1568181D01*
G02X1567878Y1717399I0J303D01*
G01Y1727405D01*
G37*
G36*
G01X1583626D02*
G02X1583929Y1727708I303J0D01*
G01X1587629D01*
G02X1587932Y1727405I0J-303D01*
G01Y1717399D01*
G02X1587629Y1717096I-303J0D01*
G01X1583929D01*
G02X1583626Y1717399I0J303D01*
G01Y1727405D01*
G37*
G36*
G01X1599374D02*
G02X1599677Y1727708I303J0D01*
G01X1603377D01*
G02X1603680Y1727405I0J-303D01*
G01Y1717399D01*
G02X1603377Y1717096I-303J0D01*
G01X1599677D01*
G02X1599374Y1717399I0J303D01*
G01Y1727405D01*
G37*
G36*
G01X1615122D02*
G02X1615425Y1727708I303J0D01*
G01X1619125D01*
G02X1619428Y1727405I0J-303D01*
G01Y1717399D01*
G02X1619125Y1717096I-303J0D01*
G01X1615425D01*
G02X1615122Y1717399I0J303D01*
G01Y1727405D01*
G37*
G36*
G01X236776Y1731341D02*
G02X237079Y1731644I303J0D01*
G01X240779D01*
G02X241082Y1731341I0J-303D01*
G01Y1721335D01*
G02X240779Y1721032I-303J0D01*
G01X237079D01*
G02X236776Y1721335I0J303D01*
G01Y1731341D01*
G37*
G36*
G01X252524D02*
G02X252827Y1731644I303J0D01*
G01X256527D01*
G02X256830Y1731341I0J-303D01*
G01Y1721335D01*
G02X256527Y1721032I-303J0D01*
G01X252827D01*
G02X252524Y1721335I0J303D01*
G01Y1731341D01*
G37*
G36*
G01X268272D02*
G02X268575Y1731644I303J0D01*
G01X272275D01*
G02X272578Y1731341I0J-303D01*
G01Y1721335D01*
G02X272275Y1721032I-303J0D01*
G01X268575D01*
G02X268272Y1721335I0J303D01*
G01Y1731341D01*
G37*
G36*
G01X284020D02*
G02X284323Y1731644I303J0D01*
G01X288023D01*
G02X288326Y1731341I0J-303D01*
G01Y1721335D01*
G02X288023Y1721032I-303J0D01*
G01X284323D01*
G02X284020Y1721335I0J303D01*
G01Y1731341D01*
G37*
G36*
G01X303706D02*
G02X304008Y1731644I302J1D01*
G01X307708D01*
G02X308010Y1731341I-1J-303D01*
G01Y1721335D01*
G02X307708Y1721032I-302J-1D01*
G01X304008D01*
G02X303706Y1721335I1J303D01*
G01Y1731341D01*
G37*
G36*
G01X319454D02*
G02X319756Y1731644I302J1D01*
G01X323456D01*
G02X323758Y1731341I-1J-303D01*
G01Y1721335D01*
G02X323456Y1721032I-302J-1D01*
G01X319756D01*
G02X319454Y1721335I1J303D01*
G01Y1731341D01*
G37*
G36*
G01X335202D02*
G02X335504Y1731644I302J1D01*
G01X339204D01*
G02X339506Y1731341I-1J-303D01*
G01Y1721335D01*
G02X339204Y1721032I-302J-1D01*
G01X335504D01*
G02X335202Y1721335I1J303D01*
G01Y1731341D01*
G37*
G36*
G01X350950D02*
G02X351252Y1731644I302J1D01*
G01X354952D01*
G02X355254Y1731341I-1J-303D01*
G01Y1721335D01*
G02X354952Y1721032I-302J-1D01*
G01X351252D01*
G02X350950Y1721335I1J303D01*
G01Y1731341D01*
G37*
G36*
G01X500948Y1731342D02*
G02X501251Y1731644I303J-1D01*
G01X504953D01*
G02X505254Y1731342I-1J-302D01*
G01Y1721336D01*
G02X504951Y1721034I-303J1D01*
G01X501249D01*
G02X500948Y1721336I1J302D01*
G01Y1731342D01*
G37*
G36*
G01X516696D02*
G02X516999Y1731644I303J-1D01*
G01X520701D01*
G02X521002Y1731342I-1J-302D01*
G01Y1721336D01*
G02X520699Y1721034I-303J1D01*
G01X516997D01*
G02X516696Y1721336I1J302D01*
G01Y1731342D01*
G37*
G36*
G01X532444D02*
G02X532747Y1731644I303J-1D01*
G01X536449D01*
G02X536750Y1731342I-1J-302D01*
G01Y1721336D01*
G02X536447Y1721034I-303J1D01*
G01X532745D01*
G02X532444Y1721336I1J302D01*
G01Y1731342D01*
G37*
G36*
G01X548192D02*
G02X548495Y1731644I303J-1D01*
G01X552197D01*
G02X552498Y1731342I-1J-302D01*
G01Y1721336D01*
G02X552195Y1721034I-303J1D01*
G01X548493D01*
G02X548192Y1721336I1J302D01*
G01Y1731342D01*
G37*
G36*
G01X567878D02*
G02X568181Y1731644I303J-1D01*
G01X571883D01*
G02X572184Y1731342I-1J-302D01*
G01Y1721336D01*
G02X571881Y1721034I-303J1D01*
G01X568179D01*
G02X567878Y1721336I1J302D01*
G01Y1731342D01*
G37*
G36*
G01X583626D02*
G02X583929Y1731644I303J-1D01*
G01X587631D01*
G02X587932Y1731342I-1J-302D01*
G01Y1721336D01*
G02X587629Y1721034I-303J1D01*
G01X583927D01*
G02X583626Y1721336I1J302D01*
G01Y1731342D01*
G37*
G36*
G01X599374D02*
G02X599677Y1731644I303J-1D01*
G01X603379D01*
G02X603680Y1731342I-1J-302D01*
G01Y1721336D01*
G02X603377Y1721034I-303J1D01*
G01X599675D01*
G02X599374Y1721336I1J302D01*
G01Y1731342D01*
G37*
G36*
G01X615122D02*
G02X615425Y1731644I303J-1D01*
G01X619127D01*
G02X619428Y1731342I-1J-302D01*
G01Y1721336D01*
G02X619125Y1721034I-303J1D01*
G01X615423D01*
G02X615122Y1721336I1J302D01*
G01Y1731342D01*
G37*
G36*
G01X1244648D02*
G02X1244951Y1731644I303J-1D01*
G01X1248653D01*
G02X1248954Y1731342I-1J-302D01*
G01Y1721336D01*
G02X1248651Y1721034I-303J1D01*
G01X1244949D01*
G02X1244648Y1721336I1J302D01*
G01Y1731342D01*
G37*
G36*
G01X1260396D02*
G02X1260699Y1731644I303J-1D01*
G01X1264401D01*
G02X1264702Y1731342I-1J-302D01*
G01Y1721336D01*
G02X1264399Y1721034I-303J1D01*
G01X1260697D01*
G02X1260396Y1721336I1J302D01*
G01Y1731342D01*
G37*
G36*
G01X1276144D02*
G02X1276447Y1731644I303J-1D01*
G01X1280149D01*
G02X1280450Y1731342I-1J-302D01*
G01Y1717194D01*
G02X1280452Y1717167I-300J-36D01*
G01Y1707161D01*
G02X1280149Y1706858I-303J0D01*
G01X1276449D01*
G02X1276146Y1707161I0J303D01*
G01Y1710025D01*
G02X1276178Y1710158I302J-2D01*
G01Y1710160D01*
X1277097Y1712034D01*
G03Y1712296I-267J131D01*
G01X1276178Y1714170D01*
Y1714172D01*
G02X1276146Y1714305I270J135D01*
G01Y1716585D01*
G02X1276144Y1716612I300J36D01*
G01Y1718101D01*
G03X1276121Y1718193I-200J-1D01*
G02Y1720309I2027J1058D01*
G03X1276144Y1720401I-177J93D01*
G01Y1731342D01*
G37*
G36*
G01X1291892D02*
G02X1292195Y1731644I303J-1D01*
G01X1295897D01*
G02X1296198Y1731342I-1J-302D01*
G01Y1721336D01*
G02X1295895Y1721034I-303J1D01*
G01X1292193D01*
G02X1291892Y1721336I1J302D01*
G01Y1731342D01*
G37*
G36*
G01X1311578D02*
G02X1311881Y1731644I303J-1D01*
G01X1315583D01*
G02X1315884Y1731342I-1J-302D01*
G01Y1721336D01*
G02X1315581Y1721034I-303J1D01*
G01X1311879D01*
G02X1311578Y1721336I1J302D01*
G01Y1731342D01*
G37*
G36*
G01X1327326D02*
G02X1327629Y1731644I303J-1D01*
G01X1331331D01*
G02X1331632Y1731342I-1J-302D01*
G01Y1721336D01*
G02X1331329Y1721034I-303J1D01*
G01X1327627D01*
G02X1327326Y1721336I1J302D01*
G01Y1731342D01*
G37*
G36*
G01X1343074D02*
G02X1343377Y1731644I303J-1D01*
G01X1347079D01*
G02X1347380Y1731342I-1J-302D01*
G01Y1721336D01*
G02X1347077Y1721034I-303J1D01*
G01X1343375D01*
G02X1343074Y1721336I1J302D01*
G01Y1731342D01*
G37*
G36*
G01X1358822D02*
G02X1359125Y1731644I303J-1D01*
G01X1362827D01*
G02X1363128Y1731342I-1J-302D01*
G01Y1721336D01*
G02X1362825Y1721034I-303J1D01*
G01X1359123D01*
G02X1358822Y1721336I1J302D01*
G01Y1731342D01*
G37*
G36*
G01X1508822D02*
G02X1509125Y1731644I303J-1D01*
G01X1512827D01*
G02X1513128Y1731342I-1J-302D01*
G01Y1721336D01*
G02X1512825Y1721034I-303J1D01*
G01X1509123D01*
G02X1508822Y1721336I1J302D01*
G01Y1731342D01*
G37*
G36*
G01X1524570D02*
G02X1524873Y1731644I303J-1D01*
G01X1528575D01*
G02X1528876Y1731342I-1J-302D01*
G01Y1721336D01*
G02X1528573Y1721034I-303J1D01*
G01X1524871D01*
G02X1524570Y1721336I1J302D01*
G01Y1731342D01*
G37*
G36*
G01X1540318D02*
G02X1540621Y1731644I303J-1D01*
G01X1544323D01*
G02X1544624Y1731342I-1J-302D01*
G01Y1721336D01*
G02X1544321Y1721034I-303J1D01*
G01X1540619D01*
G02X1540318Y1721336I1J302D01*
G01Y1731342D01*
G37*
G36*
G01X1556066D02*
G02X1556369Y1731644I303J-1D01*
G01X1560071D01*
G02X1560372Y1731342I-1J-302D01*
G01Y1721336D01*
G02X1560069Y1721034I-303J1D01*
G01X1556367D01*
G02X1556066Y1721336I1J302D01*
G01Y1731342D01*
G37*
G36*
G01X1575752D02*
G02X1576055Y1731644I303J-1D01*
G01X1579757D01*
G02X1580058Y1731342I-1J-302D01*
G01Y1721336D01*
G02X1579755Y1721034I-303J1D01*
G01X1576053D01*
G02X1575752Y1721336I1J302D01*
G01Y1731342D01*
G37*
G36*
G01X1591500D02*
G02X1591803Y1731644I303J-1D01*
G01X1595505D01*
G02X1595806Y1731342I-1J-302D01*
G01Y1721336D01*
G02X1595503Y1721034I-303J1D01*
G01X1591801D01*
G02X1591500Y1721336I1J302D01*
G01Y1731342D01*
G37*
G36*
G01X1607248D02*
G02X1607551Y1731644I303J-1D01*
G01X1611253D01*
G02X1611554Y1731342I-1J-302D01*
G01Y1721336D01*
G02X1611251Y1721034I-303J1D01*
G01X1607549D01*
G02X1607248Y1721336I1J302D01*
G01Y1731342D01*
G37*
G36*
G01X1622996D02*
G02X1623299Y1731644I303J-1D01*
G01X1627001D01*
G02X1627302Y1731342I-1J-302D01*
G01Y1721336D01*
G02X1626999Y1721034I-303J1D01*
G01X1623297D01*
G02X1622996Y1721336I1J302D01*
G01Y1731342D01*
G37*
G54D89*
X1472893Y1063134D03*
X1469192D03*
X1472893Y1069512D03*
X1469192D03*
X1472893Y1075890D03*
X1469192D03*
X1450688Y1069512D03*
X1446987D03*
X1461791Y1075890D03*
X1458090D03*
X1461791Y1069512D03*
X1458090D03*
X1461791Y1063134D03*
X1458090D03*
X1450688D03*
X1446987D03*
X1450688Y1075890D03*
X1446987D03*
X1439586D03*
X1435885D03*
X1439586Y1069512D03*
X1435885D03*
X1439586Y1063134D03*
X1435885D03*
X1430334Y1059945D03*
X1426633D03*
X1430334Y1066323D03*
X1426633D03*
X1430334Y1072701D03*
X1426633D03*
X1430334Y1079079D03*
X1426633D03*
X1408154D03*
X1404453D03*
X1408154Y1072701D03*
X1404453D03*
X1408154Y1066323D03*
X1404453D03*
X1408154Y1059945D03*
X1404453D03*
X1398902Y1063134D03*
X1395201D03*
X1398902Y1069512D03*
X1395201D03*
X1398902Y1075890D03*
X1395201D03*
X1387800Y1063134D03*
X1384099D03*
X1387800Y1069512D03*
X1384099D03*
X1387800Y1075890D03*
X1384099D03*
X1376697Y1069512D03*
X1372996D03*
X1376697Y1075890D03*
X1372996D03*
X1376697Y1063134D03*
X1372996D03*
X1365595D03*
X1361894D03*
X1365595Y1069512D03*
X1361894D03*
X1365595Y1075890D03*
X1361894D03*
X496751Y1063135D03*
X493050D03*
X496751Y1069513D03*
X493050D03*
X496751Y1075891D03*
X493050D03*
X485649Y1063135D03*
X481948D03*
X485649Y1069513D03*
X481948D03*
X485649Y1075891D03*
X481948D03*
X474546Y1063135D03*
X470845D03*
X474546Y1069513D03*
X470845D03*
X474546Y1075891D03*
X470845D03*
X463444Y1063135D03*
X459743D03*
X463444Y1069513D03*
X459743D03*
X463444Y1075891D03*
X459743D03*
X454192Y1059946D03*
X450491D03*
X454192Y1066324D03*
X450491D03*
X454192Y1072702D03*
X450491D03*
X454192Y1079080D03*
X450491D03*
X432012Y1059946D03*
X428311D03*
X432012Y1066324D03*
X428311D03*
X432012Y1072702D03*
X428311D03*
X432012Y1079080D03*
X428311D03*
X422760Y1063135D03*
X419059D03*
X422760Y1069513D03*
X419059D03*
X422760Y1075891D03*
X419059D03*
X411658Y1063135D03*
X407957D03*
X411658Y1069513D03*
X407957D03*
X411658Y1075891D03*
X407957D03*
X400555Y1063135D03*
X396854D03*
X400555Y1069513D03*
X396854D03*
X400555Y1075891D03*
X396854D03*
X389453Y1063135D03*
X385752D03*
X389453Y1069513D03*
X385752D03*
Y1075891D03*
X389453D03*
G54D110*
X766889Y1486756D03*
Y1530256D03*
G54D92*
X263316Y87665D03*
X712291Y106722D03*
X820901Y147112D03*
X1005307Y155043D03*
X101675Y160694D03*
X1571516Y319099D03*
X1290127Y410635D03*
X788710Y1488821D03*
G54D88*
X398673Y-18871D03*
Y-8871D03*
X373673D03*
Y-18871D03*
X398673Y-28871D03*
X373673D03*
X718093Y-8871D03*
Y-18871D03*
X743093D03*
Y-8871D03*
X718093Y-28871D03*
X743093D03*
X850152Y-5011D03*
X825152D03*
X850152Y-15011D03*
X825152D03*
X850152Y-35011D03*
Y-25011D03*
X825152D03*
Y-35011D03*
X850152Y4989D03*
X825152D03*
X850152Y14989D03*
X825152D03*
X850152Y24989D03*
X825152D03*
X1169572Y-5011D03*
X1194572D03*
X1169572Y-15011D03*
X1194572D03*
X1169572Y-25011D03*
Y-35011D03*
X1194572D03*
Y-25011D03*
X1169572Y4989D03*
X1194572D03*
X1169572Y14989D03*
X1194572D03*
X1169572Y24989D03*
X1194572D03*
X1253672Y-15011D03*
X1228672D03*
X1253672Y-35011D03*
Y-25011D03*
X1228672D03*
Y-35011D03*
X1253672Y-5011D03*
X1228672D03*
X1253672Y4989D03*
Y14989D03*
X1228672D03*
Y4989D03*
X1253672Y24989D03*
X1228672D03*
X1428431Y-15011D03*
X1453431D03*
X1428431Y-25011D03*
Y-35011D03*
X1453431D03*
Y-25011D03*
X1428431Y-5011D03*
X1453431D03*
X1428431Y14989D03*
Y4989D03*
X1453431D03*
Y14989D03*
X1428431Y24989D03*
X1453431D03*
X1546966Y-39212D03*
Y-29212D03*
X1521966D03*
Y-39212D03*
X1546966Y-19212D03*
X1521966D03*
X1721725Y-29212D03*
Y-39212D03*
X1746725D03*
Y-29212D03*
X1721725Y-19212D03*
X1746725D03*
G54D90*
X60303Y20354D03*
X1534712D03*
X505185Y41141D03*
G54D91*
X312921Y24291D03*
X1787330D03*
X929331Y160413D03*
X922441Y237697D03*
G54D99*
X676509Y224606D03*
G54D97*
Y145866D03*
G54D112*
X1066280Y1704890D03*
G54D107*
X1340948Y1179681D03*
G54D102*
X433624Y594259D03*
X1415690Y601230D03*
X1487677Y640145D03*
X1524437Y640365D03*
X326731Y653394D03*
X363731D03*
X1291146Y1375715D03*
X1320516D03*
X1166535Y1412479D03*
X1700840Y1424519D03*
X754645Y1426892D03*
G54D93*
X526460Y99195D03*
X400426Y114515D03*
X553780Y122940D03*
X570860Y123010D03*
X417486Y125879D03*
X35852Y668745D03*
Y679710D03*
Y690616D03*
Y701522D03*
X372000Y833497D03*
Y844727D03*
X1342036Y1204729D03*
X313284Y1216822D03*
X390974Y1221149D03*
X388630Y1238447D03*
X814296Y1385745D03*
X50880Y1417263D03*
X558876Y1456605D03*
X1115098Y1470571D03*
X427286Y1481890D03*
X555348D03*
X544794Y1482382D03*
X672856D03*
X544794Y1495782D03*
X672856D03*
X427286Y1503690D03*
X555348D03*
X1170986Y1514890D03*
X1299048D03*
X1435160D03*
X1563222D03*
X1288494Y1515382D03*
X1416556D03*
X1552668D03*
X1680730D03*
X426704Y1525031D03*
X554766D03*
X1288494Y1528782D03*
X1416556D03*
X1552668D03*
X1680730D03*
X1170986Y1536690D03*
X1299048D03*
X1435160D03*
X1563222D03*
X188254Y1546697D03*
X192978D03*
X207152D03*
X211876D03*
X226050D03*
X230774D03*
X254396D03*
X259120D03*
X316316D03*
X321040D03*
X335214D03*
X339938D03*
X354112D03*
X358836D03*
X382458D03*
X387182D03*
X461876D03*
X466600D03*
X480774D03*
X485498D03*
X499672D03*
X504396D03*
X509120D03*
X513844D03*
X589938D03*
X594662D03*
X608836D03*
X613560D03*
X627734D03*
X632458D03*
X637182D03*
X641906D03*
X1170404Y1558031D03*
X1298466D03*
X1434578D03*
X1562640D03*
X1205576Y1579697D03*
X1210300D03*
X1224474D03*
X1229198D03*
X1243372D03*
X1248096D03*
X1252820D03*
X1257544D03*
X1333638D03*
X1338362D03*
X1352536D03*
X1357260D03*
X1371434D03*
X1376158D03*
X1380882D03*
X1385606D03*
X1469750D03*
X1474474D03*
X1488648D03*
X1493372D03*
X1507546D03*
X1512270D03*
X1516994D03*
X1521718D03*
X1597812D03*
X1602536D03*
X1616710D03*
X1621434D03*
X1635608D03*
X1640332D03*
X1645056D03*
X1649780D03*
X1131824Y1602293D03*
X436776Y1612094D03*
X142576Y1641863D03*
X1141084Y1644972D03*
X1090958Y1648228D03*
X40922Y1656569D03*
X85836Y1656843D03*
X165336Y1676777D03*
G54D111*
X138071Y1482244D03*
X698819D03*
X1145945Y1515236D03*
X1706693D03*
X163662Y1593661D03*
X673228D03*
X1171536Y1626654D03*
X1681102D03*
G54D94*
X559069Y103685D03*
X482255Y131522D03*
X704771Y169488D03*
X716699Y175387D03*
X704771Y181299D03*
X716699Y187387D03*
X704771Y193110D03*
X716699Y198887D03*
X704771Y204921D03*
X716699Y210721D03*
X704771Y216732D03*
X1007587Y763246D03*
Y774180D03*
Y785182D03*
Y796184D03*
Y807118D03*
X385001Y815227D03*
X1007587Y818052D03*
X371999Y821227D03*
X1007587Y829054D03*
Y840056D03*
X1315657Y1197832D03*
X1346063Y1216029D03*
X1370685Y1224732D03*
X58349Y1408031D03*
X653999Y1425057D03*
X546253Y1455807D03*
X163113Y1481890D03*
X291175D03*
X280621Y1482382D03*
X408683D03*
X280621Y1495782D03*
X408683D03*
X163113Y1503690D03*
X291175D03*
X162531Y1525031D03*
X290593D03*
X197703Y1546697D03*
X202427D03*
X216601D03*
X221325D03*
X235499D03*
X240223D03*
X244947D03*
X249671D03*
X325765D03*
X330489D03*
X344663D03*
X349387D03*
X363561D03*
X368285D03*
X373009D03*
X377733D03*
X452427D03*
X457151D03*
X471325D03*
X476049D03*
X490223D03*
X494947D03*
X518569D03*
X523293D03*
X580489D03*
X585213D03*
X599387D03*
X604111D03*
X618285D03*
X623009D03*
X646631D03*
X651355D03*
X1196127Y1579697D03*
X1200851D03*
X1215025D03*
X1219749D03*
X1233923D03*
X1238647D03*
X1262269D03*
X1266993D03*
X1324189D03*
X1328913D03*
X1343087D03*
X1347811D03*
X1361985D03*
X1366709D03*
X1390331D03*
X1395055D03*
X1460301D03*
X1465025D03*
X1479199D03*
X1483923D03*
X1498097D03*
X1502821D03*
X1526443D03*
X1531167D03*
X1588363D03*
X1593087D03*
X1607261D03*
X1611985D03*
X1626159D03*
X1630883D03*
X1654505D03*
X1659229D03*
X1142917Y1585014D03*
X1118133Y1589698D03*
X403837Y1610756D03*
X154945Y1626050D03*
X163735Y1633669D03*
X193679Y1641752D03*
X307255Y1645450D03*
X205479Y1650430D03*
X1146501Y1653908D03*
X297323Y1655472D03*
X99443Y1660231D03*
X165491Y1663882D03*
X87891Y1672821D03*
X41679Y1675023D03*
X100443Y1685763D03*
G54D113*
X1766929Y1714960D03*
G54D95*
X516020Y107320D03*
X535170Y113180D03*
X405606Y127765D03*
X80948Y523563D03*
X80318Y541363D03*
G54D103*
X117933Y605376D03*
X1094076Y605378D03*
X1739745Y605411D03*
X763602Y605413D03*
G54D86*
X1729562Y-24215D03*
Y-34215D03*
X1436268Y9986D03*
Y-14D03*
Y-20014D03*
Y-30014D03*
X725930Y-13874D03*
Y-23874D03*
X390846Y-13874D03*
Y-23874D03*
G54D85*
X1837795Y18819D03*
X19685Y-29134D03*
X1800449Y126194D03*
X44000Y154200D03*
X31818Y1424257D03*
X1804650Y1667292D03*
X441043Y1672205D03*
X1416437D03*
X1885039Y49021D03*
X2081889Y-29134D03*
X2081889Y1803261D03*
X1871260Y1291627D03*
G54D101*
X62813Y414050D03*
X47619Y417134D03*
X1025493Y763769D03*
G54D98*
X805690Y204724D03*
X1057659D03*
G54D96*
X1829921Y130314D03*
G54D87*
X1539139Y-24215D03*
Y-34215D03*
X1245845Y9986D03*
Y-14D03*
Y-20014D03*
Y-30014D03*
X1177409Y19986D03*
Y9986D03*
Y-10014D03*
Y-20014D03*
X842325Y19986D03*
Y9986D03*
Y-10014D03*
Y-20014D03*
G54D108*
X1296331Y1199922D03*
X320189Y1199923D03*
G54D106*
X1582551Y1019213D03*
X1251055D03*
X606409Y1019214D03*
X274913D03*
G54D104*
X1296331Y838504D03*
X320189Y838505D03*
G54D105*
X1537275Y838504D03*
X561133Y838505D03*
X1537275Y1199922D03*
X561133Y1199923D03*
G54D109*
X841240Y1420331D03*
X1016240D03*
G54D100*
X177413Y277208D03*
X1153555D03*
X704185Y277236D03*
X1680327D03*
%LPC*%
G75*
G36*
G01X386552Y1069513D02*
G02I-800J0D01*
G37*
G36*
G01Y1063135D02*
G02I-800J0D01*
G37*
G36*
G01X390253Y1069513D02*
G02I-800J0D01*
G37*
G36*
G01Y1063135D02*
G02I-800J0D01*
G37*
G36*
G01X386552Y1075891D02*
G02I-800J0D01*
G37*
G36*
G01X390253D02*
G02I-800J0D01*
G37*
G36*
G01X397654Y1069513D02*
G02I-800J0D01*
G37*
G36*
G01Y1063135D02*
G02I-800J0D01*
G37*
G36*
G01X408757Y1069513D02*
G02I-800J0D01*
G37*
G36*
G01Y1063135D02*
G02I-800J0D01*
G37*
G36*
G01X401355Y1069513D02*
G02I-800J0D01*
G37*
G36*
G01Y1063135D02*
G02I-800J0D01*
G37*
G36*
G01X397654Y1075891D02*
G02I-800J0D01*
G37*
G36*
G01X408757D02*
G02I-800J0D01*
G37*
G36*
G01X401355D02*
G02I-800J0D01*
G37*
G36*
G01X419859Y1063135D02*
G02I-800J0D01*
G37*
G36*
G01Y1069513D02*
G02I-800J0D01*
G37*
G36*
G01X423560Y1063135D02*
G02I-800J0D01*
G37*
G36*
G01X412458Y1069513D02*
G02I-800J0D01*
G37*
G36*
G01Y1063135D02*
G02I-800J0D01*
G37*
G36*
G01X423560Y1069513D02*
G02I-800J0D01*
G37*
G36*
G01X419859Y1075891D02*
G02I-800J0D01*
G37*
G36*
G01X423560D02*
G02I-800J0D01*
G37*
G36*
G01X412458D02*
G02I-800J0D01*
G37*
G36*
G01X429111Y1059946D02*
G02I-800J0D01*
G37*
G36*
G01X432812D02*
G02I-800J0D01*
G37*
G36*
G01X429111Y1072702D02*
G02I-800J0D01*
G37*
G36*
G01Y1066324D02*
G02I-800J0D01*
G37*
G36*
G01X432812Y1072702D02*
G02I-800J0D01*
G37*
G36*
G01Y1066324D02*
G02I-800J0D01*
G37*
G36*
G01X429111Y1079080D02*
G02I-800J0D01*
G37*
G36*
G01X432812D02*
G02I-800J0D01*
G37*
G36*
G01X454992Y1059946D02*
G02I-800J0D01*
G37*
G36*
G01X451291D02*
G02I-800J0D01*
G37*
G36*
G01X454992Y1066324D02*
G02I-800J0D01*
G37*
G36*
G01Y1072702D02*
G02I-800J0D01*
G37*
G36*
G01X451291Y1066324D02*
G02I-800J0D01*
G37*
G36*
G01Y1072702D02*
G02I-800J0D01*
G37*
G36*
G01X454992Y1079080D02*
G02I-800J0D01*
G37*
G36*
G01X451291D02*
G02I-800J0D01*
G37*
G36*
G01X464244Y1063135D02*
G02I-800J0D01*
G37*
G36*
G01Y1069513D02*
G02I-800J0D01*
G37*
G36*
G01X460543Y1063135D02*
G02I-800J0D01*
G37*
G36*
G01Y1069513D02*
G02I-800J0D01*
G37*
G36*
G01X464244Y1075891D02*
G02I-800J0D01*
G37*
G36*
G01X460543D02*
G02I-800J0D01*
G37*
G36*
G01X475346Y1063135D02*
G02I-800J0D01*
G37*
G36*
G01Y1069513D02*
G02I-800J0D01*
G37*
G36*
G01X482748Y1063135D02*
G02I-800J0D01*
G37*
G36*
G01Y1069513D02*
G02I-800J0D01*
G37*
G36*
G01X471645Y1063135D02*
G02I-800J0D01*
G37*
G36*
G01Y1069513D02*
G02I-800J0D01*
G37*
G36*
G01X475346Y1075891D02*
G02I-800J0D01*
G37*
G36*
G01X482748D02*
G02I-800J0D01*
G37*
G36*
G01X471645D02*
G02I-800J0D01*
G37*
G36*
G01X486449Y1063135D02*
G02I-800J0D01*
G37*
G36*
G01Y1069513D02*
G02I-800J0D01*
G37*
G36*
G01X497551Y1063135D02*
G02I-800J0D01*
G37*
G36*
G01Y1069513D02*
G02I-800J0D01*
G37*
G36*
G01X493850Y1063135D02*
G02I-800J0D01*
G37*
G36*
G01Y1069513D02*
G02I-800J0D01*
G37*
G36*
G01X486449Y1075891D02*
G02I-800J0D01*
G37*
G36*
G01X497551D02*
G02I-800J0D01*
G37*
G36*
G01X493850D02*
G02I-800J0D01*
G37*
G36*
G01X816753Y1718420D02*
X901267D01*
G02X901409Y1718361I0J-200D01*
G01X904191Y1715579D01*
G02X904250Y1715437I-141J-142D01*
G01Y1662129D01*
G03X904616Y1661245I1251J0D01*
G01X923910Y1641951D01*
G03X924794Y1641585I884J885D01*
G01X1071014D01*
G02X1071156Y1641526I0J-200D01*
G01X1102501Y1610181D01*
G02X1102560Y1610039I-141J-142D01*
G01Y1554974D01*
G02X1102501Y1554832I-200J0D01*
G03X1102500Y1554831I883J-884D01*
G01X1100990Y1553321D01*
G03X1100989Y1553320I883J-884D01*
G02X1100847Y1553261I-142J141D01*
G01X1094691D01*
G02X1094581Y1553294I0J200D01*
G03X1092934Y1553786I-1647J-2511D01*
G03X1091528Y1553436I1J-3002D01*
G02X1091340I-94J177D01*
G03X1089934Y1553786I-1407J-2652D01*
G03X1088287Y1553294I0J-3003D01*
G02X1088177Y1553261I-110J167D01*
G01X1059235D01*
G02X1059120Y1553297I0J200D01*
G03X1057396Y1553842I-1725J-2457D01*
G03X1055990Y1553492I1J-3002D01*
G02X1055802I-94J177D01*
G03X1054396Y1553842I-1407J-2652D01*
G03X1052672Y1553297I1J-3002D01*
G02X1052557Y1553261I-115J164D01*
G01X1027635D01*
G02X1027520Y1553297I0J200D01*
G03X1025796Y1553842I-1725J-2457D01*
G03X1024390Y1553492I1J-3002D01*
G02X1024202I-94J177D01*
G03X1022796Y1553842I-1407J-2652D01*
G03X1021072Y1553297I1J-3002D01*
G02X1020957Y1553261I-115J164D01*
G01X996035D01*
G02X995920Y1553297I0J200D01*
G03X994196Y1553842I-1725J-2457D01*
G03X992790Y1553492I1J-3002D01*
G02X992602I-94J177D01*
G03X991196Y1553842I-1407J-2652D01*
G03X989472Y1553297I1J-3002D01*
G02X989357Y1553261I-115J164D01*
G01X964400D01*
G02X964287Y1553296I0J200D01*
G03X962584Y1553826I-1703J-2471D01*
G03X961178Y1553476I1J-3002D01*
G02X960990I-94J177D01*
G03X959584Y1553826I-1407J-2652D01*
G03X957881Y1553296I0J-3001D01*
G02X957768Y1553261I-113J165D01*
G01X941933D01*
G02X941733Y1553461I0J200D01*
G01Y1599007D01*
G03X941367Y1599891I-1251J0D01*
G01X924970Y1616288D01*
G03X924086Y1616654I-884J-885D01*
G01X904323D01*
G02X904181Y1616713I0J200D01*
G01X894299Y1626595D01*
G03X893415Y1626961I-884J-885D01*
G01X771437D01*
G02X771295Y1627020I0J200D01*
G01X768659Y1629656D01*
G02X768600Y1629798I141J142D01*
G01Y1656300D01*
G02X768659Y1656442I200J0D01*
G03X768660Y1656443I-883J884D01*
G01X810874Y1698657D01*
G03X811240Y1699541I-885J884D01*
G01Y1712907D01*
G02X811299Y1713049I200J0D01*
G01X816611Y1718361D01*
G02X816753Y1718420I142J-141D01*
G37*
G36*
G01X1075557Y1548281D02*
G03X1075558Y1548280I884J883D01*
G01X1077438Y1546400D01*
G03X1077439Y1546399I884J883D01*
G02X1077498Y1546257I-141J-142D01*
G01Y1512423D01*
G02X1077439Y1512281I-200J0D01*
G03X1077438Y1512280I883J-884D01*
G01X1076566Y1511408D01*
G02X1076564Y1511406I-142J140D01*
G03X1076557Y1511399I881J-887D01*
G02X1076415Y1511340I-142J141D01*
G01X943081D01*
G02X942939Y1511399I0J200D01*
G03X942938Y1511400I-884J-883D01*
G01X941065Y1513273D01*
X941064Y1513274D01*
G03X941057Y1513281I-887J-881D01*
G02X940998Y1513423I141J142D01*
G01Y1547257D01*
G02X941057Y1547399I200J0D01*
G03X941058Y1547400I-883J884D01*
G01X941938Y1548280D01*
G03X941939Y1548281I-883J884D01*
G02X942081Y1548340I142J-141D01*
G01X1075415D01*
G02X1075557Y1548281I0J-200D01*
G37*
G36*
G01X1081757Y1543874D02*
X1082064Y1544181D01*
G02X1082206Y1544240I142J-141D01*
G01X1099402D01*
G02X1099602Y1544040I0J-200D01*
G01Y1511540D01*
G02X1099402Y1511340I-200J0D01*
G01X1082781D01*
G02X1082639Y1511399I0J200D01*
G01X1081757Y1512281D01*
G02X1081698Y1512423I141J142D01*
G01Y1543732D01*
G02X1081757Y1543874I200J0D01*
G37*
G36*
G01X1362694Y1069512D02*
G02I-800J0D01*
G37*
G36*
G01Y1063134D02*
G02I-800J0D01*
G37*
G36*
G01Y1075890D02*
G02I-800J0D01*
G37*
G36*
G01X1373796Y1069512D02*
G02I-800J0D01*
G37*
G36*
G01Y1063134D02*
G02I-800J0D01*
G37*
G36*
G01X1366395Y1069512D02*
G02I-800J0D01*
G37*
G36*
G01Y1063134D02*
G02I-800J0D01*
G37*
G36*
G01X1377497Y1069512D02*
G02I-800J0D01*
G37*
G36*
G01Y1063134D02*
G02I-800J0D01*
G37*
G36*
G01X1373796Y1075890D02*
G02I-800J0D01*
G37*
G36*
G01X1366395D02*
G02I-800J0D01*
G37*
G36*
G01X1377497D02*
G02I-800J0D01*
G37*
G36*
G01X1384899Y1069512D02*
G02I-800J0D01*
G37*
G36*
G01Y1063134D02*
G02I-800J0D01*
G37*
G36*
G01X1388600Y1069512D02*
G02I-800J0D01*
G37*
G36*
G01Y1063134D02*
G02I-800J0D01*
G37*
G36*
G01X1384899Y1075890D02*
G02I-800J0D01*
G37*
G36*
G01X1388600D02*
G02I-800J0D01*
G37*
G36*
G01X1405253Y1059945D02*
G02I-800J0D01*
G37*
G36*
G01X1408954D02*
G02I-800J0D01*
G37*
G36*
G01X1396001Y1063134D02*
G02I-800J0D01*
G37*
G36*
G01X1405253Y1072701D02*
G02I-800J0D01*
G37*
G36*
G01Y1066323D02*
G02I-800J0D01*
G37*
G36*
G01X1396001Y1069512D02*
G02I-800J0D01*
G37*
G36*
G01X1399702Y1063134D02*
G02I-800J0D01*
G37*
G36*
G01X1408954Y1072701D02*
G02I-800J0D01*
G37*
G36*
G01Y1066323D02*
G02I-800J0D01*
G37*
G36*
G01X1399702Y1069512D02*
G02I-800J0D01*
G37*
G36*
G01X1396001Y1075890D02*
G02I-800J0D01*
G37*
G36*
G01X1405253Y1079079D02*
G02I-800J0D01*
G37*
G36*
G01X1399702Y1075890D02*
G02I-800J0D01*
G37*
G36*
G01X1408954Y1079079D02*
G02I-800J0D01*
G37*
G36*
G01X1431134Y1059945D02*
G02I-800J0D01*
G37*
G36*
G01X1427433D02*
G02I-800J0D01*
G37*
G36*
G01X1431134Y1066323D02*
G02I-800J0D01*
G37*
G36*
G01Y1072701D02*
G02I-800J0D01*
G37*
G36*
G01X1427433Y1066323D02*
G02I-800J0D01*
G37*
G36*
G01Y1072701D02*
G02I-800J0D01*
G37*
G36*
G01X1436685Y1063134D02*
G02I-800J0D01*
G37*
G36*
G01Y1069512D02*
G02I-800J0D01*
G37*
G36*
G01X1431134Y1079079D02*
G02I-800J0D01*
G37*
G36*
G01X1427433D02*
G02I-800J0D01*
G37*
G36*
G01X1436685Y1075890D02*
G02I-800J0D01*
G37*
G36*
G01X1440386Y1063134D02*
G02I-800J0D01*
G37*
G36*
G01Y1069512D02*
G02I-800J0D01*
G37*
G36*
G01X1451488Y1063134D02*
G02I-800J0D01*
G37*
G36*
G01Y1069512D02*
G02I-800J0D01*
G37*
G36*
G01X1447787Y1063134D02*
G02I-800J0D01*
G37*
G36*
G01Y1069512D02*
G02I-800J0D01*
G37*
G36*
G01X1440386Y1075890D02*
G02I-800J0D01*
G37*
G36*
G01X1451488D02*
G02I-800J0D01*
G37*
G36*
G01X1447787D02*
G02I-800J0D01*
G37*
G36*
G01X1462591Y1063134D02*
G02I-800J0D01*
G37*
G36*
G01Y1069512D02*
G02I-800J0D01*
G37*
G36*
G01X1458890Y1063134D02*
G02I-800J0D01*
G37*
G36*
G01Y1069512D02*
G02I-800J0D01*
G37*
G36*
G01X1462591Y1075890D02*
G02I-800J0D01*
G37*
G36*
G01X1458890D02*
G02I-800J0D01*
G37*
G36*
G01X1473693Y1063134D02*
G02I-800J0D01*
G37*
G36*
G01Y1069512D02*
G02I-800J0D01*
G37*
G36*
G01X1469992Y1063134D02*
G02I-800J0D01*
G37*
G36*
G01Y1069512D02*
G02I-800J0D01*
G37*
G36*
G01X1473693Y1075890D02*
G02I-800J0D01*
G37*
G36*
G01X1469992D02*
G02I-800J0D01*
G37*
%LPD*%
G75*
G54D14*
X11782Y167036D03*
X18691Y167208D03*
X22409Y230021D03*
X19684Y237154D03*
X19230Y1446459D03*
X34281Y277798D03*
Y282916D03*
X35689Y298207D03*
X34281Y312916D03*
Y307798D03*
X35740Y363337D03*
X39320Y392269D03*
X28562Y517025D03*
X39967Y526709D03*
X30562Y533055D03*
X35952Y551605D03*
X35852Y670445D03*
Y667045D03*
Y681410D03*
Y678010D03*
Y692316D03*
Y703222D03*
Y688916D03*
Y699822D03*
X35010Y1289485D03*
X35040Y1292433D03*
X35080Y1298360D03*
X35040Y1295380D03*
X34584Y1307744D03*
Y1310244D03*
Y1312744D03*
Y1315244D03*
X33822Y1477075D03*
Y1486075D03*
Y1483075D03*
Y1480075D03*
X27205Y1501630D03*
Y1498230D03*
X38058Y1591405D03*
X35167Y1598896D03*
Y1626896D03*
Y1629405D03*
X32927Y1668587D03*
X42449Y282916D03*
Y277798D03*
X41492Y292892D03*
Y298207D03*
X47892Y295452D03*
X40500Y288500D03*
X55254Y292892D03*
X42449Y312916D03*
Y307798D03*
X51114Y360862D03*
X43020Y382942D03*
X40940Y387302D03*
X41933Y395652D03*
X47619Y419084D03*
X47618Y415184D03*
X49360Y428806D03*
X45960D03*
X49212Y451602D03*
X45812D03*
X47812Y517635D03*
X42810Y528070D03*
X39952Y551605D03*
X55099Y1298676D03*
Y1292676D03*
X51000Y1339200D03*
X42822Y1477075D03*
Y1483075D03*
Y1486075D03*
Y1480075D03*
X49265Y1490950D03*
Y1493450D03*
X49188Y1499181D03*
X41360Y1498971D03*
X41309Y1496173D03*
X38650Y1499326D03*
X49177Y1496272D03*
X48383Y1532395D03*
X48157Y1536296D03*
X49196Y1551294D03*
X48324Y1545961D03*
X48758Y1559295D03*
X48907Y1554972D03*
X47735Y1584885D03*
X47973Y1589981D03*
X43633Y1606896D03*
X46833Y1612596D03*
X43933Y1613818D03*
X47633Y1600896D03*
X53633Y1629896D03*
X41208Y1619896D03*
X42491Y1638656D03*
X40167Y1632405D03*
X40922Y1654869D03*
Y1658269D03*
X45052Y1684283D03*
X41679Y1673323D03*
Y1676723D03*
X65933Y28406D03*
Y48720D03*
X66650Y265316D03*
X57271Y272357D03*
X59780Y282866D03*
X62567Y295103D03*
X66289Y298207D03*
X59780Y312866D03*
X59322Y360702D03*
X63429D03*
X67681D03*
X53406Y402862D03*
X62812Y412100D03*
X62813Y416000D03*
X64821Y430806D03*
X60921D03*
X63540Y438802D03*
X64442Y510667D03*
X55682Y517595D03*
X62142Y539495D03*
X56192Y537795D03*
X63633Y528229D03*
X58365Y552365D03*
X53299D03*
X56627Y585818D03*
X59259Y737422D03*
X58751Y777718D03*
X61251D03*
Y775218D03*
X58751D03*
X61620Y768510D03*
X56440Y766180D03*
X58751Y790218D03*
Y792718D03*
Y780218D03*
X61251D03*
X56057Y792750D03*
X61251Y792718D03*
Y790218D03*
X56057Y790250D03*
Y787750D03*
X61251Y787718D03*
X56057Y785250D03*
X61251Y785218D03*
Y782718D03*
X56057Y782750D03*
X58751Y782718D03*
Y785218D03*
Y787718D03*
X57752Y808020D03*
X60547Y1276036D03*
X57747Y1270470D03*
X55099Y1289676D03*
X55043Y1295676D03*
X53700Y1342300D03*
X67010Y1476292D03*
X57822Y1477075D03*
X57777Y1490580D03*
X66710Y1485324D03*
Y1482324D03*
X66785Y1479175D03*
X57822Y1482791D03*
Y1485294D03*
Y1480075D03*
X64030Y1491595D03*
X57770Y1488047D03*
X66696Y1488010D03*
X64030Y1499095D03*
Y1501595D03*
Y1494095D03*
Y1496595D03*
X55370Y1551351D03*
X66229Y1549536D03*
X61605Y1546833D03*
X64275Y1546296D03*
X57811Y1598061D03*
X58633Y1587481D03*
X63633D03*
X61110Y1598146D03*
X58633Y1629896D03*
X64133Y1627896D03*
X64633Y1632896D03*
X64427Y1643496D03*
X64462Y1655624D03*
X61927Y1643496D03*
X65257Y1652941D03*
X56815Y1643431D03*
X62202Y1684579D03*
X66127Y1687362D03*
X79726Y145191D03*
X82026Y143491D03*
X71659Y149191D03*
X71779Y165194D03*
X71775Y153194D03*
X72462Y268223D03*
X77680Y378395D03*
Y380895D03*
X68020Y395222D03*
X80948Y525513D03*
Y521613D03*
X80318Y543313D03*
Y539413D03*
X80915Y767400D03*
X80784Y771366D03*
X68354Y1314097D03*
X80378Y1406676D03*
X83441Y1430500D03*
X81052Y1427410D03*
X81132Y1424195D03*
X79055Y1434000D03*
X73820Y1442893D03*
X81401Y1436105D03*
X73820Y1445945D03*
X73757Y1448500D03*
X81822Y1477075D03*
X77883Y1491440D03*
X80932D03*
X80852Y1488638D03*
X75245Y1491440D03*
X81822Y1480075D03*
Y1483075D03*
Y1486075D03*
X72396Y1491290D03*
X72390Y1499211D03*
X77883Y1499240D03*
X80833D03*
X77883Y1494040D03*
Y1496640D03*
X80932Y1494040D03*
Y1496640D03*
X75245Y1499240D03*
Y1494040D03*
Y1496640D03*
X72396Y1493890D03*
Y1496490D03*
X77920Y1538245D03*
X75796Y1545669D03*
X75396Y1542369D03*
X78796Y1545669D03*
X78096Y1542444D03*
X78372Y1556416D03*
Y1558916D03*
X78522Y1562641D03*
Y1565141D03*
Y1567888D03*
X78403Y1580311D03*
X81103D03*
X78522Y1570388D03*
X81468Y1570285D03*
X68133Y1587896D03*
X81006Y1593265D03*
X72660Y1587365D03*
X72375Y1604365D03*
X74133Y1610896D03*
X70567Y1625603D03*
X72255Y1616730D03*
X74134Y1621396D03*
X75380Y1627622D03*
X75764Y1636993D03*
X79164Y1636992D03*
X77427Y1644410D03*
X82127Y1687362D03*
X82500Y1698511D03*
Y1706511D03*
X82000Y1716331D03*
X82500Y1720331D03*
X82000Y1724331D03*
X92197Y143853D03*
X87137Y143663D03*
X93775Y197241D03*
Y212241D03*
Y207241D03*
Y202241D03*
X87520Y382219D03*
Y391391D03*
Y395865D03*
X90225Y610351D03*
X84057Y599372D03*
X84038Y602233D03*
X90225Y614351D03*
Y618351D03*
Y622351D03*
X94474Y766871D03*
X95790Y1278014D03*
X82953Y1307607D03*
X83023Y1311607D03*
X97546Y1385912D03*
X85736Y1391597D03*
X86827Y1404080D03*
X93000Y1417000D03*
Y1408000D03*
X93069Y1412500D03*
X85103Y1433051D03*
X93000Y1426000D03*
X97800Y1433000D03*
X93000Y1421500D03*
Y1444500D03*
Y1448500D03*
X84500Y1444500D03*
Y1448500D03*
X88722Y1476741D03*
X89092Y1491106D03*
X89042Y1488506D03*
X83991Y1491440D03*
X83892Y1488840D03*
X88722Y1479741D03*
Y1482741D03*
Y1485741D03*
X83892Y1499140D03*
X83991Y1494040D03*
Y1496540D03*
X84051Y1501690D03*
X83796Y1533746D03*
X83811Y1537296D03*
X91511Y1552296D03*
X93296Y1549142D03*
X97018Y1546331D03*
X88511Y1552296D03*
X83121Y1542294D03*
X94786Y1574205D03*
Y1576705D03*
X97486Y1574205D03*
Y1576705D03*
X83603Y1580311D03*
X84093Y1570285D03*
X90675Y1590783D03*
X96124Y1593458D03*
Y1595958D03*
X93424Y1593458D03*
X90675Y1593283D03*
X93424Y1595958D03*
X90675Y1595783D03*
X93537Y1598506D03*
X96237D03*
X90649Y1598507D03*
X84833Y1611896D03*
X90892Y1654749D03*
X85836Y1655143D03*
Y1658543D03*
X87891Y1671121D03*
Y1674521D03*
X90127Y1687362D03*
X96101Y1696469D03*
X82945Y1702511D03*
X95342Y1713741D03*
X96555Y1705508D03*
X95400Y1719741D03*
X95460Y1725241D03*
X101679Y151191D03*
X101675Y160694D03*
X100818Y165506D03*
Y168906D03*
X110616Y767400D03*
X110485Y771366D03*
X105165Y1300380D03*
Y1302880D03*
X107665D03*
Y1300380D03*
X102665Y1302880D03*
Y1300380D03*
X105165Y1305380D03*
X107665D03*
X102665D03*
Y1307880D03*
Y1310380D03*
Y1312880D03*
X105165Y1307880D03*
Y1310380D03*
Y1312880D03*
X107665D03*
Y1310380D03*
Y1307880D03*
X105165Y1315380D03*
X107665D03*
X105165Y1317880D03*
X107665D03*
X102665D03*
Y1315380D03*
X98101Y1369018D03*
Y1371559D03*
X104863Y1382593D03*
X99594Y1379933D03*
X104863Y1380085D03*
X112305Y1382130D03*
X108817Y1380530D03*
X111555Y1379562D03*
X101874Y1376408D03*
X111600Y1403100D03*
X113500Y1398600D03*
X110000Y1407425D03*
X110075Y1410500D03*
X101637Y1432938D03*
X102076Y1427833D03*
X101955Y1448660D03*
X101500Y1436000D03*
X102398Y1440000D03*
X113500Y1455600D03*
X112481Y1452424D03*
X112100Y1467500D03*
X103571Y1476485D03*
X103555Y1485128D03*
Y1479128D03*
Y1482128D03*
X109733Y1491367D03*
X110605Y1487896D03*
X104184Y1491292D03*
X106784D03*
X105453Y1487893D03*
X108053D03*
X102931Y1488097D03*
X101584Y1491292D03*
X106396Y1485113D03*
X108996D03*
X106371Y1482181D03*
X108971D03*
X107197Y1501756D03*
X109712Y1499196D03*
X104616Y1501811D03*
X107112Y1499196D03*
X109733Y1493967D03*
Y1496567D03*
X106784Y1493892D03*
Y1496492D03*
X101634D03*
X104512Y1499196D03*
X104184Y1496492D03*
Y1493892D03*
X101534Y1499244D03*
X101634Y1493992D03*
X101835Y1501863D03*
X109878Y1501879D03*
X102011Y1550242D03*
X99818Y1546296D03*
X111196Y1542569D03*
X111901Y1545543D03*
X112418Y1555680D03*
X112339Y1565015D03*
Y1562515D03*
X112418Y1558180D03*
X99986Y1574205D03*
Y1576705D03*
X108555Y1574657D03*
Y1577462D03*
X98824Y1593558D03*
X101524D03*
X98824Y1596058D03*
X101524D03*
X101637Y1598606D03*
X98937D03*
X112353Y1646612D03*
X110378Y1670313D03*
X99443Y1661931D03*
Y1658531D03*
X110378Y1674313D03*
X100443Y1684063D03*
Y1687463D03*
X107500Y1707450D03*
X115016Y300281D03*
Y320715D03*
X118407Y526766D03*
X113042Y686285D03*
X113980Y717480D03*
X116480D03*
X118980D03*
X121480D03*
X123980D03*
X113980Y714980D03*
X116480D03*
X118980D03*
X121480D03*
X123980D03*
X116480Y722480D03*
X118980D03*
X121480D03*
X123980D03*
X113980Y719980D03*
X116480D03*
X118980D03*
X121480D03*
X123980D03*
X113980Y722480D03*
X124174Y766871D03*
X120965Y1307880D03*
Y1310380D03*
Y1312880D03*
X118465D03*
Y1310380D03*
Y1307880D03*
Y1300380D03*
X123465Y1302880D03*
Y1300380D03*
X120965Y1305380D03*
X118465D03*
X123465D03*
Y1307880D03*
Y1310380D03*
Y1312880D03*
X120965Y1300380D03*
Y1302880D03*
X118465D03*
X120965Y1315380D03*
X118465D03*
X120965Y1317880D03*
X118465D03*
X123465D03*
Y1315380D03*
X121207Y1363643D03*
X115321Y1372872D03*
X120181D03*
X117751D03*
X121241Y1367047D03*
Y1369947D03*
X127211Y1373177D03*
Y1378977D03*
X125111Y1377577D03*
X122945Y1379207D03*
X127211Y1376077D03*
X125011Y1374577D03*
X122945Y1376307D03*
X122050Y1403750D03*
X129200Y1401000D03*
X124700D03*
X126000Y1414000D03*
Y1418000D03*
X116700Y1415700D03*
Y1410500D03*
X120700Y1408100D03*
X116900Y1449000D03*
X113600Y1449100D03*
X116122Y1458000D03*
X119100Y1460300D03*
X124600Y1465100D03*
X121500Y1467400D03*
X113100Y1537346D03*
X114030Y1542419D03*
X114610Y1545543D03*
X121705Y1619460D03*
X114618Y1624541D03*
X117655Y1621766D03*
X118956Y1635244D03*
X124312Y1633488D03*
X126717Y1635893D03*
X126428Y1658587D03*
X126760Y1682383D03*
X123353Y1695941D03*
X127353Y1696062D03*
X127710Y1700166D03*
X127290Y1705666D03*
X125183Y1716741D03*
X127168Y1721695D03*
X129020Y1726741D03*
X140360Y430160D03*
X141642Y488684D03*
Y494147D03*
X139980Y507420D03*
X139890Y503440D03*
X140471Y670445D03*
X131752Y668506D03*
X134902D03*
X140600Y683029D03*
X131752Y686074D03*
X134902D03*
X131960Y679290D03*
X140317Y767400D03*
Y771200D03*
X140265Y1307880D03*
Y1310380D03*
Y1312880D03*
X137765D03*
Y1310380D03*
Y1307880D03*
X135265Y1312880D03*
Y1310380D03*
Y1307880D03*
Y1305380D03*
X140265D03*
X137765D03*
X135265Y1300380D03*
Y1302880D03*
X140265Y1300380D03*
Y1302880D03*
X137765D03*
Y1300380D03*
X140265Y1315380D03*
X137765D03*
X135265D03*
Y1317880D03*
X140265D03*
X137765D03*
X130701Y1369018D03*
Y1371559D03*
X137463Y1382593D03*
X132194Y1379933D03*
X137463Y1380085D03*
X141417Y1380530D03*
X134474Y1376408D03*
X138000Y1400600D03*
X134800Y1408100D03*
X142000Y1414500D03*
X136000Y1432000D03*
X141500Y1433500D03*
Y1429500D03*
X139500Y1446000D03*
X133100Y1444100D03*
X138013Y1440487D03*
X141514Y1436500D03*
X128661Y1464000D03*
X139802Y1556133D03*
X129070Y1608338D03*
X137386Y1626412D03*
X135543Y1637055D03*
X132353Y1646612D03*
X136353D03*
X142465Y1662493D03*
X143000Y1701011D03*
X142293Y1705166D03*
X129493Y1711846D03*
X143000Y1709166D03*
X135722Y1715672D03*
X147920Y28261D03*
X148780Y48720D03*
X149231Y224204D03*
X148228Y216118D03*
X158380Y419760D03*
X147450Y423860D03*
X154770Y441830D03*
X147810Y475710D03*
X146982Y521997D03*
Y530997D03*
X159513Y674855D03*
X152822Y665500D03*
X153875Y766871D03*
X151065Y1307880D03*
Y1310380D03*
Y1312880D03*
X153565D03*
Y1310380D03*
Y1307880D03*
X156065Y1312880D03*
Y1310380D03*
Y1307880D03*
Y1305380D03*
X151065D03*
X153565D03*
X156065Y1300380D03*
Y1302880D03*
X151065Y1300380D03*
Y1302880D03*
X153565D03*
Y1300380D03*
X151065Y1315380D03*
X153565D03*
X156065D03*
Y1317880D03*
X151065D03*
X153565D03*
X152781Y1372872D03*
X150351D03*
X147921D03*
X153741Y1369977D03*
Y1367077D03*
X144905Y1382130D03*
X144155Y1379562D03*
X155545Y1379207D03*
Y1376307D03*
X145000Y1414425D03*
X150900Y1425500D03*
X154443Y1441195D03*
X156174Y1435396D03*
X156477Y1447733D03*
X154083Y1456007D03*
X148340Y1454674D03*
X154671Y1450019D03*
X154305Y1453101D03*
X159000Y1525480D03*
X155618Y1549331D03*
X155071Y1543604D03*
X152843Y1559146D03*
Y1562666D03*
X154945Y1624350D03*
X146453Y1614879D03*
X149171Y1616759D03*
X154945Y1627750D03*
X142576Y1640163D03*
X152353Y1646612D03*
X142576Y1643563D03*
X154111Y1663933D03*
X154010Y1676811D03*
X157410D03*
X143778Y1685087D03*
X147253Y1696343D03*
X155353Y1687843D03*
X159427Y1696652D03*
X152605Y1715941D03*
X149338Y1705603D03*
X156825Y1705510D03*
X146000Y1718241D03*
X146086Y1705603D03*
X145267Y1722241D03*
X152496Y1722941D03*
X146483Y1725636D03*
X155260Y1723682D03*
X162830Y396930D03*
X172120Y412350D03*
X172010Y474900D03*
X166760Y506880D03*
X166670Y502900D03*
X163372Y670863D03*
X172725Y667898D03*
X162482Y679319D03*
X161735Y684456D03*
X172725Y679230D03*
X169987Y767666D03*
Y771266D03*
X170265Y1312880D03*
Y1310380D03*
Y1307880D03*
X167765Y1312880D03*
Y1310380D03*
Y1307880D03*
Y1305380D03*
X170265D03*
X167765Y1300380D03*
Y1302880D03*
X170265D03*
Y1300380D03*
Y1315380D03*
X167765D03*
Y1317880D03*
X170265D03*
X163401Y1369018D03*
Y1371559D03*
X159811Y1373177D03*
X170163Y1382593D03*
X164894Y1379933D03*
X170163Y1380085D03*
X167174Y1376408D03*
X159811Y1378977D03*
Y1376077D03*
X157711Y1377577D03*
X157611Y1374577D03*
X163099Y1414400D03*
X162873Y1411611D03*
X163061Y1409048D03*
Y1406548D03*
X160684Y1441046D03*
X158704Y1439411D03*
X161210Y1443542D03*
X163271Y1441588D03*
X163148Y1474504D03*
X172180Y1490210D03*
X172070Y1495550D03*
X163460Y1491010D03*
X163320Y1494340D03*
X161188Y1510800D03*
X162188Y1518040D03*
X162531Y1523331D03*
Y1526731D03*
X167666Y1550751D03*
X165166D03*
X162666D03*
X170166D03*
X170230Y1542960D03*
X160150Y1553251D03*
Y1555751D03*
X162666D03*
X165166D03*
X167666D03*
X170166D03*
Y1553251D03*
X167666D03*
X165166D03*
X162666D03*
X170166Y1567621D03*
X167666D03*
X165166D03*
X162666D03*
X170166Y1565121D03*
X167666D03*
X165166D03*
X162666D03*
Y1562621D03*
X165166D03*
X167666D03*
X170166D03*
X162466Y1570121D03*
X164966D03*
X167466D03*
X169966D03*
X163735Y1635369D03*
Y1631969D03*
X157511Y1663933D03*
X165491Y1665582D03*
Y1662182D03*
X165336Y1675077D03*
Y1678477D03*
X162740Y1713172D03*
Y1704885D03*
X166467Y1720973D03*
X171925Y1717984D03*
X171945Y1730693D03*
X162740Y1723886D03*
X184930Y125502D03*
X181025Y159123D03*
X183890Y388180D03*
X174320Y395040D03*
X189290Y396730D03*
X177675Y419260D03*
X185160Y419220D03*
X181550Y441290D03*
X182500Y672500D03*
X172500Y684799D03*
X183576Y766871D03*
X183565Y1310380D03*
Y1312880D03*
X186065D03*
Y1310380D03*
Y1307880D03*
X172765D03*
Y1310380D03*
Y1312880D03*
X183565Y1307880D03*
Y1305380D03*
X186065D03*
X183565Y1300380D03*
Y1302880D03*
X186065D03*
Y1300380D03*
X172765Y1305380D03*
Y1300380D03*
Y1302880D03*
Y1315380D03*
X183565D03*
X186065D03*
X183565Y1317880D03*
X186065D03*
X172765D03*
X185481Y1372872D03*
X183051D03*
X180621D03*
X186481Y1370147D03*
Y1367247D03*
X177605Y1382130D03*
X174117Y1380530D03*
X176855Y1379562D03*
X185558Y1418560D03*
Y1416060D03*
X183058Y1418560D03*
Y1416060D03*
X173164Y1406397D03*
Y1408897D03*
X172976Y1411460D03*
X173202Y1414249D03*
X185558Y1421060D03*
Y1423560D03*
Y1426060D03*
X183058Y1421060D03*
Y1426060D03*
Y1423560D03*
Y1428560D03*
X185558D03*
X173490Y1542540D03*
X173050Y1555751D03*
Y1553251D03*
X178582Y1575390D03*
X181087Y1576135D03*
X178582Y1572490D03*
Y1569590D03*
X180292Y1582589D03*
X177792D03*
X177509Y1653825D03*
X177666Y1649223D03*
X183974Y1656804D03*
X183920Y1653973D03*
X184139Y1651088D03*
X180103Y1668921D03*
X177672Y1657538D03*
X183986Y1659548D03*
X182533Y1676854D03*
X185124Y1701851D03*
X185084Y1691988D03*
X179999Y1699156D03*
X185173Y1695138D03*
X178385Y1715441D03*
X183813Y1705404D03*
X178376Y1720559D03*
X185760Y1731666D03*
X204088Y138912D03*
X200577Y125502D03*
X190000Y143000D03*
X191264Y147768D03*
X193610Y153951D03*
X192592Y353072D03*
X188055Y731734D03*
X199718Y767400D03*
X197651Y769241D03*
X200365Y1312880D03*
Y1310380D03*
Y1307880D03*
Y1305380D03*
Y1300380D03*
Y1302880D03*
X188565Y1312880D03*
Y1310380D03*
Y1307880D03*
Y1305380D03*
Y1300380D03*
Y1302880D03*
X200365Y1315380D03*
Y1317880D03*
X188565Y1315380D03*
Y1317880D03*
X196301Y1369018D03*
Y1371559D03*
X192511Y1373177D03*
X197794Y1379933D03*
X200074Y1376408D03*
X188245Y1379207D03*
X190411Y1377577D03*
X192511Y1378977D03*
X190311Y1374577D03*
X188245Y1376307D03*
X192511Y1376077D03*
X200408Y1416249D03*
Y1418749D03*
X192983Y1417568D03*
X188058Y1416060D03*
Y1418560D03*
X190483Y1417568D03*
X197983D03*
X195483D03*
X188695Y1404813D03*
Y1407313D03*
X191995Y1404813D03*
Y1407313D03*
X194495Y1404813D03*
Y1407313D03*
X196995Y1404813D03*
Y1407313D03*
X199495Y1404813D03*
Y1407313D03*
X188507Y1409876D03*
X191807D03*
X194307D03*
X196807D03*
X199307D03*
X200558Y1421551D03*
X195483Y1420068D03*
X192983D03*
X195483Y1422568D03*
X197983D03*
X192983D03*
X188058Y1421060D03*
Y1423560D03*
X190483Y1420068D03*
Y1422568D03*
X197983Y1420068D03*
X188058Y1426060D03*
X193679Y1640052D03*
Y1643452D03*
X198698Y1662215D03*
X199747Y1675603D03*
X200424Y1686870D03*
X197780Y1696973D03*
X200478Y1701758D03*
X200448Y1690771D03*
X202076Y1717845D03*
X189760Y1713061D03*
X193274Y1709769D03*
X199843Y1709837D03*
X203510Y1712441D03*
X196763Y1710444D03*
X189760Y1723041D03*
Y1731564D03*
X194000Y1720551D03*
X203655Y1723000D03*
X198760Y1719991D03*
X217687Y522453D03*
X214999Y585668D03*
X211254Y595145D03*
X208254D03*
X211009Y610001D03*
X208009D03*
X214202Y606943D03*
X208254Y603245D03*
X211254D03*
X214202Y609681D03*
X208326Y606918D03*
X211326D03*
X210199Y714074D03*
X206199D03*
X206254Y732537D03*
X206933Y737277D03*
X208818Y766871D03*
X205365Y1307880D03*
Y1310380D03*
Y1312880D03*
X202865D03*
Y1310380D03*
Y1307880D03*
X216165D03*
Y1310380D03*
Y1312880D03*
Y1305380D03*
Y1300380D03*
Y1302880D03*
X205365Y1305380D03*
X202865D03*
X205365Y1300380D03*
Y1302880D03*
X202865D03*
Y1300380D03*
X205365Y1315380D03*
X202865D03*
X216165D03*
Y1317880D03*
X205365D03*
X202865D03*
X213521Y1372872D03*
X215951D03*
X203063Y1382593D03*
Y1380085D03*
X210505Y1382130D03*
X207017Y1380530D03*
X209755Y1379562D03*
X205558Y1418560D03*
Y1416060D03*
X202945Y1415910D03*
Y1418410D03*
X208058Y1416060D03*
X208061Y1418605D03*
X205479Y1652130D03*
Y1648730D03*
X206788Y1660960D03*
X210833Y1660867D03*
X210217Y1668603D03*
X207807Y1681302D03*
Y1696409D03*
X211862Y1701100D03*
X212365Y1705403D03*
X211000Y1717675D03*
X229131Y26477D03*
X225731D03*
X229127Y50649D03*
X225727D03*
X233284Y137195D03*
X221051Y153167D03*
X223687Y522453D03*
X229687D03*
X226599Y570970D03*
X217999Y585668D03*
X223999D03*
X220999D03*
X217202Y606943D03*
X220202D03*
X223202D03*
X223111Y603782D03*
X225895Y609691D03*
X228895D03*
X220111Y603782D03*
X217202Y609681D03*
X220202D03*
X223202D03*
X218024Y622385D03*
X221024D03*
X224024D03*
X227024D03*
X221024Y632385D03*
X218024D03*
X224024D03*
X227024D03*
X224157Y715915D03*
Y712915D03*
X229263Y765863D03*
X229275Y769292D03*
X218665Y1312880D03*
Y1310380D03*
Y1307880D03*
X221165Y1312880D03*
Y1310380D03*
Y1307880D03*
Y1305380D03*
X218665D03*
X221165Y1300380D03*
Y1302880D03*
X218665D03*
Y1300380D03*
Y1315380D03*
X221165D03*
Y1317880D03*
X218665D03*
X229101Y1369018D03*
Y1371559D03*
X218381Y1372872D03*
X219401Y1370067D03*
Y1367167D03*
X225411Y1373177D03*
X230594Y1379933D03*
X225411Y1378977D03*
Y1376077D03*
X221145Y1379207D03*
X223311Y1377577D03*
X223211Y1374577D03*
X221145Y1376307D03*
X238059Y26235D03*
X233335Y17665D03*
X235697Y21585D03*
X241306Y20325D03*
X246356Y26855D03*
X246506Y20365D03*
X242216Y39365D03*
X246216D03*
X238059Y37165D03*
X235697Y39755D03*
X248816Y48965D03*
X239816Y54365D03*
X248487Y68690D03*
X242920Y67915D03*
X238846Y72977D03*
X235186Y98067D03*
X234331Y103286D03*
X232529Y114830D03*
X238297Y121555D03*
X244818Y111546D03*
Y115546D03*
X235460Y115790D03*
X235186Y112022D03*
X238600Y130400D03*
X235147Y124435D03*
X243813Y132383D03*
X241271Y130719D03*
X234000Y148000D03*
X239988Y141986D03*
X236104Y151996D03*
X245486Y159705D03*
X234628Y166735D03*
X240413Y360867D03*
X233413D03*
X235913D03*
X243845Y656940D03*
X246045Y655540D03*
X243845Y651140D03*
Y654040D03*
X245945Y652540D03*
X232981Y743983D03*
X240200Y766300D03*
X246371Y772388D03*
X232965Y1297880D03*
X237965D03*
X235465D03*
Y1300380D03*
Y1302880D03*
X237965D03*
Y1300380D03*
X235465Y1305380D03*
X237965D03*
X232965Y1302880D03*
Y1300380D03*
Y1305380D03*
Y1307880D03*
Y1310380D03*
Y1312880D03*
X237965Y1307880D03*
Y1310380D03*
Y1312880D03*
X235465D03*
Y1310380D03*
Y1307880D03*
X237965Y1315380D03*
X235465D03*
X232965D03*
X246321Y1372872D03*
X235863Y1380085D03*
X243305Y1382130D03*
X239817Y1380530D03*
X242555Y1379562D03*
X235863Y1382593D03*
X232874Y1376408D03*
X255106Y16615D03*
X251106Y12615D03*
X250216Y39365D03*
X254046Y39425D03*
X259316Y48965D03*
X261016Y51565D03*
X252316Y48965D03*
X255816D03*
X254016Y51565D03*
X250516D03*
X257516D03*
X247893Y100546D03*
X248093Y92146D03*
X261416Y100665D03*
X253874Y111774D03*
X252800Y114800D03*
X256586Y138373D03*
X260596Y151065D03*
X248350Y165700D03*
X257252Y156730D03*
X258439Y214000D03*
X247859Y375389D03*
X250359D03*
X254859D03*
X247694Y378523D03*
X250194D03*
X254694D03*
X258751Y647987D03*
X262239Y649587D03*
X259501Y650555D03*
X255735Y657245D03*
X253305D03*
X250875D03*
X248111Y653810D03*
Y650910D03*
X250312Y663080D03*
Y660180D03*
X247587Y714760D03*
Y717260D03*
X252591Y714737D03*
Y717237D03*
X250091D03*
Y714737D03*
X247587Y712237D03*
X250087D03*
X252587D03*
X247587Y719760D03*
X252591Y719737D03*
X250091D03*
X247587Y724760D03*
X252587D03*
X250087D03*
X247587Y722260D03*
Y727260D03*
X250087Y729760D03*
X247587D03*
X250087Y727260D03*
X252587D03*
Y729760D03*
X252591Y722237D03*
X250091D03*
X254671Y776388D03*
X257071Y772770D03*
X260971Y777988D03*
X248765Y1297880D03*
X251265D03*
X248765Y1292880D03*
Y1295380D03*
X251265D03*
Y1292880D03*
X248765Y1307880D03*
Y1310380D03*
Y1312880D03*
X251265D03*
Y1310380D03*
Y1307880D03*
X248765Y1305380D03*
X251265D03*
X248765Y1300380D03*
Y1302880D03*
X251265D03*
Y1300380D03*
X248765Y1315380D03*
X251265D03*
Y1317880D03*
X248765D03*
X248751Y1372872D03*
X251181D03*
X252211Y1370232D03*
Y1367332D03*
X258211Y1373177D03*
X256111Y1377577D03*
X258211Y1378977D03*
X256011Y1374577D03*
X258211Y1376077D03*
X253945Y1379207D03*
Y1376307D03*
X261530Y1550300D03*
X275116Y28565D03*
X275896Y48875D03*
X266420Y39120D03*
X265365Y49171D03*
X263516Y51565D03*
X261816Y48965D03*
X263182Y73396D03*
X269860Y72741D03*
X262893Y77529D03*
Y80029D03*
X263316Y87665D03*
X275238Y83024D03*
X264916Y100665D03*
X268416D03*
X262916Y97965D03*
X266416D03*
X269916D03*
X273616Y96665D03*
X264293Y120972D03*
X269487Y121095D03*
X275793Y120248D03*
X266000Y125800D03*
X275793Y129595D03*
X266971Y140110D03*
X264574Y151206D03*
X276821Y140465D03*
X270178Y140322D03*
X262500Y161100D03*
X273500Y207500D03*
X266360Y203070D03*
X269925Y217700D03*
X274993Y522052D03*
X269568Y522366D03*
X266327Y522456D03*
X274096Y574698D03*
X273208Y588237D03*
X267601Y608378D03*
X271462Y650184D03*
X266193Y650032D03*
X272955Y658558D03*
X266193Y647524D03*
X269182Y653709D03*
X272955Y661099D03*
X276575Y685381D03*
Y688281D03*
Y691181D03*
X265891Y714737D03*
Y717237D03*
X263391D03*
Y714737D03*
X263387Y712237D03*
X265887D03*
X265891Y719737D03*
X263391D03*
X265787Y724760D03*
X263287D03*
X265787Y727260D03*
X263287D03*
X265787Y729760D03*
X263287D03*
X265787Y732260D03*
X263287D03*
X265891Y722237D03*
X263391D03*
X265787Y737260D03*
X263287D03*
X265787Y734760D03*
X263287D03*
X271161Y780588D03*
X268991Y783248D03*
X271245Y785474D03*
X274282Y786741D03*
X272054Y801112D03*
X270850Y797605D03*
X272165Y1256716D03*
X269665Y1259216D03*
X272165D03*
X269765Y1269234D03*
X272265D03*
X269765Y1261734D03*
Y1264234D03*
Y1266734D03*
X272265D03*
Y1264234D03*
Y1261734D03*
X267179Y1269273D03*
Y1266773D03*
Y1264273D03*
Y1261773D03*
Y1271773D03*
X269679D03*
X272179D03*
X262701Y1322872D03*
Y1325413D03*
X264194Y1333787D03*
X269463Y1333939D03*
X273417Y1334384D03*
X276155Y1333416D03*
X269463Y1336447D03*
X266474Y1330262D03*
X269829Y1521436D03*
X273597Y1519845D03*
X269144Y1511953D03*
X273474Y1516120D03*
Y1512220D03*
X269144Y1514453D03*
Y1516953D03*
X267322Y1519250D03*
X276624Y1516120D03*
Y1512220D03*
X276637Y1521436D03*
X274546Y1549295D03*
Y1546795D03*
X267297Y1546119D03*
X286996Y20365D03*
X290795Y28365D03*
X284228Y25935D03*
X280828D03*
X282716Y40020D03*
X290716D03*
X287988Y54893D03*
X291379Y55746D03*
X293157Y50525D03*
X284226Y50649D03*
X280826D03*
X278638Y83024D03*
X288553Y105006D03*
X285353D03*
X280853Y109906D03*
X282853Y115606D03*
X285853D03*
X280853Y107306D03*
X286996Y139865D03*
X283049Y139731D03*
X288000Y209000D03*
X290000Y222575D03*
X289163Y212503D03*
X278425Y230925D03*
X289393Y498960D03*
X278547Y523041D03*
X284018Y522300D03*
X287723Y548499D03*
X289421Y575098D03*
X291481Y682228D03*
X280841Y688051D03*
X278675Y686781D03*
X280841Y685151D03*
X288465Y691493D03*
X283605D03*
X286035D03*
X278775Y689781D03*
X283042Y697280D03*
Y694380D03*
X285317Y746478D03*
X282817D03*
X280317D03*
Y759110D03*
X285317D03*
X282817D03*
X285317Y761610D03*
X285321Y748978D03*
Y751478D03*
Y753978D03*
X282821D03*
Y751478D03*
Y748978D03*
X285321Y756478D03*
X282821D03*
X280317Y756610D03*
Y751610D03*
Y754110D03*
Y749110D03*
Y761610D03*
X282817D03*
X284035Y796850D03*
X285258Y799314D03*
X282323Y794867D03*
X281449Y809609D03*
X283987Y811342D03*
X285565Y1246716D03*
X288065D03*
X283065D03*
X288065Y1251716D03*
X285565D03*
X283065D03*
X288065Y1249216D03*
X285565D03*
X283065D03*
Y1254216D03*
X288065D03*
X285565D03*
X283065Y1269234D03*
X285565D03*
X283065Y1261734D03*
Y1264234D03*
Y1266734D03*
X285565D03*
Y1264234D03*
Y1261734D03*
X283065Y1256716D03*
X285565D03*
X288065D03*
X283065Y1259216D03*
X285565D03*
X288065D03*
Y1266716D03*
Y1264216D03*
Y1261716D03*
Y1269216D03*
X285479Y1271773D03*
X282979D03*
X287979D03*
X284781Y1326726D03*
X282351D03*
X279921D03*
X285891Y1320942D03*
Y1323842D03*
X289611Y1328431D03*
X276905Y1335984D03*
X289711Y1331431D03*
X287545Y1330161D03*
Y1333061D03*
X280088Y1509469D03*
X282588D03*
X279774Y1512220D03*
Y1516120D03*
X284024Y1514576D03*
X279499Y1519845D03*
X284024Y1512076D03*
X290593Y1523331D03*
Y1526731D03*
X291416Y1541795D03*
Y1549295D03*
Y1546795D03*
Y1544295D03*
X285586Y1551844D03*
X288004Y1551099D03*
X290509Y1551844D03*
X288004Y1548199D03*
X284014Y1538682D03*
X286514D03*
X284546Y1549295D03*
Y1546795D03*
Y1541795D03*
Y1544295D03*
X287046D03*
Y1541795D03*
X277046Y1546795D03*
Y1549295D03*
X282046D03*
Y1546795D03*
Y1544295D03*
X279546Y1549295D03*
Y1546795D03*
X282046Y1541795D03*
X300230Y14820D03*
X302606Y26365D03*
X292056Y24475D03*
X295516Y26365D03*
X300244Y28365D03*
X299496Y22865D03*
X304923Y24657D03*
X304968Y28365D03*
X303252Y38199D03*
X298716Y40020D03*
X296337Y55855D03*
X301306Y52485D03*
X298542Y51088D03*
X303711Y50860D03*
X295755Y72800D03*
X301107Y75676D03*
X305820Y73693D03*
X303852Y65042D03*
X306470Y65160D03*
X301780Y82900D03*
X299002Y88700D03*
X307816Y95727D03*
X301179Y112806D03*
Y110006D03*
Y107106D03*
X296478Y149203D03*
X296474Y158706D03*
X292811Y213242D03*
X296283Y242391D03*
X306528Y256528D03*
X297815Y580384D03*
X294299Y577188D03*
X302130Y584160D03*
X304192Y684425D03*
X298923Y684273D03*
X294969Y683828D03*
X292231Y684796D03*
X298923Y681765D03*
X301912Y687950D03*
X305685Y695340D03*
Y692799D03*
X298617Y746478D03*
X296117D03*
X301117D03*
X298621Y753978D03*
X296121D03*
Y751478D03*
Y748978D03*
X298621Y756478D03*
X296121D03*
X301121Y748996D03*
Y751496D03*
Y753996D03*
Y756496D03*
X296117Y759110D03*
Y761610D03*
X301117Y759110D03*
X298617D03*
X301117Y761610D03*
X298617D03*
X298621Y748978D03*
Y751478D03*
X301117Y766610D03*
X296117D03*
Y764110D03*
X301117Y771610D03*
X298617D03*
Y769110D03*
X301117D03*
X296117Y771610D03*
Y769110D03*
X298617Y766610D03*
Y764110D03*
X301117D03*
X305061Y1254131D03*
X300061D03*
X302561D03*
X305061Y1249131D03*
Y1251631D03*
X300061D03*
X302561D03*
X300061Y1249131D03*
X302561D03*
X305061Y1246631D03*
X300061D03*
X302561D03*
X302661Y1269149D03*
X305161D03*
X302661Y1261649D03*
Y1264149D03*
Y1266649D03*
X305161D03*
Y1264149D03*
Y1261649D03*
X300061Y1269131D03*
Y1266631D03*
X305061Y1259131D03*
Y1256631D03*
X300061D03*
Y1259131D03*
Y1261631D03*
Y1264131D03*
X302561Y1256631D03*
Y1259131D03*
X305075Y1271688D03*
X302575D03*
X300075D03*
X295597Y1322844D03*
Y1325385D03*
X291811Y1327031D03*
X297090Y1333759D03*
X302359Y1333911D03*
X306313Y1334356D03*
X302359Y1336419D03*
X299370Y1330234D03*
X291811Y1332831D03*
Y1329931D03*
X294725Y1381612D03*
X294533Y1384401D03*
X305204Y1381461D03*
X305012Y1384250D03*
X294684Y1387040D03*
X305163Y1386889D03*
X294683Y1390281D03*
X305163Y1389678D03*
X295042Y1530596D03*
X296416Y1549295D03*
X293916D03*
Y1546795D03*
X296416D03*
Y1544295D03*
X293916D03*
X296416Y1541795D03*
X293916D03*
X298916D03*
Y1549295D03*
Y1546795D03*
Y1544295D03*
X303041Y1544299D03*
X297323Y1657172D03*
Y1653772D03*
X310396Y50365D03*
X306566Y50225D03*
X323036Y73125D03*
X310455Y75895D03*
X320190Y77648D03*
X314653Y71806D03*
Y68906D03*
X312410Y89060D03*
X322871Y84321D03*
X316982Y89003D03*
X311053Y112806D03*
Y110006D03*
Y107106D03*
X323646Y147120D03*
Y152120D03*
X308240Y148100D03*
X317472Y222262D03*
Y225217D03*
X319970Y228167D03*
X320095Y231810D03*
X319075Y260075D03*
X311749Y440921D03*
X314780Y545716D03*
X322955Y556148D03*
X310445Y700931D03*
X312611Y702301D03*
X321235Y711636D03*
X316375D03*
X318805D03*
X311545Y709931D03*
X310445Y703931D03*
X311445Y706931D03*
X313611Y708201D03*
Y705301D03*
X315912Y717400D03*
Y714500D03*
X313087Y769160D03*
Y771660D03*
Y774160D03*
Y776660D03*
X318091Y769128D03*
Y771628D03*
Y774128D03*
X315591D03*
Y771628D03*
Y769128D03*
X318091Y776628D03*
X315591D03*
X313087Y766628D03*
X315587D03*
X318087D03*
Y791660D03*
X313087D03*
X315587D03*
X318087Y789160D03*
X313087D03*
X315587D03*
Y779160D03*
X313087Y784160D03*
X315587D03*
X313087Y786660D03*
X315587D03*
X313087Y781660D03*
X315587D03*
X313087Y779160D03*
X318087Y786660D03*
Y784160D03*
Y779160D03*
Y781660D03*
X313284Y1218522D03*
Y1215122D03*
X318461Y1254131D03*
X320961D03*
X315961D03*
Y1249131D03*
X318461D03*
X320961D03*
X315961Y1251631D03*
X318461D03*
X320961D03*
X315961Y1246631D03*
X318461D03*
X320961D03*
X315961Y1269149D03*
X318461D03*
X315961Y1261649D03*
Y1264149D03*
Y1266649D03*
X318461D03*
Y1264149D03*
Y1261649D03*
X320961Y1269131D03*
Y1256631D03*
Y1259131D03*
Y1261631D03*
X318461Y1256631D03*
Y1259131D03*
X320961Y1264131D03*
Y1266631D03*
X315961Y1256631D03*
Y1259131D03*
X320875Y1271688D03*
X315875D03*
X318375D03*
X312817Y1326698D03*
X315247D03*
X317677D03*
X318811Y1320902D03*
Y1323802D03*
X309801Y1335956D03*
X309051Y1333388D03*
X320441Y1330133D03*
Y1333033D03*
X307255Y1643750D03*
Y1647150D03*
X323113Y76941D03*
X334339Y162580D03*
X323646Y160120D03*
Y156120D03*
X331780Y182900D03*
X336000Y284000D03*
X324406Y367744D03*
X325816Y543012D03*
X324647Y566086D03*
X334031Y613498D03*
Y610498D03*
X331391D03*
Y613498D03*
X333502Y600019D03*
Y603019D03*
X330109Y602883D03*
Y605883D03*
X334031Y619398D03*
Y616498D03*
X331391D03*
Y619398D03*
X324251Y702378D03*
X331693Y701915D03*
Y704423D03*
X327739Y703978D03*
X325001Y704946D03*
X334682Y708100D03*
X331391Y769128D03*
Y771628D03*
Y774128D03*
X328891D03*
Y771628D03*
Y769128D03*
X331391Y776628D03*
X328891D03*
X333887Y766628D03*
X328887D03*
X331387D03*
X333891Y776646D03*
Y774146D03*
Y771646D03*
Y769146D03*
X333887Y791660D03*
X328887D03*
X331387D03*
X333887Y789160D03*
X328887D03*
X331387D03*
X333887Y779160D03*
Y781660D03*
X331387Y779160D03*
X328887D03*
Y781660D03*
X331387D03*
X333887Y786660D03*
X328887D03*
X331387D03*
X333887Y784160D03*
X328887D03*
X331387D03*
X335465Y1246631D03*
X332965D03*
X335465Y1249131D03*
X332965D03*
X335465Y1251631D03*
X332965D03*
X335465Y1254131D03*
X332965D03*
X335465Y1259131D03*
Y1256631D03*
X332965Y1259131D03*
Y1256631D03*
X335565Y1269149D03*
Y1261649D03*
Y1264149D03*
Y1266649D03*
X332961Y1269188D03*
Y1266688D03*
Y1261688D03*
Y1264188D03*
Y1271688D03*
X335461D03*
X328501Y1322787D03*
Y1325328D03*
X324707Y1327003D03*
X322507Y1328403D03*
X329994Y1333702D03*
X335263Y1333854D03*
Y1336362D03*
X332274Y1330177D03*
X324707Y1332803D03*
X322607Y1331403D03*
X324707Y1329903D03*
X334038Y1373469D03*
X334230Y1370680D03*
X323559Y1373620D03*
X323751Y1370831D03*
X334189Y1376108D03*
X323710Y1376259D03*
X334189Y1378897D03*
X323709Y1379500D03*
X341082Y56308D03*
X340436Y120555D03*
X343446Y131170D03*
X338244Y192264D03*
X344984Y199299D03*
X344106Y222659D03*
X348107Y220420D03*
X341895Y233980D03*
X348645Y229180D03*
X352000Y230643D03*
Y235643D03*
X344034Y282609D03*
X348890Y409120D03*
Y411620D03*
X340337Y496462D03*
X346751Y515376D03*
X351157Y550415D03*
X350566Y541882D03*
X351018Y554896D03*
X351157Y566936D03*
X345521Y564388D03*
X349397Y564459D03*
X351157Y570415D03*
X341500Y574500D03*
X342500Y582500D03*
Y578500D03*
X338420Y574500D03*
X351157Y590415D03*
Y586415D03*
X337031Y607498D03*
Y613498D03*
Y610498D03*
X346031Y607498D03*
X343031D03*
X349031D03*
X346031Y610498D03*
X343031D03*
X349031D03*
X340031Y607498D03*
Y610498D03*
Y613498D03*
X346031Y604498D03*
X343031D03*
X349031D03*
X340031D03*
X343691Y614018D03*
X346191D03*
X348691D03*
X343721Y618348D03*
X346221D03*
X348721D03*
X351191Y614018D03*
X351221Y618348D03*
X340031Y619398D03*
Y616498D03*
X337031Y619398D03*
Y616498D03*
X342675Y640994D03*
X345175D03*
X347675D03*
X350175D03*
X342675Y643494D03*
X345175D03*
X347675D03*
X350175D03*
X342595Y646054D03*
X345095D03*
X347595D03*
X350095D03*
X336962Y704575D03*
X338455Y715490D03*
Y712949D03*
X349435Y711368D03*
X346671Y705033D03*
X344505Y706663D03*
X346671Y707933D03*
X344605Y709663D03*
X342405Y705263D03*
Y708163D03*
Y711063D03*
X348395Y717060D03*
Y714160D03*
X346051Y769058D03*
Y771558D03*
Y774058D03*
Y776558D03*
X351151Y769040D03*
Y771540D03*
Y774040D03*
X348651D03*
Y771540D03*
Y769040D03*
X351151Y776540D03*
X348651D03*
X351147Y766540D03*
X348647D03*
X346147D03*
X346051Y791558D03*
X348551D03*
X351051D03*
X346051Y789058D03*
X348551D03*
X346051Y784058D03*
X348551D03*
X346051Y786558D03*
X348551D03*
X346051Y779058D03*
X348551D03*
X346051Y781558D03*
X348551D03*
X351051Y789058D03*
Y784058D03*
Y786558D03*
Y779058D03*
Y781558D03*
X347107Y1174343D03*
X339278Y1192112D03*
X336778D03*
X347885Y1206426D03*
X339532Y1218605D03*
X349938Y1214563D03*
X337965Y1251631D03*
Y1249131D03*
Y1254131D03*
X348865Y1246631D03*
Y1251631D03*
Y1249131D03*
Y1254131D03*
X337965Y1246631D03*
X348865Y1269149D03*
Y1261649D03*
Y1264149D03*
Y1266649D03*
X338065Y1269149D03*
Y1266649D03*
Y1264149D03*
Y1261649D03*
X337965Y1256631D03*
Y1259131D03*
X348865D03*
Y1256631D03*
X337961Y1271688D03*
X348861D03*
X348151Y1326641D03*
X350581D03*
X345721D03*
X342705Y1335899D03*
X339217Y1334299D03*
X341955Y1333331D03*
X346464Y1380102D03*
X343964D03*
X348964D03*
Y1387602D03*
Y1385102D03*
Y1382602D03*
X343964Y1385102D03*
Y1387602D03*
X346464Y1385102D03*
Y1387602D03*
X343964Y1382602D03*
X346464D03*
X348964Y1390102D03*
X343964D03*
Y1392602D03*
X346464D03*
Y1390102D03*
X343777Y1395166D03*
X346302Y1395242D03*
X348828Y1395392D03*
X349032Y1392675D03*
X361744Y120713D03*
X363621Y127665D03*
X361171Y223114D03*
X358618Y223129D03*
X361171Y220614D03*
X358671D03*
X355910Y223847D03*
X365739Y221871D03*
X365559Y238896D03*
X357925Y304082D03*
X351390Y409120D03*
X353890D03*
Y411620D03*
X351390D03*
X365852Y516466D03*
X365071Y551038D03*
X355100Y544390D03*
X362200Y566750D03*
X364047Y556773D03*
X359200Y566990D03*
X360261Y561044D03*
X359657Y570702D03*
X359157Y574415D03*
X365158Y597546D03*
Y593580D03*
X352031Y607498D03*
Y610498D03*
X355031Y607498D03*
Y613498D03*
Y610498D03*
X352031Y604498D03*
X355031D03*
X361031Y607498D03*
Y613498D03*
Y610498D03*
X358031Y607498D03*
Y613498D03*
Y610498D03*
Y604498D03*
Y619398D03*
Y616498D03*
X355031Y619398D03*
Y616498D03*
X361031Y619398D03*
Y616498D03*
X352675Y640994D03*
Y643494D03*
X355275Y641034D03*
Y643534D03*
X355195Y646094D03*
X352595Y646054D03*
X357311Y702110D03*
X364753Y701647D03*
Y704155D03*
X360799Y703710D03*
X358061Y704678D03*
X351865Y711368D03*
X354295D03*
X364451Y769040D03*
Y771540D03*
Y774040D03*
X361951D03*
Y771540D03*
Y769040D03*
X364451Y776540D03*
X361951D03*
X364447Y766540D03*
X361947D03*
X364451Y791558D03*
X361951D03*
X364451Y786558D03*
Y789058D03*
X361951D03*
Y786558D03*
X364451Y784058D03*
X361951Y781558D03*
X364451Y779058D03*
Y781558D03*
X361951Y779058D03*
Y784058D03*
X361671Y803588D03*
X356671D03*
X351671D03*
X363313Y812088D03*
X359813Y812188D03*
X356313D03*
X352813D03*
X356535Y849708D03*
X364897Y852564D03*
X364821Y861852D03*
X357400Y855982D03*
X356895Y859791D03*
X353281Y859620D03*
X363236Y1199632D03*
X361922Y1206891D03*
X357271Y1208988D03*
X351413Y1210052D03*
X365461Y1254188D03*
Y1251688D03*
Y1249188D03*
Y1246688D03*
X351365Y1246631D03*
X353865D03*
Y1251631D03*
X351365D03*
X353865Y1249131D03*
X351365D03*
X353865Y1254131D03*
X351365D03*
Y1269149D03*
Y1266649D03*
Y1264149D03*
Y1261649D03*
X365461Y1256688D03*
Y1259188D03*
X353865Y1266631D03*
Y1264131D03*
Y1261631D03*
Y1269131D03*
X351365Y1259131D03*
Y1256631D03*
X353865Y1259131D03*
Y1256631D03*
X365561Y1269288D03*
Y1264288D03*
Y1266788D03*
Y1261788D03*
Y1271788D03*
X351361Y1271688D03*
X353861D03*
X361301Y1322987D03*
Y1325528D03*
X351651Y1320942D03*
Y1323842D03*
X357611Y1326946D03*
X355411Y1328346D03*
X362794Y1333902D03*
X365074Y1330377D03*
X353345Y1332976D03*
X357611Y1329846D03*
X353345Y1330076D03*
X355511Y1331346D03*
X357611Y1332746D03*
X356764Y1359296D03*
X354264D03*
X364764D03*
X362264D03*
X359764D03*
X351632Y1359203D03*
X351923Y1364724D03*
X354423D03*
X356923D03*
X359423D03*
X362223D03*
X364723D03*
X351772Y1362085D03*
X354272D03*
X356772D03*
X359272D03*
X362072D03*
X364572D03*
X363964Y1385102D03*
X356464Y1380102D03*
X358964D03*
X361464D03*
X353964D03*
X351464D03*
X363964D03*
Y1382602D03*
X351464Y1385102D03*
X353964D03*
X361464D03*
X356464D03*
X358964D03*
X351464Y1382602D03*
X361464D03*
X358964D03*
X356464D03*
X353964D03*
X352067Y1387665D03*
X354567D03*
X357067D03*
X359567D03*
X363190Y1387527D03*
X365979Y1387641D03*
X352332Y1391886D03*
X354832D03*
X357332D03*
X359832D03*
X363191Y1390292D03*
Y1392792D03*
X365980Y1392906D03*
Y1390406D03*
X363003Y1395393D03*
X365792Y1395507D03*
X352313Y1395223D03*
X359859D03*
X357208D03*
X365493Y1655107D03*
X370888Y155250D03*
X377118Y222229D03*
X380012Y239615D03*
X370327Y228951D03*
X370352Y235455D03*
X366671Y297114D03*
X369171D03*
X369671Y292114D03*
Y294614D03*
X380935Y443386D03*
X375935D03*
X378435D03*
X382184Y466351D03*
X378976Y479226D03*
X379633Y493942D03*
X371962Y524954D03*
X368371Y553038D03*
X371971Y553138D03*
X375410Y552254D03*
X377502Y554193D03*
X380157Y553090D03*
X375271Y542191D03*
X379114Y544866D03*
X368647Y550422D03*
X370271Y555038D03*
X379689Y586040D03*
X368798Y587938D03*
X369271Y600138D03*
X373477Y593338D03*
X378577Y593026D03*
X377577Y590126D03*
X370022Y704307D03*
X371515Y715222D03*
Y712681D03*
X367742Y707832D03*
X379711Y708001D03*
Y705101D03*
X375445Y708231D03*
X377545Y706731D03*
X375445Y705331D03*
X377645Y709731D03*
X375445Y711131D03*
X366951Y769058D03*
Y771558D03*
Y774058D03*
Y776558D03*
X379187Y766428D03*
Y768960D03*
Y771460D03*
Y773960D03*
Y776460D03*
X366947Y766540D03*
X366951Y781558D03*
Y786558D03*
Y789058D03*
Y784058D03*
X379187Y786460D03*
Y783960D03*
Y788960D03*
Y778960D03*
Y781460D03*
X366951Y791558D03*
X379187Y791460D03*
X366951Y779058D03*
X376671Y803588D03*
X371671D03*
X366671D03*
X366864Y857274D03*
X369626Y860717D03*
X370316Y1204673D03*
X367931Y1196981D03*
X376271Y1207488D03*
X380718Y1221906D03*
X379223Y1219527D03*
X372126Y1214455D03*
X368726D03*
X367961Y1254188D03*
Y1251688D03*
Y1249188D03*
Y1246688D03*
X370461Y1254188D03*
Y1249188D03*
Y1251688D03*
Y1246688D03*
X367961Y1256688D03*
Y1259188D03*
X370461D03*
Y1256688D03*
X368061Y1269206D03*
X370561D03*
X368061Y1261706D03*
Y1264206D03*
Y1266706D03*
X370561D03*
Y1264206D03*
Y1261706D03*
Y1271788D03*
X368061D03*
X380951Y1326841D03*
X378521D03*
X368063Y1334054D03*
X375505Y1336099D03*
X372017Y1334499D03*
X374755Y1333531D03*
X368063Y1336562D03*
X368964Y1382602D03*
Y1385102D03*
X366464D03*
X368964Y1380102D03*
X366464D03*
Y1382602D03*
X368542Y1387639D03*
X368543Y1390404D03*
Y1392904D03*
X368355Y1395505D03*
X374432Y1582600D03*
X375050Y1639400D03*
X371823Y1644516D03*
X370533Y1658605D03*
X374962Y1648511D03*
X372953Y1653197D03*
X373330Y1668539D03*
X370369Y1661817D03*
X372449Y1680520D03*
X372395Y1677449D03*
X395048Y121178D03*
X384375Y147365D03*
X386350Y138980D03*
X395590Y147010D03*
X391310Y227871D03*
X389912Y280345D03*
X390881Y284156D03*
X395053Y318125D03*
X383525Y443386D03*
X389784Y476070D03*
X384827Y507057D03*
X397184Y507101D03*
X382184D03*
X388985Y554870D03*
X383071Y553738D03*
X382705Y546433D03*
X395171Y559463D03*
X395669Y563328D03*
X385318Y555238D03*
X394168Y568482D03*
X395157Y573815D03*
X393481Y571239D03*
X387103Y584506D03*
X392471Y596988D03*
X391021Y588788D03*
X390351Y702178D03*
X393839Y703778D03*
X391101Y704746D03*
X382475Y711436D03*
X387335D03*
X384905D03*
X381812Y717060D03*
Y714160D03*
X394987Y766428D03*
X381687D03*
X384187D03*
X394991Y773928D03*
Y771428D03*
Y768928D03*
Y776428D03*
X384191Y768928D03*
Y771428D03*
Y773928D03*
X381691D03*
Y771428D03*
Y768928D03*
X384191Y776428D03*
X381691D03*
X381687Y791460D03*
X384187D03*
X394987Y784060D03*
Y779060D03*
Y781560D03*
Y789060D03*
Y786560D03*
X381687Y778960D03*
Y786460D03*
Y783960D03*
Y788960D03*
Y781460D03*
X384187Y788960D03*
Y786460D03*
Y783960D03*
Y778960D03*
Y781460D03*
X386381Y1015474D03*
X393861D03*
X386381Y1022560D03*
Y1019017D03*
X393861Y1022560D03*
Y1019017D03*
X390974Y1222849D03*
Y1219449D03*
X388630Y1236747D03*
X381361Y1254188D03*
Y1249188D03*
Y1251688D03*
Y1246688D03*
X383861Y1254188D03*
X386361D03*
X383861Y1249188D03*
X386361D03*
X383861Y1251688D03*
X386361D03*
X383861Y1246688D03*
X386361D03*
X388630Y1240147D03*
X381361Y1269206D03*
X383861D03*
X381361Y1261706D03*
Y1264206D03*
Y1266706D03*
X383861D03*
Y1264206D03*
Y1261706D03*
X381361Y1256688D03*
Y1259188D03*
X386361Y1256688D03*
Y1259188D03*
X383861Y1256688D03*
Y1259188D03*
X386361Y1269288D03*
Y1261788D03*
Y1266788D03*
Y1264288D03*
X381361Y1271788D03*
X386361D03*
X383861D03*
X383381Y1326841D03*
X384481Y1321192D03*
Y1324092D03*
X388211Y1328546D03*
X393883Y1342318D03*
X388311Y1331546D03*
X386145Y1333176D03*
Y1330276D03*
X386611Y1336056D03*
X388771Y1337546D03*
Y1334546D03*
X395376Y1353233D03*
X393883Y1344859D03*
X395384Y1519250D03*
X395359Y1546519D03*
X389290Y1561250D03*
X387939Y1565534D03*
X389276Y1568413D03*
X391526Y1582373D03*
X394521Y1575891D03*
X388784Y1581801D03*
X393005Y1592304D03*
X381711Y1593842D03*
X381607Y1590393D03*
X388445Y1585898D03*
X389333Y1598816D03*
X387805Y1617302D03*
Y1614802D03*
X394824Y1629713D03*
X394000Y1621500D03*
X389824Y1629713D03*
X389000Y1621500D03*
X384824Y1629713D03*
X381350Y1649000D03*
Y1642900D03*
Y1645800D03*
X382115Y1661545D03*
X387324Y1680495D03*
X392324D03*
X382642Y1680979D03*
X385068Y1683502D03*
X410500Y104883D03*
X410400Y107383D03*
X399264Y121144D03*
X403141Y148300D03*
X410678Y159140D03*
X408603Y152278D03*
X411299Y212096D03*
X400000Y220300D03*
X411940Y240501D03*
X410000Y304000D03*
X402184Y466469D03*
X410984Y496649D03*
X406184Y507900D03*
X403657Y546915D03*
X408550Y557850D03*
X404871Y567338D03*
X403381Y573516D03*
X410111Y572608D03*
X407543Y577415D03*
Y580490D03*
X408445Y687531D03*
X397793Y701715D03*
X410645Y691931D03*
X410545Y688931D03*
X408445Y690431D03*
Y693331D03*
X403062Y704375D03*
X397793Y704223D03*
X404555Y715290D03*
Y712749D03*
X400782Y707900D03*
X399991Y776560D03*
X397491Y768928D03*
Y771428D03*
Y773928D03*
Y776428D03*
X397487Y766428D03*
X399991Y771560D03*
Y769060D03*
X399987Y766428D03*
X399991Y774060D03*
X397487Y779060D03*
Y781560D03*
Y786560D03*
Y784060D03*
X399991D03*
Y779060D03*
Y781560D03*
X401341Y1015474D03*
Y1019017D03*
Y1022560D03*
X403347Y1266162D03*
Y1268662D03*
X400847Y1266162D03*
X398347D03*
X400847Y1268662D03*
X398347D03*
X403347Y1271162D03*
Y1273662D03*
X400847Y1271162D03*
X398347D03*
X400847Y1273662D03*
X398347D03*
X403347Y1276162D03*
Y1278662D03*
X400847D03*
Y1276162D03*
X398347Y1278662D03*
Y1276162D03*
X398447Y1281262D03*
Y1283762D03*
X400947Y1281180D03*
Y1283680D03*
X403447D03*
Y1281180D03*
X400947Y1288680D03*
X403447D03*
X400947Y1286180D03*
X403447D03*
X398447Y1286262D03*
Y1288762D03*
X398461Y1291319D03*
X403461D03*
X400961D03*
X400645Y1353385D03*
X408087Y1355430D03*
X404599Y1353830D03*
X407337Y1352862D03*
X400645Y1355893D03*
X397656Y1349708D03*
X401536Y1516120D03*
Y1512220D03*
X397206Y1516953D03*
Y1511953D03*
Y1514453D03*
X397891Y1521436D03*
X401659Y1519845D03*
X404686Y1516120D03*
Y1512220D03*
X410650Y1509469D03*
X408150D03*
X407836Y1512220D03*
Y1516120D03*
X407561Y1519845D03*
X404699Y1521436D03*
X410108Y1535680D03*
X408895Y1553644D03*
X405331Y1548928D03*
X410851Y1557434D03*
X407198Y1564990D03*
X401249Y1564422D03*
X405758Y1557900D03*
X402912Y1558011D03*
X396452Y1577738D03*
X403163Y1579357D03*
X403004Y1582457D03*
X408925Y1573805D03*
Y1576805D03*
X404669Y1594317D03*
X403837Y1609056D03*
Y1612456D03*
X399447Y1612609D03*
X399801Y1606376D03*
X406697Y1604207D03*
X408856Y1623435D03*
X400380Y1621500D03*
X405436Y1620268D03*
X406343Y1613847D03*
X405747Y1623350D03*
X404640Y1637425D03*
X397822Y1629615D03*
X409552Y1633606D03*
X405342Y1628611D03*
X404661Y1634139D03*
X412000Y1647177D03*
X403844Y1665769D03*
X405000Y1675000D03*
X397324Y1680495D03*
X409000Y1683500D03*
X424975Y54762D03*
X417025D03*
X416549Y66365D03*
Y71665D03*
X427300Y71300D03*
X419900Y96620D03*
X414100D03*
X424084Y110839D03*
X424086Y123023D03*
X422890Y136700D03*
X424086Y133265D03*
X412370Y188210D03*
X411610Y223140D03*
X424815Y217646D03*
X422936Y223501D03*
X419299Y212096D03*
X423299D03*
X420115Y230323D03*
Y240501D03*
Y235442D03*
Y226323D03*
X411940Y235442D03*
X412715Y251165D03*
Y258165D03*
Y266165D03*
X419617Y308000D03*
X424151Y453174D03*
X415984Y466392D03*
X424784Y496572D03*
X419984Y508000D03*
X411500Y510800D03*
X412771Y524820D03*
X414402Y544690D03*
X423351Y684378D03*
X424101Y686946D03*
X412711Y687301D03*
X420335Y693636D03*
X415475D03*
X417905D03*
X412711Y690201D03*
X414712Y699440D03*
Y696540D03*
X420158Y748643D03*
X415158Y756175D03*
Y751175D03*
Y753675D03*
X417658Y748643D03*
X415158D03*
Y761175D03*
X420158D03*
X417658D03*
X415158Y758675D03*
X420162Y751143D03*
Y753643D03*
Y756143D03*
X417662D03*
Y753643D03*
Y751143D03*
X420162Y758643D03*
X417662D03*
X415158Y771175D03*
X420158Y763675D03*
Y766175D03*
X417658Y768675D03*
X415158D03*
X417658Y763675D03*
Y766175D03*
X415158Y763675D03*
Y766175D03*
X415318Y1009765D03*
Y1006025D03*
X424873Y1014745D03*
X423811Y1005800D03*
X415318Y1013505D03*
X424873Y1023013D03*
Y1018879D03*
X415318Y1028466D03*
Y1020986D03*
Y1024726D03*
Y1017245D03*
X418918Y1032206D03*
X423811Y1032431D03*
X424024Y1267144D03*
X414247Y1268662D03*
X416747D03*
X419247D03*
X424024Y1269644D03*
Y1272144D03*
X414247Y1281180D03*
Y1283680D03*
X416747D03*
Y1281180D03*
Y1271162D03*
X414247D03*
X416747Y1278662D03*
Y1276162D03*
X419247Y1278662D03*
Y1276162D03*
Y1273662D03*
X416747D03*
X414247Y1278662D03*
Y1276162D03*
Y1273662D03*
X419361Y1283719D03*
Y1281219D03*
X419247Y1271162D03*
X424024Y1274644D03*
X414247Y1288680D03*
X416747D03*
X414247Y1286180D03*
X416747D03*
X419361Y1288719D03*
Y1291219D03*
X414361D03*
X416861D03*
X419361Y1286219D03*
X417063Y1340523D03*
Y1343423D03*
X415963Y1346172D03*
X413533D03*
X411103D03*
X421315Y1354276D03*
Y1351376D03*
X421205Y1348586D03*
Y1345686D03*
X418675Y1352166D03*
Y1349266D03*
X425631Y1517138D03*
X425087Y1510708D03*
X422587D03*
X423131Y1517138D03*
X412086Y1512076D03*
Y1514576D03*
X422557Y1537595D03*
X420057D03*
X417098Y1536411D03*
X418157Y1549295D03*
X423157Y1541795D03*
Y1544295D03*
X415657Y1541795D03*
X418157Y1546795D03*
Y1544295D03*
Y1541795D03*
X415657Y1549295D03*
Y1546795D03*
Y1544295D03*
X420657Y1541795D03*
Y1544295D03*
Y1546795D03*
Y1549295D03*
X417098Y1538911D03*
X424115Y1548199D03*
Y1551099D03*
X421697Y1551844D03*
X421683Y1565312D03*
X421108Y1560235D03*
X424488Y1565400D03*
X413540Y1556646D03*
X424616Y1560086D03*
X414202Y1559396D03*
X421294Y1557729D03*
X419254Y1566828D03*
X427081Y1581620D03*
X421277Y1571923D03*
X413396Y1594597D03*
X410991Y1597002D03*
X425469Y1595433D03*
X422069D03*
X419277Y1600725D03*
X414500Y1639075D03*
X417365Y1627695D03*
X420765D03*
X423500Y1652500D03*
X411448Y1650598D03*
X420000Y1664925D03*
X411500Y1657500D03*
X417000Y1675000D03*
X413000Y1683500D03*
X415500Y1672500D03*
X433673Y73960D03*
X428149Y65016D03*
X431359Y82589D03*
X433997Y166400D03*
X437997D03*
X436103Y158594D03*
X437997Y170701D03*
X433997D03*
X438200Y212096D03*
X431299Y212095D03*
X437440Y237270D03*
X442710Y237990D03*
X435710Y250340D03*
X440710D03*
X426947Y320749D03*
X433277Y471970D03*
X429784Y466315D03*
X426208Y468977D03*
X436226Y475526D03*
X437084Y501865D03*
X429784Y506947D03*
X442084Y511870D03*
X427500Y510553D03*
X426011Y524888D03*
X436062Y686575D03*
X430793Y686423D03*
X426839Y685978D03*
X430793Y683915D03*
X437555Y697490D03*
Y694949D03*
X433782Y690100D03*
X430958Y748643D03*
X433458D03*
X433462Y751143D03*
Y753643D03*
Y756143D03*
X430962D03*
Y753643D03*
Y751143D03*
Y758643D03*
X440159Y970341D03*
Y977841D03*
Y985341D03*
X438359Y993766D03*
X438434Y989766D03*
X438359Y997766D03*
X427551Y1005800D03*
X434716Y1014745D03*
X431291Y1005800D03*
X435031D03*
X438771D03*
X438359Y1001766D03*
X434716Y1018879D03*
Y1023013D03*
X431291Y1032431D03*
X435031D03*
X438771D03*
X427551D03*
X427615Y1282917D03*
Y1275417D03*
Y1280417D03*
Y1277917D03*
X436903Y1285694D03*
Y1289694D03*
X426704Y1523331D03*
Y1526731D03*
X439935Y1532600D03*
X430027Y1546795D03*
Y1544295D03*
X432527Y1541795D03*
Y1549295D03*
Y1546795D03*
Y1544295D03*
X430027Y1541795D03*
Y1549295D03*
X435027D03*
Y1546795D03*
Y1544295D03*
Y1541795D03*
X427527Y1549295D03*
Y1546795D03*
Y1544295D03*
Y1541795D03*
X426620Y1551844D03*
X437736Y1544392D03*
X431923Y1565790D03*
X432051Y1560635D03*
X437910Y1553910D03*
X433440Y1581700D03*
X429947Y1594398D03*
X436776Y1610394D03*
X430500Y1605835D03*
X431664Y1624342D03*
X436776Y1613794D03*
X433012Y1621612D03*
X430500Y1613709D03*
X434500Y1641500D03*
X431000Y1640500D03*
X432000Y1650000D03*
X436925Y1649500D03*
X441182Y77125D03*
X445267Y82124D03*
X452948Y104003D03*
X445997Y166400D03*
X453997D03*
X449997D03*
X448038Y158659D03*
X441997Y170701D03*
X449997D03*
X448499Y212036D03*
X443299Y212095D03*
X456231Y227764D03*
X443299Y220046D03*
X447299D03*
X456231Y232883D03*
X455422Y244103D03*
X444310Y243370D03*
X446710Y249340D03*
X454518Y280793D03*
X447840Y275970D03*
X441320Y295170D03*
Y301170D03*
Y307170D03*
Y313170D03*
Y316170D03*
X442297Y474442D03*
X453269Y478388D03*
X449496Y474009D03*
X446547Y480123D03*
X443683Y502256D03*
X448024Y505345D03*
X452084Y511870D03*
X447084D03*
X457084D03*
X453723Y526558D03*
X444441Y565549D03*
X450305Y669036D03*
X452735D03*
X447875D03*
X440845Y668731D03*
Y665831D03*
X445111Y662701D03*
X442945Y664331D03*
X440845Y662931D03*
X443045Y667331D03*
X445111Y665601D03*
X447212Y671640D03*
Y674540D03*
X446686Y726660D03*
Y729160D03*
Y731660D03*
X449190Y726528D03*
Y729028D03*
Y731528D03*
X451690D03*
Y729028D03*
Y726528D03*
X446686Y724028D03*
X449186D03*
X451686D03*
Y741660D03*
X449186D03*
Y739160D03*
Y736660D03*
X451686Y739160D03*
Y736660D03*
X446686Y741660D03*
Y736660D03*
Y739160D03*
Y734160D03*
X449190Y734028D03*
X451690D03*
X453810Y1014745D03*
X449992Y1005800D03*
X453732D03*
X443574Y1014745D03*
X446252Y1005800D03*
X442511D03*
X453810Y1023013D03*
X443574D03*
X453810Y1018879D03*
X443574D03*
X453732Y1032431D03*
X442884Y1038766D03*
X442511Y1032431D03*
X442884Y1042766D03*
X446252Y1032431D03*
X449992D03*
X441159Y1051541D03*
X443764Y1179395D03*
X446810Y1565020D03*
X446910Y1562098D03*
X446653Y1573264D03*
X441931Y1581662D03*
X443590Y1593880D03*
X441460Y1596020D03*
X450500Y1612450D03*
X446182Y1625555D03*
X450180Y1614950D03*
X445800Y1633200D03*
Y1636000D03*
X446000Y1650000D03*
X462653Y72525D03*
X470010Y141070D03*
X461997Y166400D03*
X471371Y227764D03*
X461931Y212703D03*
X468574Y213104D03*
X471371Y222764D03*
X464440Y218253D03*
X460567Y225205D03*
Y235442D03*
X460624Y240953D03*
Y230323D03*
X463240Y244980D03*
X456720Y285158D03*
X457248Y280143D03*
Y282643D03*
X470243Y285693D03*
X467545Y356864D03*
X460441Y499842D03*
X457424Y497978D03*
X468638Y514096D03*
X465766Y524991D03*
X458725Y524480D03*
X470331Y566632D03*
X465331D03*
X467831D03*
X462831D03*
X467831Y569132D03*
X470331D03*
X459931Y566632D03*
X457431D03*
X462831Y569132D03*
X457431D03*
X459931D03*
X465331D03*
X470331Y576132D03*
X467831Y571632D03*
X465331D03*
X467831Y576132D03*
X465331D03*
X470331Y571632D03*
X462831D03*
Y576132D03*
X457431Y571632D03*
Y574132D03*
X459931Y571632D03*
Y574132D03*
X457431Y576632D03*
X459931D03*
X462831Y598514D03*
X467831D03*
X470331D03*
X465331D03*
X457711D03*
X460211D03*
X462831Y601014D03*
X467831D03*
X470331D03*
X465331D03*
X457711D03*
X460211D03*
X469955Y672890D03*
X463193Y659315D03*
X468462Y661975D03*
X463193Y661823D03*
X455751Y659778D03*
X459239Y661378D03*
X469955Y670349D03*
X456501Y662346D03*
X466182Y665500D03*
X462490Y731528D03*
Y726528D03*
Y729028D03*
X464990D03*
Y726528D03*
X467486Y724028D03*
X464986D03*
X462486D03*
X467490Y726660D03*
X457472Y1005800D03*
X465965Y1009765D03*
Y1006025D03*
Y1013505D03*
Y1020986D03*
Y1024726D03*
Y1028466D03*
Y1017245D03*
Y1032206D03*
X457472Y1032431D03*
X462215Y1581510D03*
X462753Y1641289D03*
X459500Y1659000D03*
X467500Y1651500D03*
X457000Y1650000D03*
X468075Y1662500D03*
X470463Y1670038D03*
X464925Y1662500D03*
X467500Y1678500D03*
X468575Y1704000D03*
X462500Y1697000D03*
X466000Y1714575D03*
X468575Y1731000D03*
X479400Y90574D03*
Y94574D03*
Y97574D03*
Y110930D03*
X479465Y119644D03*
Y115644D03*
Y123644D03*
X482380Y141942D03*
X483800Y189400D03*
X480200Y191900D03*
X480700Y208200D03*
X480715Y211099D03*
X471371Y235764D03*
X483227Y233000D03*
X487620Y270400D03*
X479870D03*
X483823Y285893D03*
X474808Y291492D03*
X482893Y291293D03*
X479148Y315502D03*
X484063Y305669D03*
X480773Y307153D03*
X471015Y527283D03*
X475731Y566632D03*
X473231D03*
Y569132D03*
X475731D03*
Y574132D03*
Y571632D03*
X473231Y574132D03*
Y571632D03*
X475731Y576632D03*
X473231D03*
X485335Y642536D03*
X480475D03*
X482905D03*
X473445Y642231D03*
X477711Y639101D03*
X475645Y640831D03*
X473445Y639331D03*
X475545Y637831D03*
X473445Y636431D03*
X477711Y636201D03*
X479812Y645240D03*
Y648140D03*
X479058Y702660D03*
Y700160D03*
X484062Y700028D03*
Y702528D03*
X481562D03*
Y700028D03*
X479058Y697528D03*
X481558D03*
X484058D03*
X479058Y717660D03*
Y707660D03*
Y712660D03*
Y710160D03*
Y715160D03*
X484058Y710160D03*
Y712660D03*
X481558Y710160D03*
Y712660D03*
X484058Y715160D03*
X481558D03*
X484062Y707528D03*
X481562D03*
X479058Y705160D03*
X484062Y705028D03*
X481562D03*
X480803Y1015474D03*
Y1022560D03*
Y1019017D03*
X483500Y1658500D03*
X479500Y1666500D03*
X473500Y1662500D03*
X477538Y1661463D03*
X474000Y1704000D03*
X478500Y1697000D03*
Y1710500D03*
Y1733500D03*
X491849Y55095D03*
Y60105D03*
X497885Y51315D03*
X491849Y64965D03*
X500674Y116261D03*
X485780Y141942D03*
X500136Y141058D03*
X495500Y161386D03*
X497700Y157200D03*
X492685Y160994D03*
X486682Y193516D03*
X495232D03*
Y185516D03*
X486682Y189516D03*
X496831Y205030D03*
X499380Y222510D03*
X491635Y225970D03*
X494144Y221370D03*
X487442Y223377D03*
X500209Y227881D03*
X491635Y215652D03*
X500209Y233000D03*
X491859D03*
X500119Y243173D03*
X500209Y238119D03*
X491577Y238120D03*
Y243240D03*
X485962Y290679D03*
X487827Y354017D03*
X490419Y362138D03*
X498500Y419425D03*
X495793Y632815D03*
X495839Y635323D03*
X488351Y633278D03*
X491839Y634878D03*
X489101Y635846D03*
X498782Y639000D03*
X497362Y700028D03*
Y702528D03*
X494862D03*
Y700028D03*
X499858Y697528D03*
X497358D03*
X494858D03*
X499862Y700160D03*
Y702660D03*
X494862Y705028D03*
X497362D03*
X499862Y705160D03*
X488384Y1015474D03*
X495884D03*
X488384Y1022560D03*
Y1019017D03*
X495884Y1022560D03*
Y1019017D03*
X512658Y46613D03*
X504796Y86320D03*
X516020Y105370D03*
Y109270D03*
X513772Y121220D03*
X502750Y111276D03*
X503000Y135600D03*
X509346Y125842D03*
X507945Y160919D03*
X503161Y154620D03*
X500600Y157100D03*
X505315Y196944D03*
X503507Y185516D03*
X504351Y202776D03*
X508238Y199506D03*
X512076Y206404D03*
X511684Y221219D03*
X504351Y215901D03*
X508001Y220166D03*
X515223Y289035D03*
Y313200D03*
Y305145D03*
X513775Y608436D03*
X506745Y608131D03*
X508945Y606731D03*
X506745Y602331D03*
Y605231D03*
X508845Y603731D03*
X511011Y602101D03*
Y605001D03*
X513012Y611040D03*
Y613940D03*
X501062Y635475D03*
X502555Y646390D03*
Y643849D03*
X514162Y673428D03*
Y665928D03*
Y668428D03*
Y670928D03*
X514158Y663428D03*
Y678460D03*
Y683460D03*
Y680960D03*
Y675960D03*
X509572Y865327D03*
X513572D03*
X524713Y33346D03*
X529713D03*
X516058Y46613D03*
X519765Y40328D03*
X523165D03*
X519743Y71436D03*
X523143D03*
X524993Y125914D03*
X521618Y165428D03*
X519268Y167428D03*
X519601Y196117D03*
X518691Y191846D03*
X517314Y200449D03*
X519248Y280721D03*
X516723D03*
X521773D03*
X520273Y289035D03*
X517748D03*
X522798D03*
X520273Y313200D03*
X517748D03*
X520273Y305145D03*
X517748D03*
X515523Y335613D03*
X529317Y403784D03*
X524680Y417602D03*
X529095Y452049D03*
X529153Y598735D03*
X529235Y601543D03*
X521651Y599178D03*
X525139Y600778D03*
X522401Y601746D03*
X516205Y608436D03*
X518635D03*
X529962Y673428D03*
Y670928D03*
Y668428D03*
Y665928D03*
X516662Y673428D03*
Y670928D03*
Y668428D03*
Y665928D03*
X527462Y673428D03*
Y665928D03*
Y668428D03*
Y670928D03*
X516658Y663428D03*
X527458D03*
X529958D03*
X516658Y678460D03*
Y683460D03*
Y680960D03*
X527458Y678460D03*
X516658Y675960D03*
X527458D03*
X529958D03*
Y678460D03*
X526474Y851934D03*
Y849434D03*
X517009Y856494D03*
X523074Y853439D03*
Y855939D03*
X528220Y1167366D03*
X517118D03*
X520818D03*
X539120Y31340D03*
X535117D03*
X544721Y42892D03*
X539721Y42862D03*
X541003Y71436D03*
X544403D03*
X538210Y90618D03*
X540615Y88213D03*
X535170Y111230D03*
Y115130D03*
X530567Y125914D03*
X543408Y133912D03*
X538166Y130698D03*
X541675Y146874D03*
Y151470D03*
Y142021D03*
Y137169D03*
Y156195D03*
X533442Y164428D03*
X532222Y207849D03*
X540695Y217874D03*
X534277Y224930D03*
X538613Y227882D03*
X537051Y211959D03*
X538613Y238119D03*
X534277Y230441D03*
Y235560D03*
X538613Y233000D03*
X539217Y245270D03*
X543780Y294168D03*
X541808Y289743D03*
X544628Y291633D03*
Y289133D03*
X542983Y334531D03*
X533211Y350838D03*
X533543Y404130D03*
X530729Y398634D03*
X543170Y434737D03*
X534455Y428561D03*
X531753Y453232D03*
X540616Y463486D03*
X538067Y592652D03*
X542071Y593089D03*
X535855Y612290D03*
X539657Y607658D03*
X534362Y601375D03*
X535855Y609749D03*
X532082Y604900D03*
X534962Y670960D03*
Y665960D03*
Y668460D03*
X532462D03*
Y665960D03*
Y670960D03*
Y673460D03*
Y663460D03*
X534962D03*
Y673460D03*
Y675960D03*
X532462D03*
X531921Y1167366D03*
X543947Y1516120D03*
Y1512220D03*
X543672Y1519845D03*
X540810Y1521436D03*
X533317Y1511953D03*
Y1514453D03*
Y1516953D03*
X531495Y1519250D03*
X537770Y1519845D03*
X537647Y1516120D03*
Y1512220D03*
X534002Y1521436D03*
X540797Y1516120D03*
Y1512220D03*
X543719Y1549295D03*
Y1546795D03*
X541219D03*
Y1549295D03*
X538719D03*
Y1546795D03*
X531339Y1546481D03*
X553620Y31048D03*
X549919D03*
X554984Y45312D03*
X553651Y48842D03*
X546350Y39562D03*
X550972Y42902D03*
X561721Y41024D03*
X556351Y41538D03*
X548610Y48082D03*
X547821Y79372D03*
X551721D03*
X555176Y71436D03*
X558576D03*
X553780Y121240D03*
Y124640D03*
X559484Y156667D03*
X553757Y160075D03*
X547196Y190256D03*
X550196D03*
X554196D03*
X553578Y193541D03*
X547196Y199256D03*
X550553Y200304D03*
Y197778D03*
X548963Y218441D03*
X549248Y237652D03*
Y230441D03*
X555567Y236970D03*
X549248Y234152D03*
X559774Y243176D03*
X557243Y294693D03*
X561808Y300492D03*
X562030Y372872D03*
X551044Y373085D03*
X562208Y383668D03*
Y404717D03*
X550573Y399586D03*
Y403586D03*
X562208Y397599D03*
X550573Y414274D03*
X549854Y406298D03*
X547529Y425411D03*
X551591Y443665D03*
X552510Y446490D03*
X547751Y472678D03*
X550925Y475178D03*
X553360Y477822D03*
X555727Y479968D03*
X558379Y482096D03*
X549957Y658478D03*
Y661478D03*
X558690Y1226149D03*
X558876Y1454905D03*
Y1458305D03*
X546253Y1454107D03*
Y1457507D03*
X555348Y1483590D03*
Y1480190D03*
Y1501990D03*
Y1505390D03*
X548197Y1514641D03*
X550471Y1513584D03*
Y1511031D03*
X548197Y1512088D03*
X554766Y1523331D03*
Y1526731D03*
X550939Y1536646D03*
X559215Y1530596D03*
X546219Y1549295D03*
Y1541795D03*
Y1546795D03*
Y1544295D03*
X548719Y1549295D03*
Y1546795D03*
Y1541795D03*
Y1544295D03*
X551219D03*
Y1541795D03*
X549674Y1538890D03*
X558089Y1541795D03*
Y1544295D03*
Y1546795D03*
Y1549295D03*
X555589Y1541795D03*
Y1549295D03*
Y1546795D03*
Y1544295D03*
X549759Y1551844D03*
X552177Y1551099D03*
X554682Y1551844D03*
X552177Y1548199D03*
X565185Y47982D03*
X575331Y47672D03*
X573191Y42912D03*
X570209Y47982D03*
X566771Y41133D03*
X564794Y58911D03*
X567997Y58992D03*
X573763Y58688D03*
X562331Y48438D03*
X570860Y121310D03*
Y124710D03*
X563951Y153640D03*
Y148640D03*
Y157494D03*
X572003Y164356D03*
Y169415D03*
X568804Y221926D03*
X571427Y217771D03*
X569004Y225496D03*
X568736Y235821D03*
X565093Y242640D03*
X570823Y294893D03*
X572447Y299470D03*
X569893Y300293D03*
X571063Y314669D03*
X566148Y324502D03*
X567773Y316153D03*
X575913Y413287D03*
X570863Y410728D03*
X572121Y437038D03*
X564407Y431638D03*
X568709Y434227D03*
X563763Y486350D03*
X567297Y487551D03*
X560890Y484664D03*
X569923Y490726D03*
X561346Y1228547D03*
X564669Y1238907D03*
X564283Y1231192D03*
X565537Y1235456D03*
X574200Y1229900D03*
X567127Y1249536D03*
X570775Y1263008D03*
X564986Y1462595D03*
X571686Y1452895D03*
X561586Y1462595D03*
X568286Y1452895D03*
X560589Y1541795D03*
Y1544295D03*
Y1546795D03*
Y1549295D03*
X563089Y1541795D03*
Y1549295D03*
Y1546795D03*
Y1544295D03*
X567214Y1544299D03*
X591938Y46308D03*
X576478Y58563D03*
X591070Y60201D03*
X586953Y63441D03*
X583685Y70678D03*
X586390Y69291D03*
X579561Y73090D03*
X585000Y82500D03*
X584752Y86248D03*
X590501Y86909D03*
X578454Y88926D03*
X586394Y95948D03*
X591811Y97421D03*
X580485Y133056D03*
Y130530D03*
X583485D03*
Y133056D03*
X589203Y164356D03*
X581203D03*
X589203Y169415D03*
X585685Y174975D03*
X581203Y169415D03*
X575425Y189835D03*
X582124Y194150D03*
X588244Y208991D03*
X575440Y200785D03*
X582002Y197481D03*
X582766Y225496D03*
Y221421D03*
X588554Y217277D03*
Y225277D03*
X580343Y217771D03*
X588215Y214079D03*
X588968Y240112D03*
X582816Y228696D03*
X581099Y263680D03*
X586157Y366827D03*
X585585Y372052D03*
X577482Y383668D03*
X581985Y387227D03*
Y376427D03*
X587710Y399287D03*
X581985Y401158D03*
X587710Y404287D03*
X588723Y415846D03*
X588798Y435949D03*
X588723Y427949D03*
X588742Y431976D03*
X577845Y437151D03*
X587829Y445138D03*
X575345Y437151D03*
X580523Y435949D03*
X575075Y451263D03*
X582390Y464701D03*
X589507Y462559D03*
X583116Y476745D03*
X587500Y470308D03*
X587795Y479631D03*
X581335Y472100D03*
X581421Y813078D03*
X588500Y812093D03*
X584271Y1263988D03*
X588386Y1462595D03*
X585086Y1472295D03*
X581686D03*
X602837Y32910D03*
X603064Y48023D03*
X599284Y42481D03*
X597956Y48047D03*
X606585Y43529D03*
X601073Y60301D03*
X603350Y73642D03*
X599295Y100747D03*
X606183Y95873D03*
X597275Y94922D03*
X596068Y106798D03*
X591385Y109165D03*
X602328Y109062D03*
X597769Y153640D03*
Y148640D03*
X603344Y139131D03*
X598552Y159066D03*
X600161Y188776D03*
X593661D03*
X604293Y193185D03*
X597293Y193186D03*
X602294Y203786D03*
X598968Y238878D03*
X603526Y229995D03*
X597050Y281950D03*
X602223Y298035D03*
X603723Y289721D03*
X602223Y314145D03*
Y322200D03*
X598414Y372357D03*
X598208Y383668D03*
X599884Y412000D03*
X593758Y415850D03*
X603326Y429530D03*
X590326Y445015D03*
X592529Y461563D03*
X598496Y451421D03*
X597500Y483500D03*
X602833Y791746D03*
X590710Y804192D03*
X603743Y794963D03*
X595619Y806084D03*
X600337Y800649D03*
X596821Y802688D03*
X592572Y809088D03*
X596621Y1240366D03*
X595253Y1266668D03*
X596944Y1270115D03*
X595532Y1262668D03*
X605771Y1263098D03*
X598112Y1264365D03*
X594991Y1285582D03*
Y1289582D03*
X591786Y1462595D03*
X598486Y1452895D03*
X595086D03*
X613025Y42725D03*
X612608Y35961D03*
X618732Y39913D03*
X619563Y49193D03*
X615587Y45611D03*
X606263Y60301D03*
X616815Y60277D03*
X611579D03*
X615190Y74533D03*
X615772Y106645D03*
X618182Y100786D03*
X610009Y100748D03*
X614282Y95873D03*
X617420Y119640D03*
X619240Y123232D03*
X605853Y149640D03*
Y145640D03*
Y152140D03*
Y155131D03*
X618801Y165356D03*
Y175534D03*
Y170415D03*
X616357Y182229D03*
X608794Y203786D03*
X607868Y257562D03*
X618705Y285305D03*
X608773Y289721D03*
X609798Y298035D03*
X607273D03*
X606248Y289721D03*
X604748Y298035D03*
X609798Y314145D03*
X607273D03*
X604748D03*
X621585Y331358D03*
X609798Y322200D03*
X607273D03*
X604748D03*
X611118Y359462D03*
X613565Y350819D03*
X619035Y369542D03*
X613482Y383668D03*
X617985Y387227D03*
Y376427D03*
Y401728D03*
X606032Y418968D03*
X617985Y407346D03*
X617998Y415546D03*
X606811Y429528D03*
X611925Y437000D03*
X605769Y442593D03*
X615903Y493474D03*
X608886Y494400D03*
X618680Y511302D03*
X618957Y502306D03*
X616457D03*
X611896Y535178D03*
Y538178D03*
X607091Y528168D03*
X618645Y783582D03*
X609402Y788678D03*
X615571Y788448D03*
X608940Y1265991D03*
X610551Y1262988D03*
X618761Y1266988D03*
X615591Y1282038D03*
X618761Y1278668D03*
X606619Y1278302D03*
X610551Y1269888D03*
X616037Y1367166D03*
X608148Y1373890D03*
X616615Y1386232D03*
X616629Y1375082D03*
X618586Y1462595D03*
X615186D03*
X611886Y1472295D03*
X608486D03*
X613948Y1641600D03*
X624634Y48104D03*
X628410Y45381D03*
X624689Y58262D03*
X627881Y57120D03*
X622207Y60573D03*
X627496Y74977D03*
X626642Y71365D03*
X622156Y95948D03*
X626208Y100861D03*
X628885Y127057D03*
X630810Y122089D03*
X625532Y146982D03*
X625553Y152683D03*
X625755Y168917D03*
X626372Y193431D03*
X626824Y182080D03*
X620455Y219277D03*
Y228777D03*
X631505Y284355D03*
X626705Y285305D03*
X622705D03*
X626473Y305338D03*
X626388Y330536D03*
X631694Y341300D03*
X626555Y343929D03*
X624133Y346520D03*
X626596Y360196D03*
X636500Y360362D03*
X634105Y404652D03*
X635058Y399700D03*
X627925Y421966D03*
X631075Y429888D03*
X632281Y441904D03*
X622174Y438925D03*
X622197Y436116D03*
X622800Y461348D03*
X627880Y455310D03*
X620800Y474700D03*
X627364Y478823D03*
X632984Y471462D03*
X630758Y505874D03*
X633406Y497964D03*
X624381Y503765D03*
X631510Y510613D03*
X624718Y553428D03*
X634794Y590504D03*
X635567Y671774D03*
X631557Y773359D03*
X631741Y770318D03*
X633406Y1358576D03*
X634776Y1353739D03*
X630477Y1350109D03*
Y1353109D03*
X624795Y1373257D03*
X624976Y1378313D03*
X630195Y1384263D03*
X625195Y1383457D03*
X622352Y1393285D03*
X630523Y1392554D03*
X635849Y1393376D03*
X625286Y1452895D03*
X621886D03*
X629808Y1668863D03*
X633422Y1673488D03*
X631643Y1670946D03*
X635491Y1696845D03*
X635472Y1711808D03*
X644963Y29143D03*
X638490Y33340D03*
X642157Y44695D03*
X639876Y49193D03*
X651042Y41545D03*
X647987Y47606D03*
X646042Y41545D03*
X640653Y58274D03*
X640670Y74369D03*
X650846Y74074D03*
X647938Y83795D03*
X644202Y84604D03*
X642607Y94116D03*
X645752Y134988D03*
X643800Y166053D03*
X641111Y158300D03*
X641006Y161829D03*
X643800Y161862D03*
X640923Y169388D03*
X649871Y181942D03*
X641276Y187557D03*
X637804Y235371D03*
X640804D03*
X637804Y239371D03*
X640804D03*
X640084Y227113D03*
X637804Y243371D03*
X640804D03*
X642171Y311280D03*
X641013Y324459D03*
X640922Y360342D03*
X639000Y364862D03*
X642128Y363279D03*
X636579Y366941D03*
X642617Y389299D03*
X637314Y393680D03*
X640784Y395957D03*
X651279Y404458D03*
X637160Y405449D03*
X635243Y433518D03*
X637432Y428935D03*
X642406Y427614D03*
X639211Y433862D03*
Y438191D03*
X635449Y449797D03*
X639002Y449862D03*
X639500Y442362D03*
X639313Y452361D03*
X635690Y461441D03*
X648500Y453862D03*
X635640Y464257D03*
X644849Y495582D03*
X647576Y497964D03*
X643053Y502891D03*
X640076Y497964D03*
X635906D03*
X642310Y535773D03*
X649592Y540078D03*
X639757Y533440D03*
X636055Y528605D03*
X646151Y535227D03*
X648314Y571169D03*
X644414D03*
X638694Y590504D03*
X650258Y590316D03*
X646358D03*
X650228Y674761D03*
X638967Y671774D03*
X646446Y674643D03*
X640271Y763488D03*
X636551Y767900D03*
X642804Y766871D03*
X636247Y771179D03*
X635092Y1277102D03*
X634995Y1384457D03*
X638053Y1384491D03*
X647401Y1384160D03*
X645386Y1462595D03*
X641986D03*
X648686Y1452895D03*
X638686Y1472295D03*
X635286D03*
X639907Y1570443D03*
X639132Y1573127D03*
X645180Y1597800D03*
X645190Y1595050D03*
X649153Y1625726D03*
X649297Y1623185D03*
X640242Y1639951D03*
X647630Y1641522D03*
X643128Y1639803D03*
X642716Y1653939D03*
X637218Y1654131D03*
X644905Y1646491D03*
X639800Y1646650D03*
X643074Y1668505D03*
X647574D03*
X647460Y1662952D03*
X640846Y1665189D03*
X650158Y1687189D03*
X643041Y1682883D03*
X647500Y1674805D03*
X640600D03*
X643300D03*
X639391Y1700695D03*
X640690Y1703547D03*
X651143Y1706162D03*
X644975Y1725236D03*
X635210Y1718395D03*
X641825Y1730516D03*
X640865Y1719684D03*
X657921Y30864D03*
X654117Y29099D03*
X654582Y45448D03*
X660928Y60707D03*
X651014Y60820D03*
X656600Y60537D03*
X661601Y75562D03*
X656501Y69662D03*
X657166Y79131D03*
X656427Y75431D03*
X661588Y69662D03*
X658228Y88447D03*
X666200Y84862D03*
X654037Y93241D03*
Y96041D03*
X651950Y99890D03*
X658949Y139840D03*
X662881Y149912D03*
Y146912D03*
X654326Y174437D03*
X653700Y179962D03*
X659881Y208262D03*
Y205762D03*
Y210762D03*
X662781Y207862D03*
Y205362D03*
Y210362D03*
X663915Y234476D03*
X659918Y326503D03*
X658905Y341885D03*
X661019Y344831D03*
X663551Y346035D03*
X649500Y373500D03*
X652425Y385924D03*
X659095Y381020D03*
X649495Y385118D03*
X659354Y393938D03*
X653523Y399987D03*
X652954Y394284D03*
X661297Y409857D03*
X662016Y417897D03*
X652027Y415930D03*
X654273Y419251D03*
X662000Y433862D03*
X654248Y422500D03*
X657535Y422694D03*
X666000Y429844D03*
X651432Y433532D03*
X662000Y429844D03*
X652763Y427866D03*
X651384Y445252D03*
X661546Y444497D03*
X662000Y449862D03*
X654441Y449618D03*
X662000Y437844D03*
X657622Y437819D03*
X651853Y439518D03*
X653449Y458542D03*
X662570Y461547D03*
Y457755D03*
X662000Y473862D03*
X666000Y473844D03*
X651072Y465939D03*
X654000Y465824D03*
X654014Y473862D03*
X662000Y465862D03*
X651114Y473884D03*
X662000Y469862D03*
X653266Y479106D03*
X663374Y484295D03*
X652380Y482390D03*
X657520Y486330D03*
X649500Y490260D03*
X660215Y483109D03*
X658758Y497964D03*
X655917D03*
X661718Y498056D03*
X651406Y501178D03*
X650404Y496102D03*
X652576Y497964D03*
X659425Y521075D03*
X665689Y550294D03*
X649922Y545610D03*
X655967Y544375D03*
X658642Y573893D03*
X661718Y579932D03*
X653368Y581468D03*
X655572Y572603D03*
X656832Y577205D03*
X662992Y598660D03*
X658613Y599534D03*
X662628Y674761D03*
X660175Y679517D03*
X657428Y674761D03*
X663580Y731509D03*
X658947Y767300D03*
Y771100D03*
X662600Y1311502D03*
Y1308502D03*
X653376Y1365793D03*
X661719Y1363394D03*
X651973Y1363038D03*
X653149Y1372500D03*
X653101Y1369862D03*
X652651Y1375308D03*
X661813Y1370081D03*
X653117Y1378037D03*
X651877Y1391074D03*
X652086Y1452895D03*
X662086D03*
X663160Y1511734D03*
Y1516734D03*
Y1519234D03*
Y1521734D03*
X660660Y1519234D03*
X661710Y1514148D03*
X663160Y1524234D03*
X666092Y1553650D03*
X660953Y1539998D03*
X663133Y1543744D03*
Y1541244D03*
Y1538744D03*
X660953Y1542498D03*
X657430Y1555228D03*
X659532Y1546519D03*
X664246Y1561009D03*
X661731Y1561083D03*
X661156Y1626532D03*
X650966Y1618934D03*
X651870Y1612986D03*
X650753Y1615912D03*
X653542Y1649059D03*
X660058Y1648889D03*
X660389Y1654481D03*
X663431Y1645780D03*
X654712Y1653813D03*
X664315Y1654484D03*
X650074Y1668505D03*
X658648Y1664169D03*
X655683Y1664212D03*
X653154Y1683265D03*
X664159Y1674844D03*
X661528Y1674865D03*
X650200Y1674805D03*
X658491Y1688965D03*
X649464Y1691180D03*
X659837Y1698400D03*
X659557Y1714672D03*
X658759Y1707147D03*
X659028Y1710047D03*
X660930Y1730277D03*
X662120Y1720404D03*
X670613Y42464D03*
X674013D03*
X677476Y33317D03*
X680864Y38190D03*
X666506Y32750D03*
X674647Y38190D03*
X677305Y57947D03*
X665469Y58525D03*
X674036Y74522D03*
X675509Y88173D03*
X667941Y80142D03*
X677561Y118409D03*
X677738Y115428D03*
X665651Y147692D03*
X673011Y169021D03*
X679035Y204181D03*
X678226Y215771D03*
X674348Y218580D03*
X666552Y346115D03*
X677111Y345662D03*
X672111D03*
X674611D03*
X676800Y369362D03*
X672800D03*
X680800Y380280D03*
X672800Y382362D03*
X676000Y378100D03*
X667090Y385150D03*
X671500Y390862D03*
X679940Y400933D03*
X675500Y398862D03*
Y390862D03*
X670018Y418690D03*
X669929Y407999D03*
X666000Y433862D03*
Y425862D03*
X670000Y429864D03*
Y433844D03*
Y425894D03*
X666000Y437844D03*
X670000Y442362D03*
Y437844D03*
X666000Y442362D03*
X670000Y446362D03*
X679062Y455140D03*
X666000Y453844D03*
Y457862D03*
X670000Y453844D03*
X666000Y461862D03*
X670000Y469824D03*
Y477862D03*
X678000D03*
X670000Y482862D03*
X678000D03*
X681213Y495658D03*
X672699Y506907D03*
X664741Y506865D03*
X680488Y504784D03*
X665425Y537000D03*
X664454Y574896D03*
X665774Y571762D03*
X666192Y598660D03*
X679047Y678733D03*
X673287Y733156D03*
X674123Y736083D03*
X667101Y736071D03*
X672505Y766871D03*
X674552Y1342488D03*
Y1344988D03*
X665167Y1380836D03*
Y1376836D03*
X673671Y1431922D03*
X675272Y1434525D03*
X665486Y1452895D03*
X672856Y1484082D03*
Y1480682D03*
Y1497482D03*
Y1494082D03*
X678386Y1507965D03*
X677871Y1522079D03*
X678345Y1516994D03*
X677871Y1519579D03*
X673174Y1515806D03*
X675505Y1512606D03*
X678339Y1510960D03*
X677871Y1524579D03*
X678121Y1528516D03*
X665832Y1527425D03*
X672715Y1526626D03*
Y1530526D03*
X678350Y1567400D03*
X669524Y1560850D03*
X672163Y1560899D03*
X673729Y1556768D03*
X666978Y1560945D03*
X672810Y1571560D03*
X666610Y1571580D03*
X668133Y1625828D03*
X670839Y1620863D03*
X673960Y1633042D03*
X669648Y1640917D03*
X670803Y1654606D03*
X671068Y1650818D03*
X674908Y1644481D03*
X667971Y1654404D03*
X669178Y1646627D03*
X673548Y1669550D03*
X678117Y1662787D03*
X675497Y1687253D03*
X673359Y1674409D03*
X671001Y1696017D03*
X671798Y1704542D03*
X673113Y1716599D03*
X667701Y1705043D03*
X668058Y1720092D03*
X673113Y1727261D03*
X684611Y41857D03*
X682291Y46822D03*
X690476Y32684D03*
X692390Y46939D03*
X692466Y35950D03*
X687835Y37850D03*
X687345Y46940D03*
X687018Y58357D03*
X683369Y58157D03*
X692390Y72692D03*
X690028Y70142D03*
X687665Y73202D03*
X685781Y70022D03*
X680580Y79230D03*
X681054Y104668D03*
X686891Y115868D03*
X687000Y119500D03*
X685500Y124000D03*
X679316Y209861D03*
X680576Y207105D03*
X681333Y212326D03*
X679737Y217763D03*
X693621Y346169D03*
X680828Y363500D03*
X684800Y369362D03*
X680800D03*
X691484Y360643D03*
X691500Y382462D03*
X685200Y377820D03*
X690105Y401775D03*
X687500Y390680D03*
X684794Y402268D03*
X683500Y390862D03*
X679500D03*
X692996Y418358D03*
X694299Y413108D03*
X689269Y410420D03*
X687612Y471850D03*
X691572Y465214D03*
X684800Y477862D03*
X687472Y486994D03*
X684680Y485942D03*
X684800Y481862D03*
X680187Y491243D03*
X690452Y486984D03*
X687310Y500453D03*
X682915Y500568D03*
X683000Y521500D03*
X687310Y522141D03*
X694111Y537881D03*
X690718Y578913D03*
X694996Y575081D03*
X689574Y572866D03*
X681352Y681305D03*
X691417Y680382D03*
X685786Y680936D03*
X686509Y677440D03*
X688648Y767300D03*
Y771100D03*
X687961Y1314308D03*
Y1320308D03*
Y1323308D03*
Y1317308D03*
X684868Y1327117D03*
X682348D03*
Y1339617D03*
X683052Y1342548D03*
X684868Y1329617D03*
X682348D03*
X684868Y1332117D03*
X682348D03*
X684868Y1334617D03*
X682348D03*
X684868Y1337117D03*
Y1339617D03*
X682348Y1337117D03*
X683052Y1345048D03*
X681289Y1418291D03*
X683391Y1420531D03*
X685448Y1423137D03*
X691587Y1429515D03*
X689538Y1427467D03*
X684350Y1448911D03*
X692376Y1438326D03*
X691943Y1441626D03*
X687040Y1452300D03*
X684280Y1452260D03*
X684603Y1507851D03*
X681517Y1508034D03*
X687529Y1508173D03*
X690683Y1508058D03*
X693395D03*
X693532Y1510755D03*
X690820D03*
X687666Y1510870D03*
X687711Y1513612D03*
X690751Y1513750D03*
X693655Y1513818D03*
X693587Y1516470D03*
X690752Y1516516D03*
X683666Y1515189D03*
X680717Y1513292D03*
X684557Y1510685D03*
X681563Y1510708D03*
X693495Y1519305D03*
X679854Y1551492D03*
X679413Y1548843D03*
X680107Y1554330D03*
X681780Y1574280D03*
X684080Y1576500D03*
X686949Y1625144D03*
X689897Y1621781D03*
X692209Y1620037D03*
X691036Y1625508D03*
X686994Y1629077D03*
X693451Y1628733D03*
X686808Y1643500D03*
X685578Y1637479D03*
X683067Y1641758D03*
X686075Y1657082D03*
X679413Y1653251D03*
X685719Y1672391D03*
X685747Y1669303D03*
X693608Y1671081D03*
X685635Y1675310D03*
X691560Y1682047D03*
X693480Y1673940D03*
X692390Y1687594D03*
X705666Y48010D03*
X697678Y47132D03*
X697893Y35950D03*
X702481Y48327D03*
X698462Y60683D03*
X695220Y60455D03*
X704201Y72112D03*
X699476Y69982D03*
X701081Y72450D03*
X694752Y70212D03*
X696701Y72462D03*
X698711Y86035D03*
X696371Y78512D03*
X696728Y81552D03*
Y84052D03*
X706721Y100462D03*
X702721Y102162D03*
X701221Y104862D03*
X697721D03*
X695721Y102162D03*
X694221Y104862D03*
X699221Y102162D03*
X699398Y123668D03*
X704709Y125586D03*
X704771Y171188D03*
Y167788D03*
X703486Y345507D03*
X699813Y344798D03*
X706139Y345597D03*
X695500Y374362D03*
X699500D03*
X703500D03*
X707500D03*
X707943Y360643D03*
X707500Y368862D03*
X696391Y368617D03*
X703477Y369409D03*
X695500Y382362D03*
X700300Y382502D03*
X707500Y382362D03*
X700000Y386790D03*
X707500Y386862D03*
X703700Y386832D03*
X695500Y386862D03*
X699500Y390862D03*
X695500D03*
X707500D03*
X703500Y401290D03*
Y390862D03*
X708584Y404868D03*
X699431Y513344D03*
X703774Y513463D03*
X707664Y513375D03*
X703788Y521817D03*
X696020Y521844D03*
X699800Y521760D03*
X708500Y517362D03*
X708210Y537816D03*
X708500Y529862D03*
X704500D03*
X700790Y537732D03*
X704500Y537862D03*
X708500Y533862D03*
X696829Y533604D03*
X702657Y533695D03*
X697018Y537577D03*
X704500Y545862D03*
X696283Y546530D03*
X710429Y545752D03*
X708500Y555451D03*
X698996Y575081D03*
X704056D03*
X708056D03*
X704056Y583081D03*
X698996D03*
X702806Y613264D03*
X696928Y613207D03*
X706387Y621686D03*
X705158Y645357D03*
X703781Y641805D03*
X704965Y638767D03*
X707833Y655325D03*
X704549Y655238D03*
X701233Y655355D03*
X708418Y650389D03*
X694812Y680188D03*
X698756Y676388D03*
X694837Y676412D03*
X701386Y679683D03*
X703584Y676544D03*
X708012Y676836D03*
X705697Y679533D03*
X697571Y730453D03*
X704598Y732288D03*
X700205Y733211D03*
X702553Y735811D03*
X702206Y766871D03*
X697461Y1314008D03*
Y1320008D03*
Y1323008D03*
X702388Y1327127D03*
X699868D03*
X697461Y1317008D03*
X701771Y1342488D03*
X702388Y1337127D03*
Y1339627D03*
X699868Y1337127D03*
Y1339627D03*
X702388Y1329627D03*
X699868D03*
X702388Y1332127D03*
X699868D03*
X702388Y1334627D03*
X699868D03*
X701771Y1344988D03*
X705657Y1387027D03*
X701689Y1399545D03*
X697731Y1397513D03*
X706351Y1397588D03*
X705657Y1389568D03*
X695162Y1441350D03*
X696237Y1508149D03*
X699247Y1508062D03*
X699049Y1510892D03*
X696374Y1510846D03*
X696329Y1513818D03*
X696330Y1516584D03*
X699140Y1513772D03*
X707050Y1531700D03*
X709150Y1536250D03*
X703290Y1551700D03*
X707050Y1548400D03*
Y1541800D03*
X703290Y1545100D03*
X708500Y1560500D03*
X708994Y1568507D03*
X699500Y1559000D03*
X699610Y1568523D03*
Y1572523D03*
Y1576523D03*
X708600Y1572523D03*
X710420Y1585173D03*
X710550Y1576523D03*
X710080Y1581683D03*
X699610Y1584523D03*
X699500Y1596500D03*
Y1588500D03*
X709836Y1594721D03*
X710360Y1589296D03*
X699000Y1604500D03*
X699500Y1599500D03*
X709382Y1601210D03*
X699500Y1608500D03*
X709020Y1609101D03*
X699424Y1616627D03*
X695933Y1623460D03*
X709260Y1617903D03*
X701114Y1640345D03*
X702683Y1633715D03*
X703563Y1644116D03*
X702402Y1650469D03*
X700528Y1661468D03*
X697503Y1661331D03*
X703102Y1665554D03*
X714471Y46670D03*
X724621Y40062D03*
X719821Y45862D03*
X714322Y56286D03*
X721163Y58588D03*
X714096Y73686D03*
X712717Y68541D03*
X719416Y68738D03*
Y74036D03*
X725016Y86952D03*
X720016D03*
X715745Y86300D03*
X712725Y84714D03*
X712291Y106722D03*
X715934Y117488D03*
Y114588D03*
X712734Y117488D03*
Y114588D03*
X720434Y135088D03*
X717434D03*
X719934Y124488D03*
X723134D03*
X712341Y128093D03*
X710284Y169826D03*
X717021Y220862D03*
X714867Y344943D03*
X717712Y346103D03*
X715500Y374362D03*
X719500D03*
X723531Y368862D03*
X723500Y360862D03*
X711500Y374362D03*
X715500Y360862D03*
X719500Y368862D03*
X715500D03*
X711363Y369274D03*
X711500Y382362D03*
X719640Y386862D03*
X723632D03*
X711500D03*
X715500D03*
X722500Y383162D03*
X723500Y390862D03*
X719500D03*
X715500D03*
X711500D03*
X716500Y521862D03*
X711617Y513531D03*
X724500Y517362D03*
X716500D03*
X720400Y517440D03*
X720452Y513362D03*
X716716Y513368D03*
X720499Y533474D03*
X719841Y537348D03*
X712113Y537797D03*
X720500Y555862D03*
Y546211D03*
X712115Y541872D03*
X712409Y555413D03*
X710464Y557036D03*
X722201Y579306D03*
X723483Y574890D03*
X714583Y590792D03*
X716181Y585562D03*
X715037Y606428D03*
X716313Y610134D03*
X719710Y612831D03*
X720787Y627907D03*
X716721D03*
X713343Y633842D03*
X724000Y633906D03*
X725812Y654713D03*
X715371Y654726D03*
X711702Y646533D03*
X711295Y665117D03*
X718129Y666725D03*
X722129D03*
X712164Y676912D03*
X712120Y680287D03*
X717515Y679833D03*
X720563Y679886D03*
X720613Y677040D03*
X723814Y736782D03*
X718349Y767300D03*
Y771100D03*
X721339Y1314048D03*
X711839Y1314348D03*
X721339Y1323048D03*
Y1320048D03*
Y1317048D03*
X715828Y1327277D03*
X710488Y1327177D03*
X713008D03*
X711839Y1323348D03*
Y1320348D03*
Y1317348D03*
X713008Y1329877D03*
Y1332377D03*
Y1334877D03*
X715828Y1332877D03*
Y1330377D03*
X713008Y1337377D03*
Y1339877D03*
X715828Y1335377D03*
X710288Y1339677D03*
Y1337177D03*
X710221Y1342488D03*
X710288Y1334677D03*
Y1332177D03*
Y1329677D03*
X710221Y1344988D03*
X712419Y1398094D03*
X719861Y1400139D03*
X716373Y1398539D03*
X719111Y1397571D03*
X712419Y1400602D03*
X709430Y1394417D03*
X722877Y1390881D03*
X712099Y1416973D03*
X714599D03*
X717099D03*
X712099Y1414473D03*
X714599D03*
X717099D03*
X709599Y1416973D03*
Y1414473D03*
X717099Y1432773D03*
X712099D03*
X714599D03*
X717099Y1430273D03*
X712099D03*
X714599D03*
X709599Y1432773D03*
Y1427373D03*
Y1424873D03*
Y1430273D03*
Y1419873D03*
Y1422373D03*
X714259Y1447483D03*
X719471Y1467422D03*
X711671D03*
X714271D03*
X716871D03*
X720217Y1472287D03*
X717617D03*
X715017D03*
X720926Y1469814D03*
X718326D03*
X715726D03*
X713126D03*
X716067Y1474792D03*
X718667D03*
X721267D03*
X717358Y1477038D03*
X719958D03*
X714474Y1566333D03*
X724110Y1561825D03*
X714110Y1581475D03*
X714900Y1571273D03*
X721963Y1576932D03*
X719963Y1578932D03*
X721440Y1570963D03*
X719963Y1585790D03*
X721963Y1587790D03*
X723590Y1595323D03*
X718892Y1597152D03*
X714372Y1594679D03*
X723408Y1608740D03*
X720106Y1609542D03*
X717798Y1607335D03*
X713718Y1610235D03*
X717229Y1612376D03*
X718129Y1624330D03*
X722104Y1626253D03*
X715744Y1622842D03*
X722889Y1622491D03*
X711298Y1632534D03*
X718122Y1636332D03*
X718116Y1639129D03*
X713771Y1654927D03*
X722480Y1657616D03*
X719117Y1682722D03*
X723181Y1688825D03*
X740101Y41162D03*
X736621Y45262D03*
X733315Y40862D03*
X728721Y43562D03*
X726789Y60562D03*
X738590Y59868D03*
X730785Y58068D03*
X728285Y58135D03*
X724645Y58362D03*
X734769Y60757D03*
X725769Y69737D03*
X736864Y74943D03*
X731864D03*
X727200Y73210D03*
X729918Y90998D03*
X739824Y91052D03*
X734380Y80518D03*
X729380D03*
X736650Y102350D03*
X735771Y94988D03*
X730660Y108484D03*
X728734Y132088D03*
Y129288D03*
Y126388D03*
X735500Y143000D03*
X724147Y345291D03*
X729211Y346379D03*
X726431Y346384D03*
X738773Y346716D03*
X734463Y346712D03*
X735500Y368862D03*
X734166Y360782D03*
X739500Y368862D03*
X727564D03*
X731500Y360862D03*
X731406Y374331D03*
X731500Y368862D03*
Y386862D03*
X739553Y388270D03*
X735500Y386862D03*
X727500D03*
X735500Y390862D03*
X727500D03*
X735500Y399330D03*
X738672Y494444D03*
X728938Y517520D03*
X724500Y513362D03*
X732500D03*
X739185Y521394D03*
X728500Y521862D03*
X724500D03*
X728500Y513362D03*
X736609Y518426D03*
X728500Y529862D03*
X728576Y537476D03*
X736500Y537862D03*
X724336Y537527D03*
X724433Y530870D03*
X732500Y529862D03*
X736647Y529772D03*
X732580Y537193D03*
X724697Y535053D03*
X728652Y545862D03*
X728695Y550943D03*
X736670Y545864D03*
X740500Y545862D03*
X724684Y545864D03*
X724281Y553438D03*
X728714Y554190D03*
X732520Y545988D03*
X736528Y576480D03*
Y579615D03*
X727253Y610689D03*
X724246Y627939D03*
X736362Y636854D03*
X730770Y644218D03*
X733382Y633574D03*
X729489Y666547D03*
X734442Y675695D03*
X730837Y678940D03*
X738486Y679139D03*
X724931Y678364D03*
X735316Y736742D03*
X725712Y734135D03*
X729391D03*
X727576Y736756D03*
X727448Y766871D03*
X735739Y1314048D03*
Y1320048D03*
Y1317048D03*
X724788Y1327277D03*
X727501Y1327230D03*
X730021D03*
X735739Y1323048D03*
X727401Y1332430D03*
Y1329930D03*
Y1334930D03*
X724788Y1330377D03*
Y1332877D03*
X727401Y1339930D03*
Y1337430D03*
X724788Y1335377D03*
X730021Y1337230D03*
Y1339730D03*
Y1334730D03*
Y1329730D03*
Y1332230D03*
X730795Y1342444D03*
Y1344944D03*
X738439Y1387127D03*
X728198Y1388026D03*
Y1385126D03*
X738439Y1389668D03*
X727737Y1390881D03*
X725307D03*
X734767Y1396986D03*
Y1394086D03*
X732567Y1392586D03*
X732667Y1395586D03*
X730501Y1397216D03*
Y1394316D03*
X734767Y1391186D03*
X735418Y1426122D03*
Y1423122D03*
Y1420122D03*
X732418Y1426122D03*
Y1423122D03*
Y1420122D03*
X735453Y1525368D03*
X737551Y1524008D03*
X727325Y1563400D03*
X727571Y1558353D03*
X736782Y1555496D03*
X730782D03*
X733782D03*
X727571Y1555353D03*
X733782Y1567496D03*
X736782D03*
X730782D03*
X733782Y1558496D03*
Y1561496D03*
X736782Y1558496D03*
Y1561496D03*
X733782Y1564496D03*
X736782D03*
X730782Y1558496D03*
Y1561496D03*
Y1564496D03*
X726475Y1571293D03*
X723963Y1578932D03*
X730782Y1570496D03*
X736782D03*
X733782D03*
X733380Y1577231D03*
X727780Y1582361D03*
Y1577231D03*
X723963Y1585790D03*
X726550Y1599358D03*
X733380Y1587491D03*
X727780D03*
X736998Y1597463D03*
X730998D03*
X733998D03*
X736998Y1594463D03*
X730998D03*
X733998D03*
X736998Y1600463D03*
X730998D03*
X733998D03*
Y1603663D03*
X736998D03*
X733998Y1606663D03*
X736998D03*
X730998Y1603663D03*
Y1606663D03*
X730647Y1623629D03*
X727320Y1623698D03*
X736723Y1623938D03*
X731119Y1647997D03*
X735642Y1648537D03*
X730347Y1682902D03*
X725638Y1682890D03*
X732852Y1695701D03*
X738030Y1723903D03*
Y1726903D03*
X738108Y1721157D03*
X738075Y1718082D03*
X746101Y46262D03*
X745901Y40362D03*
X749478Y59902D03*
X746588Y59754D03*
X740817Y58503D03*
X747488Y71429D03*
X740537Y73564D03*
X750034Y89988D03*
X750701Y106642D03*
X754783Y96553D03*
X750034Y92888D03*
X741309Y108742D03*
X748034Y116288D03*
X748261Y112552D03*
X743050Y139182D03*
X751221Y137864D03*
X743547Y147703D03*
X748915Y158608D03*
X745031Y161463D03*
X748125Y170618D03*
X751575Y184252D03*
X746522Y308804D03*
X750717Y319907D03*
X747594Y319106D03*
X747696Y332772D03*
X751337Y343849D03*
X748752Y343582D03*
X745132Y344964D03*
X752926Y361021D03*
X747500Y368862D03*
X751500D03*
X743500D03*
Y374362D03*
X749389Y360816D03*
X755135Y368907D03*
X754813Y374362D03*
X739500D03*
X747500D03*
X747454Y386817D03*
X751652Y386862D03*
X743500Y386962D03*
X739652Y390862D03*
X743500D03*
X747500D03*
X751500D03*
X747629Y406163D03*
X753252Y495234D03*
X748381Y495244D03*
X752652Y504106D03*
X752500Y517362D03*
X744500Y513362D03*
X748661Y517060D03*
X740500Y513362D03*
X752500D03*
X748500D03*
X753951Y521801D03*
X748077Y521789D03*
X740500Y537862D03*
X752965Y537678D03*
X748143Y530269D03*
X744916Y530268D03*
X752500Y529862D03*
X748000Y537862D03*
X741851Y553544D03*
X745645Y545880D03*
X752500Y545862D03*
X745091Y553563D03*
X748500Y545862D03*
X752195Y554761D03*
X748482Y557085D03*
X751731Y557714D03*
X739128Y566639D03*
X741624Y580707D03*
X741200Y577470D03*
X749131Y570340D03*
X750062Y655415D03*
X753309Y655515D03*
X750074Y648739D03*
X753483Y648749D03*
X751885Y666724D03*
X753231Y678679D03*
X742579Y676093D03*
X746665Y678879D03*
X750168Y675833D03*
X748049Y767300D03*
Y771100D03*
X745439Y1314048D03*
X748188Y1327317D03*
X745491Y1327124D03*
X742971D03*
X745439Y1323048D03*
Y1320048D03*
Y1317048D03*
X745691Y1332424D03*
Y1329924D03*
Y1334924D03*
X748188Y1333017D03*
Y1330517D03*
X745691Y1339924D03*
Y1337424D03*
X748188Y1335517D03*
X742971Y1337124D03*
Y1339624D03*
Y1334624D03*
Y1329624D03*
Y1332124D03*
X739501Y1342244D03*
Y1344744D03*
X739932Y1398042D03*
X745201Y1398194D03*
X752643Y1400239D03*
X749155Y1398639D03*
X751893Y1397671D03*
X745201Y1400702D03*
X742212Y1394517D03*
X739611Y1458211D03*
X750418Y1468893D03*
X750968Y1482349D03*
X746111Y1504125D03*
X745984Y1501052D03*
X745001Y1516471D03*
X750205Y1512307D03*
X750155Y1516451D03*
X739900Y1523152D03*
X748782Y1555496D03*
X742782D03*
X739782D03*
X745782D03*
X739782Y1558496D03*
Y1561496D03*
Y1564496D03*
X745782Y1558496D03*
X742782D03*
X745782Y1561496D03*
X742782D03*
X745782Y1564496D03*
X742782D03*
X739782Y1567496D03*
X742782D03*
X748782Y1558496D03*
Y1561496D03*
Y1564496D03*
X747110Y1575863D03*
X747150Y1583247D03*
X747110Y1579863D03*
X739782Y1570496D03*
X742782D03*
X738880Y1582361D03*
Y1577231D03*
X747160Y1587773D03*
X749167Y1591967D03*
X754635Y1592571D03*
X738880Y1587491D03*
X745998Y1597463D03*
X742998D03*
X745998Y1594463D03*
X742998D03*
X739998Y1597463D03*
Y1594463D03*
X745998Y1600463D03*
X742998D03*
X739998D03*
X745998Y1603663D03*
X742998D03*
X739998D03*
X745998Y1606663D03*
X742998D03*
X739998D03*
X743664Y1626945D03*
X753770Y1636083D03*
X751521Y1656008D03*
X739880Y1648046D03*
X742792Y1647982D03*
X745075Y1665675D03*
X754030Y1669256D03*
X748254Y1674771D03*
X752187Y1682994D03*
X748413Y1679367D03*
X746766Y1696036D03*
X740328Y1698376D03*
X747289Y1693063D03*
X752187Y1691058D03*
X741030Y1723903D03*
Y1726903D03*
X741160Y1721150D03*
X741025Y1718195D03*
X757721Y62132D03*
X760221D03*
X762721D03*
X755621Y51602D03*
X758621D03*
X757721Y64632D03*
X760221D03*
X763221Y65132D03*
X757188Y91829D03*
X757694Y98108D03*
Y100653D03*
X760193Y106500D03*
X757576Y112575D03*
X756000Y145500D03*
X754825Y163397D03*
X756303Y158417D03*
X765950Y190669D03*
X765000Y186500D03*
X754737Y185469D03*
X757629Y239295D03*
X761067Y280355D03*
X763384Y279231D03*
X763508Y284404D03*
X763463Y281840D03*
X760614Y284100D03*
X754759Y281007D03*
X758510Y298620D03*
X760462Y295662D03*
X757937Y303908D03*
X768130Y335363D03*
X758245Y343763D03*
X764331Y374401D03*
X756347Y360851D03*
X764983Y368052D03*
X766304Y372862D03*
X768304Y374362D03*
X759652D03*
X755500Y386862D03*
X759500D03*
X763500D03*
X767500D03*
X759500Y390791D03*
X755500Y390862D03*
X759500Y402098D03*
X767500Y401470D03*
Y390862D03*
X763500D03*
X757258Y408763D03*
X765975Y414414D03*
X769648Y430511D03*
X770530Y423460D03*
X768301Y438223D03*
X770918Y442510D03*
X770042Y446829D03*
X770590Y470940D03*
X762800Y493654D03*
X764500Y521862D03*
X756500Y513340D03*
X764500D03*
X756800Y517050D03*
X760500Y521189D03*
X764600Y517022D03*
X756186Y529888D03*
X764500Y529862D03*
X760500Y529845D03*
X757860Y537859D03*
X760660Y537862D03*
X756500Y545862D03*
X764500D03*
X759568Y545867D03*
X768340Y563678D03*
X765809Y563410D03*
X758103Y556873D03*
X765041Y565867D03*
X762530Y565340D03*
X757745Y655353D03*
X755765Y666904D03*
X762656Y667835D03*
X756936Y676319D03*
X768565Y677573D03*
X760529Y677715D03*
X764401Y676968D03*
X762396Y732915D03*
X754532Y735859D03*
X760425Y736233D03*
X764568Y736183D03*
X761608Y766871D03*
X759839Y1313948D03*
Y1319948D03*
X760204Y1327314D03*
X762754D03*
X759839Y1316948D03*
X757638Y1327317D03*
X759839Y1322948D03*
X760204Y1332514D03*
Y1330014D03*
Y1335014D03*
X757638Y1333017D03*
Y1330517D03*
X760194Y1340024D03*
Y1337524D03*
X757638Y1335517D03*
X762844Y1337324D03*
Y1339824D03*
X762754Y1334814D03*
Y1329814D03*
Y1332314D03*
X762261Y1343424D03*
Y1345924D03*
X760980Y1385146D03*
Y1388046D03*
X758089Y1390981D03*
X760519D03*
X755659D03*
X767549Y1391286D03*
Y1397086D03*
Y1394186D03*
X765349Y1392686D03*
X765449Y1395686D03*
X763283Y1397316D03*
Y1394416D03*
X758163Y1490789D03*
Y1498663D03*
Y1494726D03*
Y1502600D03*
Y1506538D03*
Y1522286D03*
Y1510474D03*
X757826Y1514412D03*
X758056Y1518349D03*
X760650Y1570633D03*
Y1578733D03*
Y1574733D03*
X757610Y1576023D03*
X766212Y1568043D03*
X757650Y1580023D03*
X766950Y1581233D03*
X757610Y1584023D03*
X767750Y1584108D03*
X757610Y1589023D03*
X760650Y1587733D03*
X760521Y1595500D03*
X759723Y1626161D03*
X755261Y1628208D03*
X758030Y1668583D03*
X754839Y1678069D03*
X768463Y1687769D03*
X757161Y1696424D03*
X768733Y1694485D03*
X781441Y118637D03*
X782819Y149471D03*
X780159Y146961D03*
X772270Y153728D03*
X771427Y158026D03*
X782712Y260466D03*
X777408Y256648D03*
X777421Y277962D03*
X779884Y281705D03*
X769790Y296231D03*
X777468Y296315D03*
X769861Y302462D03*
X782641Y310888D03*
X779681Y313053D03*
X770190Y312563D03*
X779121Y303410D03*
Y308755D03*
X780046Y328268D03*
X772119Y333537D03*
X771964Y339716D03*
X781812Y341863D03*
X779118Y341749D03*
X769000Y364000D03*
X776500Y371000D03*
X784500Y367500D03*
X771512Y386862D03*
X775388Y390862D03*
X770000Y380787D03*
X777612Y403505D03*
X771512Y390862D03*
X780295Y403538D03*
X784498Y396353D03*
X782700Y415284D03*
X773181Y415197D03*
X773233Y409154D03*
X783256Y409340D03*
X770159Y410257D03*
X783770Y422454D03*
X772610Y434690D03*
X780877Y427344D03*
X771718Y426804D03*
X780877Y423344D03*
X783821Y431534D03*
X780877Y431368D03*
X772677Y451374D03*
X780577Y435564D03*
X780877Y443344D03*
Y447344D03*
X780977Y459524D03*
X780877Y463344D03*
Y455344D03*
X783377Y451344D03*
X780877Y475344D03*
X780759Y479344D03*
X783877Y475344D03*
X772427D03*
X783759Y479344D03*
X780877Y483344D03*
X772390Y491047D03*
X772427Y487344D03*
X783358Y495344D03*
X783351Y499221D03*
X771039Y511292D03*
X775100Y502504D03*
X772427Y495344D03*
X777166Y504477D03*
X774998Y511306D03*
X774964Y514204D03*
X772100Y532700D03*
X777200Y530250D03*
X772000Y529862D03*
X781699Y536425D03*
X772000Y545862D03*
X776345Y545733D03*
X777754Y558740D03*
X773463Y563455D03*
X778747Y572269D03*
X779448Y632498D03*
X772459Y655290D03*
X771553Y677963D03*
X777750Y767300D03*
Y771100D03*
X783280Y1296009D03*
X778030Y1296259D03*
X780530D03*
X783280Y1298509D03*
X785520Y1292160D03*
X769439Y1313948D03*
X783280Y1301009D03*
X769439Y1319948D03*
Y1322948D03*
Y1316948D03*
X770881Y1343344D03*
X782115Y1334173D03*
X770881Y1345844D03*
X774646Y1516441D03*
X772906Y1522901D03*
X774616Y1520361D03*
X778850Y1556133D03*
X781850D03*
Y1559133D03*
Y1562133D03*
Y1565133D03*
X778850Y1559133D03*
Y1562133D03*
Y1565133D03*
X771450Y1577333D03*
X781850Y1568133D03*
Y1571133D03*
X778850Y1568133D03*
Y1571133D03*
X779977Y1577233D03*
Y1582363D03*
X771550Y1587133D03*
X774420Y1587284D03*
X779977Y1587493D03*
X779550Y1594533D03*
X782550D03*
X776550Y1597533D03*
Y1594533D03*
X779550Y1597533D03*
X782550D03*
Y1600533D03*
X776550D03*
X779550D03*
Y1606533D03*
X782550Y1603533D03*
X779550D03*
X776550Y1606533D03*
Y1603533D03*
X782550Y1606533D03*
X785181Y120947D03*
X792681D03*
X790181D03*
X787681D03*
X783941Y118637D03*
X786441D03*
X788941D03*
X785529Y270459D03*
X798205Y279146D03*
X794058Y301569D03*
X793221Y296062D03*
X793897Y309026D03*
X793855Y305316D03*
X798493Y301377D03*
X795921Y312662D03*
X787500Y328362D03*
X799226Y328467D03*
X791726D03*
X783726D03*
X785674Y342279D03*
X788806Y342236D03*
X791403Y342262D03*
X793951Y342224D03*
X795685Y357498D03*
X792302Y357537D03*
X798312Y372571D03*
X796021Y395924D03*
X797000Y404000D03*
X786571Y403455D03*
X785923Y419194D03*
X787000Y407500D03*
X796283Y415344D03*
Y419344D03*
X786877Y427344D03*
X796283Y423344D03*
Y431344D03*
X783877Y427344D03*
X796283D03*
X786999Y435476D03*
X797252Y443344D03*
X786877D03*
X796333Y435344D03*
X786203Y447054D03*
X783877Y435444D03*
X797197Y447344D03*
X786887Y451344D03*
X797252D03*
X797322Y463344D03*
X786825Y459518D03*
X786755Y455524D03*
X797252Y455344D03*
X797326Y479344D03*
X786877Y471344D03*
X797463Y476159D03*
X786877Y475344D03*
X786440Y480769D03*
X797405Y487464D03*
X797326Y483344D03*
X787092Y490681D03*
X786358Y483566D03*
X786102Y507536D03*
X787446Y495344D03*
X787279Y499238D03*
X790503Y501826D03*
X799450Y511801D03*
X800674Y504130D03*
X789125Y529425D03*
X800500Y540500D03*
X794357Y559996D03*
X785919Y559660D03*
X792782Y565323D03*
X791723Y574946D03*
X799742Y628983D03*
X789135Y617097D03*
X783653Y631671D03*
X787591Y631785D03*
X788537Y734410D03*
X793131Y734310D03*
X784543Y734510D03*
X791308Y766871D03*
X789020Y1292160D03*
X792520D03*
X796020D03*
X794273Y1354600D03*
Y1357600D03*
Y1364500D03*
Y1361500D03*
X784669Y1462178D03*
X796955Y1487468D03*
X788710Y1488821D03*
X784277Y1504569D03*
Y1500632D03*
Y1508506D03*
Y1512443D03*
X791867Y1524254D03*
X784850Y1556133D03*
X796850D03*
X790850D03*
X787850D03*
X793850D03*
X784850Y1559133D03*
Y1562133D03*
Y1565133D03*
X796850Y1559133D03*
Y1562133D03*
Y1565133D03*
X787850Y1559133D03*
Y1562133D03*
Y1565133D03*
X793850Y1559133D03*
X790850D03*
X793850Y1562133D03*
X790850D03*
X793850Y1565133D03*
X790850D03*
X799150Y1581379D03*
X784850Y1568133D03*
Y1571133D03*
X787850Y1568133D03*
Y1571133D03*
X793850Y1568133D03*
X790850D03*
X793850Y1571133D03*
X790850D03*
X791077Y1577233D03*
X785577D03*
X791077Y1582363D03*
X796650Y1583347D03*
X785577Y1587493D03*
X791077D03*
X791550Y1597533D03*
X785550Y1594533D03*
X788550D03*
X791550D03*
X785550Y1597533D03*
X788550D03*
X785550Y1600533D03*
X788550D03*
X791550D03*
Y1606533D03*
X788550D03*
X785550D03*
X791550Y1603533D03*
X788550D03*
X785550D03*
X803302Y265848D03*
X812867Y278860D03*
X810139Y274098D03*
X804330Y281380D03*
X801341Y279141D03*
X799935Y286823D03*
X799113Y297733D03*
X803893Y301969D03*
X805871Y304812D03*
X806461Y310610D03*
X808617Y330102D03*
X806117D03*
X812070Y341590D03*
X803410Y341572D03*
X803500Y366000D03*
X802660Y381020D03*
X802462Y387756D03*
X807564Y403805D03*
X811224Y395974D03*
X803412Y403978D03*
X813148Y403908D03*
X805425Y395502D03*
X813252Y427060D03*
X802270Y435372D03*
X802459Y443218D03*
X813208Y435344D03*
X812895Y449802D03*
X813114Y443344D03*
X802533Y449802D03*
X812983Y463578D03*
X813114Y459344D03*
X801552Y463318D03*
X802752Y459344D03*
X813114Y455344D03*
X812983Y471344D03*
Y476159D03*
X801874Y471344D03*
X802752Y480159D03*
X812983D03*
X813000Y484862D03*
X801762Y495344D03*
X802752Y487344D03*
X801753Y491344D03*
X813187Y498362D03*
X813114Y495344D03*
X802250Y500504D03*
X801857Y508031D03*
X805940Y534500D03*
X805341Y578059D03*
X805199Y620347D03*
X804863Y626789D03*
X805150Y623843D03*
X807451Y767299D03*
X807127Y770958D03*
X799280Y1296009D03*
X802030Y1296259D03*
X804530D03*
X807601Y1299241D03*
X799280Y1298509D03*
Y1301009D03*
X801614Y1339062D03*
X811771Y1355488D03*
X799071Y1350088D03*
X807866Y1369177D03*
X805366Y1367093D03*
X802866D03*
X807866Y1366677D03*
X808714Y1490376D03*
Y1487376D03*
Y1506784D03*
Y1519784D03*
Y1509784D03*
Y1516784D03*
X802150Y1570633D03*
Y1578633D03*
Y1582833D03*
X810150Y1574633D03*
X813150Y1579410D03*
Y1570633D03*
X810050Y1584033D03*
X802150Y1594633D03*
X810850Y1587733D03*
X810150Y1590633D03*
X813049D03*
X802700Y1587183D03*
X810150Y1602633D03*
Y1598633D03*
X802150Y1606633D03*
X819321Y56961D03*
X823115Y115223D03*
X820901Y147112D03*
X814571Y145952D03*
X814532Y139851D03*
X822635Y165468D03*
X825332Y166862D03*
X813676Y266065D03*
X823067Y273225D03*
X823038Y276301D03*
X819828Y288063D03*
X827621Y302962D03*
X822689Y305148D03*
X826915Y311842D03*
X822252Y309973D03*
X816232Y341584D03*
X818677Y356405D03*
X826765Y356334D03*
X817780Y366905D03*
X823778Y376378D03*
X818157Y381020D03*
X816991Y395337D03*
X820018Y403710D03*
X816281Y403814D03*
X828286Y401567D03*
X824653Y405347D03*
X817497Y415344D03*
X827341Y419344D03*
X817497D03*
X827341Y415344D03*
X817497Y427060D03*
X826474Y431344D03*
X816239Y435344D03*
X817497Y431060D03*
X826474Y435344D03*
X816117Y443552D03*
X816236Y439279D03*
X816109Y449802D03*
X822878Y446425D03*
X816109Y455344D03*
X816000Y463578D03*
X816170Y458524D03*
X826912Y475989D03*
X816109Y471344D03*
X816409Y467568D03*
X817393Y491594D03*
X830212Y483892D03*
X826472Y483896D03*
X827000Y489055D03*
X817996Y496219D03*
X828259Y501027D03*
X824380Y517595D03*
X827237Y550771D03*
X817849Y550871D03*
X820620Y550846D03*
X824366Y552444D03*
X827832Y554269D03*
X814489Y558082D03*
X825200Y580300D03*
X815287Y580401D03*
X820617Y641273D03*
X816732Y629198D03*
X815753Y644219D03*
X817900Y649012D03*
X822579Y760169D03*
X822218Y756979D03*
X822794Y767511D03*
X825390Y770020D03*
X822794Y777511D03*
X816550Y766871D03*
X822625Y763529D03*
X822794Y772511D03*
Y775011D03*
X825061Y764884D03*
X822864Y783262D03*
X822772Y788359D03*
X822790Y785838D03*
X822883Y780334D03*
X822982Y791245D03*
X822555Y807409D03*
X822794Y797511D03*
Y800011D03*
Y795011D03*
X822494Y802941D03*
X823927Y907676D03*
X823958Y936140D03*
X826958D03*
X823958Y939140D03*
X826958D03*
X827088Y933387D03*
X824036Y933394D03*
X826953Y930432D03*
X824003Y930319D03*
X828109Y1234504D03*
X826728Y1246315D03*
X824444Y1249420D03*
X828246Y1266501D03*
X824714Y1490376D03*
Y1487376D03*
X816690Y1490376D03*
Y1487376D03*
X824714Y1500376D03*
Y1497376D03*
Y1506784D03*
X816717Y1500388D03*
X816729Y1497364D03*
X816693Y1506784D03*
X824714Y1519784D03*
Y1509784D03*
Y1516784D03*
X816706Y1519820D03*
X816693Y1516784D03*
X816694Y1509796D03*
X824714Y1529784D03*
Y1526784D03*
X816714Y1529784D03*
Y1526784D03*
X823850Y1556133D03*
X820850D03*
X826850D03*
X820850Y1565133D03*
Y1562133D03*
Y1559133D03*
X826850Y1565133D03*
X823850D03*
X826850Y1562133D03*
Y1559133D03*
X823850Y1562133D03*
Y1559133D03*
X820850Y1571133D03*
Y1568133D03*
X826850Y1571133D03*
Y1568133D03*
X823850Y1571133D03*
Y1568133D03*
X821977Y1577233D03*
X827577D03*
X821977Y1582363D03*
X816150Y1587284D03*
X821977Y1587493D03*
X827577D03*
X821550Y1594533D03*
X827550Y1597533D03*
Y1594533D03*
X824550Y1597533D03*
Y1594533D03*
X821550Y1597533D03*
Y1600533D03*
X827550D03*
X824550D03*
X815550Y1606533D03*
X818550D03*
X821550Y1603533D03*
X818550D03*
X827550Y1606533D03*
X824550D03*
X821550D03*
X827550Y1603533D03*
X824550D03*
X842320Y11689D03*
Y8289D03*
X828601Y61752D03*
X836780Y68008D03*
X839899Y87248D03*
X841585Y94181D03*
X837251Y93221D03*
X839361Y114862D03*
X835115Y115223D03*
X845221Y135862D03*
Y129362D03*
X829115Y147123D03*
X838221Y163862D03*
X835221D03*
X842721Y181362D03*
X837161Y213207D03*
X844527Y204968D03*
X838821Y206872D03*
X837161Y218212D03*
X837501Y229642D03*
X836305Y268624D03*
X836181Y275686D03*
X830418Y311865D03*
X837754Y335345D03*
X829800Y331013D03*
X840457Y335368D03*
X842257Y350376D03*
X829344Y356224D03*
X833219Y375992D03*
X840357Y382813D03*
X833097Y393000D03*
X837912Y401545D03*
X834426Y401504D03*
X833000Y409500D03*
X838500D03*
X837847Y405347D03*
X833807Y423257D03*
X841809Y423219D03*
X838000Y423362D03*
X829106Y439279D03*
X842825Y448739D03*
X828979Y449802D03*
X834106Y439279D03*
X828714Y443552D03*
X833800Y444700D03*
X828751Y455344D03*
Y463578D03*
X834251Y455578D03*
X828751Y459344D03*
X832224Y450328D03*
X831381Y455167D03*
X833751Y463578D03*
X842825Y452739D03*
X828751Y471344D03*
Y467568D03*
X838575Y477554D03*
X839200Y467900D03*
X830046Y476031D03*
X838561Y484071D03*
X841854Y504972D03*
X833000Y503500D03*
X831798Y515314D03*
X838342Y514610D03*
X839061Y555808D03*
X841660Y558200D03*
X835519Y580056D03*
X831018Y583076D03*
X835059Y660940D03*
X837391Y659820D03*
X831505Y897291D03*
X831582Y905153D03*
X832347Y1251703D03*
X844250Y1266759D03*
X832274Y1277301D03*
X832342Y1274626D03*
X833756Y1330156D03*
X834017Y1336252D03*
X833963Y1339464D03*
X838963Y1345974D03*
X833853Y1345833D03*
X841039Y1358082D03*
X839244Y1352094D03*
X841472Y1365050D03*
X835850Y1556133D03*
X829850D03*
X832850D03*
X838850D03*
X832850Y1565133D03*
X835850D03*
X832850Y1562133D03*
X835850D03*
X832850Y1559133D03*
X835850D03*
X829850Y1565133D03*
Y1562133D03*
Y1559133D03*
X838850Y1565133D03*
Y1562133D03*
Y1559133D03*
X841150Y1581379D03*
X832850Y1571133D03*
X835850D03*
X832850Y1568133D03*
X835850D03*
X829850Y1571133D03*
Y1568133D03*
X833077Y1577233D03*
Y1582363D03*
X838650Y1583347D03*
X833077Y1587493D03*
X830550Y1597533D03*
X833550D03*
X830550Y1594533D03*
X833550D03*
X830550Y1600533D03*
X833550D03*
X830550Y1603533D03*
X836550Y1606533D03*
Y1603533D03*
X833550D03*
X830550Y1606533D03*
X833550D03*
X850016Y87341D03*
X843856Y87711D03*
X847473Y94754D03*
X854221Y135862D03*
Y129362D03*
X854201Y143062D03*
X848745Y160137D03*
X845721Y181362D03*
X856213Y191545D03*
X855859Y212425D03*
X855934Y215375D03*
X847581Y232222D03*
X853621Y269057D03*
X853829Y262057D03*
X846189Y281419D03*
X856244Y286447D03*
X843504Y287602D03*
X855481Y299692D03*
X860071Y304850D03*
X843308Y335550D03*
X857187Y342210D03*
X848030Y338461D03*
X850155Y335042D03*
X852303Y337488D03*
X852177Y341882D03*
X848425Y378089D03*
X854552Y381000D03*
X854190Y404035D03*
X855722Y416606D03*
X846000Y418862D03*
X854239Y412911D03*
X851517Y411745D03*
X846000Y423362D03*
X845986Y429413D03*
X857942Y448575D03*
X845100Y440100D03*
X857887Y459847D03*
X848500Y452128D03*
X847686Y475915D03*
X847303Y485788D03*
X846104Y494661D03*
X847518Y490905D03*
X846411Y482128D03*
X849772Y494585D03*
X852209Y507211D03*
X855497Y507205D03*
X849351Y499070D03*
X848097Y503315D03*
X855837Y519713D03*
X847941Y538325D03*
X845094Y535110D03*
X844741Y543864D03*
X843655Y555683D03*
X847435Y555496D03*
X856647Y616786D03*
X854484Y647436D03*
X848999Y644995D03*
X846931Y1291468D03*
X846895Y1295981D03*
X845801Y1287776D03*
X851500Y1302000D03*
X851400Y1305499D03*
X852811Y1313450D03*
X850684Y1310000D03*
X852955Y1320320D03*
X856500Y1321500D03*
X853100Y1331688D03*
X856500Y1330500D03*
X852780Y1338365D03*
X856500Y1339500D03*
Y1348500D03*
X844150Y1578633D03*
Y1570633D03*
Y1582833D03*
X852150Y1574633D03*
X855150Y1579410D03*
Y1570633D03*
X852050Y1584033D03*
X844150Y1594633D03*
X852850Y1587733D03*
X852150Y1590633D03*
X855049D03*
X844700Y1587183D03*
X852150Y1602633D03*
Y1598633D03*
X844150Y1606633D03*
X857550Y1606533D03*
X858630Y60293D03*
X863343Y90021D03*
X865912Y89252D03*
X870892Y131868D03*
X871145Y163862D03*
X875170Y185113D03*
X867529Y231788D03*
X863104Y273103D03*
X868104D03*
X867701Y267537D03*
X863230Y280001D03*
X866619Y286801D03*
X870672Y295485D03*
X870008Y302273D03*
X872508D03*
X871099Y323000D03*
X864342Y330858D03*
X860942D03*
X860587Y342210D03*
X860372Y375195D03*
X866168Y374774D03*
X871190Y382230D03*
X858925Y398537D03*
X864826Y411557D03*
X870220Y430424D03*
X870826Y423423D03*
X870064Y427703D03*
X859500Y429362D03*
X863420D03*
X859469Y425293D03*
X860541Y446089D03*
X860328Y475162D03*
X858288Y467048D03*
X860280Y488636D03*
X860299Y491620D03*
X864361Y493001D03*
X860508Y497772D03*
X862987Y507305D03*
X860341Y503154D03*
X860658Y515961D03*
X867356Y558714D03*
X867733Y575522D03*
X864590Y642420D03*
X870590D03*
X866727Y650739D03*
X866549Y748027D03*
X869275Y750472D03*
X873175D03*
X868496Y776516D03*
X868539Y790882D03*
X870591Y785437D03*
X865466Y790581D03*
Y785581D03*
Y788081D03*
Y783081D03*
X865394Y801244D03*
X865466Y793081D03*
Y795581D03*
Y798081D03*
X865569Y806045D03*
Y808545D03*
X863369Y827461D03*
X863344Y824713D03*
X863372Y833469D03*
Y830718D03*
X867651Y836820D03*
X867646Y833388D03*
X863671Y839062D03*
X865601Y841219D03*
X865109Y850795D03*
X864768Y844815D03*
X864140Y856052D03*
X864020Y859972D03*
X864106Y863534D03*
X864003Y866609D03*
X866005Y941554D03*
X863055Y941441D03*
X863010Y947262D03*
X866010D03*
X863010Y950262D03*
X866010D03*
X866140Y944509D03*
X863088Y944516D03*
X862044Y1249687D03*
X866294Y1255903D03*
X874989Y1410441D03*
X863745Y1444560D03*
X871214Y1466542D03*
X865850Y1556133D03*
X871850D03*
X862850D03*
X868850D03*
X865850Y1565133D03*
Y1562133D03*
Y1559133D03*
X862850Y1565133D03*
Y1562133D03*
Y1559133D03*
X868850Y1565133D03*
X871850D03*
X868850Y1562133D03*
X871850D03*
X868850Y1559133D03*
X871850D03*
X865850Y1571133D03*
Y1568133D03*
X862850Y1571133D03*
Y1568133D03*
X868850Y1571133D03*
X871850D03*
X868850Y1568133D03*
X871850D03*
X863977Y1577233D03*
Y1582363D03*
X869577Y1577233D03*
X858150Y1587284D03*
X863977Y1587493D03*
X869577D03*
X863550Y1597533D03*
X866550Y1594533D03*
Y1597533D03*
X869550Y1594533D03*
Y1597533D03*
X863550Y1594533D03*
X872550D03*
Y1597533D03*
X866550Y1600533D03*
X869550D03*
X863550D03*
X872550D03*
Y1606533D03*
Y1603533D03*
X863550Y1606533D03*
X866550D03*
X869550D03*
X860550D03*
X869550Y1603533D03*
X866550D03*
X863550D03*
X860550D03*
X876696Y176862D03*
Y171362D03*
X887521D03*
Y176862D03*
X889351Y195489D03*
X878328Y183169D03*
X878221Y187449D03*
X887130Y183169D03*
X884986Y198829D03*
X881354Y267407D03*
X884004Y278712D03*
Y274482D03*
X885764Y284361D03*
X877448Y284825D03*
X884004Y271332D03*
X874244Y287047D03*
X873172Y295485D03*
X888000Y293000D03*
X877640Y315789D03*
X873884Y447991D03*
Y450491D03*
X885916Y653912D03*
X883731Y651690D03*
X884410Y794332D03*
X883633Y790336D03*
X883776Y786814D03*
X877459Y802356D03*
X875412Y797350D03*
X882582Y1075083D03*
X879582D03*
X876582D03*
X873582D03*
X882582Y1061983D03*
X879582D03*
X876582D03*
Y1071533D03*
Y1068533D03*
Y1065533D03*
X873582D03*
Y1068533D03*
Y1071533D03*
Y1061983D03*
X886707Y1229920D03*
Y1232920D03*
X881807Y1238920D03*
X876923Y1239520D03*
X886707Y1235920D03*
X881694Y1229763D03*
Y1232763D03*
Y1235763D03*
X876907Y1235586D03*
Y1232586D03*
Y1229586D03*
X881807Y1241920D03*
X877936Y1312336D03*
X883379Y1417881D03*
X875039Y1407246D03*
X886362Y1428973D03*
X884399Y1431507D03*
X879424Y1425001D03*
X883279Y1421726D03*
X883562Y1440356D03*
X881987Y1449608D03*
X887519Y1444625D03*
X877226Y1441585D03*
X887117Y1436735D03*
X877850Y1556133D03*
X874850D03*
X880850D03*
X874850Y1565133D03*
X877850D03*
X880850D03*
X874850Y1562133D03*
X877850D03*
X880850D03*
X874850Y1559133D03*
X877850D03*
X880850D03*
X886150Y1578633D03*
Y1570633D03*
Y1582833D03*
X883150Y1581379D03*
X874850Y1571133D03*
X877850D03*
X874850Y1568133D03*
X877850D03*
X875077Y1577233D03*
Y1582363D03*
X886150Y1594633D03*
X880650Y1583347D03*
X886700Y1587183D03*
X875077Y1587493D03*
X875550Y1597533D03*
Y1594533D03*
X886150Y1606633D03*
X875550Y1600533D03*
Y1606533D03*
X878550D03*
Y1603533D03*
X875550D03*
X891621Y207162D03*
X888930Y206823D03*
X891621Y209662D03*
X888930Y209323D03*
X896621Y207162D03*
X894121D03*
Y209662D03*
X896621D03*
X892376Y466430D03*
X899000Y481038D03*
X888372Y547518D03*
X902376Y590172D03*
X900323Y604377D03*
X900301Y828248D03*
Y831221D03*
X899500Y853000D03*
X901000Y909000D03*
X901842Y936863D03*
X903925Y948500D03*
X889273Y1134470D03*
X902382Y1137558D03*
X891996Y1149707D03*
X900280Y1150769D03*
X902482Y1140558D03*
X888247Y1219520D03*
Y1222520D03*
X891247D03*
Y1219520D03*
X888247Y1225520D03*
X896974Y1232869D03*
Y1235869D03*
X896907Y1238920D03*
X896974Y1229869D03*
X891247Y1225520D03*
X896907Y1241920D03*
X892000Y1307500D03*
X888854Y1337936D03*
X890620Y1342990D03*
X900885Y1435041D03*
X900808Y1437798D03*
X902377Y1456465D03*
X904850Y1556133D03*
X894150Y1574633D03*
X897150Y1579410D03*
Y1570633D03*
X894050Y1584033D03*
X894150Y1590633D03*
X894850Y1587733D03*
X897049Y1590633D03*
X900150Y1587284D03*
X894150Y1602633D03*
Y1598633D03*
X899550Y1606533D03*
X902550Y1603533D03*
Y1606533D03*
X917387Y184114D03*
X908621Y188899D03*
X910267Y242658D03*
X910093Y246015D03*
X916268Y269859D03*
X909023Y294734D03*
X910752Y286141D03*
X913512Y486743D03*
X903340Y505105D03*
X917582Y549564D03*
X909747Y579695D03*
X911980Y585280D03*
X910731Y590251D03*
X905526Y594657D03*
X910535Y619251D03*
X906706Y614062D03*
X909747Y628426D03*
X915334Y639166D03*
X908823Y655116D03*
X906274Y654921D03*
X909320Y663930D03*
X907207Y667646D03*
X906345Y742414D03*
X904535Y744639D03*
X906387Y821221D03*
Y815721D03*
X906313Y825095D03*
X903149Y825094D03*
X917000Y853000D03*
X907000Y899777D03*
X913000Y909000D03*
X917000D03*
Y918500D03*
X905000D03*
X915575Y948500D03*
X910000Y954500D03*
X912425Y948500D03*
X907075D03*
X910000Y957500D03*
X912500Y963309D03*
X907500D03*
X909000Y974000D03*
Y982000D03*
X911041Y979459D03*
X909000Y977491D03*
X919779Y1155658D03*
X915053Y1219520D03*
Y1222520D03*
X912053D03*
Y1219520D03*
Y1225520D03*
X915053D03*
X910707Y1229920D03*
Y1232920D03*
X905007Y1238920D03*
X910707Y1235920D03*
X905008Y1229940D03*
Y1232940D03*
Y1235940D03*
X905007Y1241920D03*
X917112Y1266300D03*
X917127Y1275251D03*
X917396Y1271025D03*
X917158Y1279451D03*
X917341Y1283775D03*
X916895Y1292330D03*
X916945Y1296713D03*
X917034Y1288235D03*
X912500Y1310000D03*
X914333Y1322700D03*
X914462Y1329351D03*
X914355Y1340726D03*
X914276Y1347550D03*
X913270Y1440429D03*
X910041Y1440536D03*
X907031Y1457231D03*
X909473Y1448779D03*
X910850Y1556133D03*
X907850D03*
X916850D03*
X913850D03*
X907850Y1559133D03*
Y1562133D03*
X910850Y1559133D03*
Y1562133D03*
X907850Y1565133D03*
X910850D03*
X904850Y1559133D03*
Y1562133D03*
Y1565133D03*
X913850Y1559133D03*
Y1562133D03*
Y1565133D03*
X916850Y1559133D03*
Y1562133D03*
Y1565133D03*
X907850Y1568133D03*
Y1571133D03*
X910850Y1568133D03*
Y1571133D03*
X904850Y1568133D03*
Y1571133D03*
X913850Y1568133D03*
Y1571133D03*
X916850Y1568133D03*
Y1571133D03*
X905977Y1577233D03*
Y1582363D03*
X911577Y1577233D03*
X917077D03*
Y1582363D03*
X905977Y1587493D03*
X911577D03*
X917077D03*
X914550Y1597533D03*
Y1594533D03*
X905550D03*
X911550Y1597533D03*
Y1594533D03*
X908550Y1597533D03*
Y1594533D03*
X905550Y1597533D03*
X917550D03*
Y1594533D03*
X914550Y1600533D03*
X905550D03*
X911550D03*
X908550D03*
X917550D03*
X914550Y1603533D03*
Y1606533D03*
X905550Y1603533D03*
X908550D03*
X911550D03*
Y1606533D03*
X908550D03*
X905550D03*
X917550Y1603533D03*
Y1606533D03*
X915991Y1667328D03*
X922128Y182486D03*
X923386Y193563D03*
X932129Y244103D03*
X922341Y263875D03*
X923103Y362852D03*
X924724Y372211D03*
X919294Y374503D03*
X921318Y372475D03*
X920018Y362877D03*
X921430Y507156D03*
X921367Y503407D03*
X924430Y507156D03*
X924367Y503407D03*
X922591Y496671D03*
X926730Y540897D03*
X921318Y549357D03*
X920031Y577846D03*
X926449Y577806D03*
X930406Y577308D03*
X923747Y584945D03*
X920989Y614132D03*
X925643Y616620D03*
X920989Y617692D03*
X924987Y622523D03*
X932000Y850500D03*
X920234Y843349D03*
X927777Y843416D03*
X930575Y864075D03*
X918500Y860075D03*
X920897Y881879D03*
X929603Y879000D03*
X920000Y895500D03*
X923000D03*
X925500Y907500D03*
X921000Y921925D03*
X925500Y916500D03*
X929500D03*
X932500Y941500D03*
X919500D03*
X928500D03*
X923500D03*
X926000Y949500D03*
Y946500D03*
X919272Y986782D03*
X920107Y1235920D03*
Y1232920D03*
Y1238920D03*
Y1229920D03*
Y1241920D03*
X924500Y1306000D03*
Y1302000D03*
X918000Y1312500D03*
Y1321500D03*
X925459Y1315352D03*
X925500Y1319000D03*
X922000Y1324000D03*
Y1328000D03*
X931326Y1328467D03*
X931216Y1323050D03*
X918000Y1330500D03*
Y1339500D03*
X922000Y1342000D03*
X925500Y1333000D03*
Y1337000D03*
X922000Y1346000D03*
X922850Y1556133D03*
X919850D03*
X922850Y1559133D03*
Y1562133D03*
Y1565133D03*
X919850Y1559133D03*
Y1562133D03*
Y1565133D03*
X925650Y1581379D03*
X919850Y1568133D03*
Y1571133D03*
X922650Y1583347D03*
X920550Y1603533D03*
Y1606533D03*
X921289Y1666337D03*
X927798Y1660762D03*
X945721Y173389D03*
X943221D03*
Y176389D03*
X945721D03*
X935551Y173329D03*
X938161Y173389D03*
Y176389D03*
X935591Y176049D03*
X940721Y173389D03*
Y176389D03*
X939271Y191419D03*
X935771D03*
X944520Y182094D03*
X936454Y184015D03*
X937267Y189010D03*
X945120Y193264D03*
X938570Y233152D03*
X945380Y233962D03*
X949181Y280131D03*
X939938Y386423D03*
X933390Y386405D03*
X944112Y386593D03*
X941764Y420403D03*
X944264D03*
X933390Y559943D03*
X939613Y562031D03*
X937310Y580755D03*
X941764Y587884D03*
X944264D03*
X935766Y587692D03*
X939511Y597073D03*
X935746Y611573D03*
X935783Y631192D03*
X937580Y655946D03*
X945602Y664653D03*
X934539Y664648D03*
X934339Y668533D03*
X941478Y668648D03*
X939216Y664767D03*
X948644Y811190D03*
X938000Y862620D03*
X943000Y862823D03*
X934925Y891425D03*
X945075Y891500D03*
X938500Y907500D03*
X946500Y915988D03*
X938500Y916500D03*
X934500D03*
X942500Y916340D03*
X942631Y943162D03*
X936960Y942898D03*
X935368Y939182D03*
X944515Y939850D03*
X940000Y973500D03*
Y986500D03*
Y982500D03*
Y977500D03*
X937148Y1134343D03*
X933234Y1145058D03*
X936393Y1148087D03*
X947305Y1150769D03*
X943101Y1219520D03*
Y1222520D03*
X946101D03*
Y1219520D03*
X943101Y1225520D03*
X946101D03*
X945691Y1229920D03*
Y1232920D03*
X940791Y1238920D03*
X935907Y1239520D03*
X945691Y1235920D03*
X940678Y1229763D03*
Y1232763D03*
Y1235763D03*
X935891Y1235586D03*
Y1232586D03*
Y1229586D03*
X940791Y1241920D03*
X940994Y1265636D03*
X941011Y1269499D03*
X941500Y1278059D03*
X941033Y1282115D03*
X946730Y1293219D03*
Y1290719D03*
X940919Y1290152D03*
X940937Y1294191D03*
X941083Y1286156D03*
X947135Y1287403D03*
X945872Y1304541D03*
Y1301500D03*
X945617Y1309500D03*
X935028Y1313769D03*
X935300Y1317525D03*
X939071Y1448219D03*
X949216Y1448337D03*
X944105Y1448317D03*
X946402Y1491204D03*
X943902D03*
X936402D03*
X938902D03*
X941402D03*
X933778D03*
X946402Y1501204D03*
Y1498704D03*
Y1496204D03*
Y1493704D03*
X943902D03*
Y1496204D03*
Y1498704D03*
Y1501204D03*
X936402Y1493704D03*
Y1496204D03*
Y1498704D03*
Y1501204D03*
X938902Y1493704D03*
Y1496204D03*
Y1498704D03*
Y1501204D03*
X941402Y1493704D03*
Y1496204D03*
Y1498704D03*
Y1501204D03*
X933778Y1493704D03*
Y1496204D03*
Y1498704D03*
Y1501204D03*
X936150Y1582233D03*
Y1578233D03*
Y1590233D03*
Y1586233D03*
X943798Y1660762D03*
X948401Y176499D03*
X961407Y205125D03*
X950950Y284662D03*
X947821Y386567D03*
X958158Y449020D03*
X958049Y453912D03*
X958101Y457846D03*
X958255Y465811D03*
X959033Y487289D03*
X957380Y515233D03*
X960054Y516982D03*
X962035Y518988D03*
X954757Y593045D03*
X948156Y593912D03*
X952497Y614080D03*
X951102Y628662D03*
X954362Y633314D03*
Y630061D03*
X954259Y657371D03*
X958299Y659886D03*
X954361Y660215D03*
X957462Y668700D03*
X951886Y804495D03*
X951895Y808163D03*
X951466Y816400D03*
X961592Y821737D03*
X949000Y850500D03*
X951000Y855425D03*
X958000Y865500D03*
Y862000D03*
X949500Y870500D03*
Y886500D03*
X953925Y900500D03*
X951169Y910425D03*
X957075Y906500D03*
X960925D03*
X954500Y915988D03*
X950500Y916150D03*
X948500Y937000D03*
X949407Y1137558D03*
X949507Y1140558D03*
X955958Y1232869D03*
Y1235869D03*
X955891Y1238920D03*
X955958Y1229869D03*
X955891Y1241920D03*
X964669Y1271000D03*
X963500Y1275000D03*
X955000Y1283000D03*
Y1287000D03*
X947650Y1314500D03*
Y1319000D03*
Y1323500D03*
Y1328000D03*
Y1337000D03*
Y1332500D03*
Y1341500D03*
Y1346000D03*
X960313Y1362654D03*
X958306Y1448056D03*
X954541Y1448307D03*
X961566Y1448341D03*
X953902Y1491204D03*
X951402D03*
X948902D03*
X956402D03*
X958902D03*
X961402D03*
X953902Y1501204D03*
Y1498704D03*
Y1496204D03*
Y1493704D03*
X951402Y1501204D03*
Y1498704D03*
Y1496204D03*
Y1493704D03*
X948902Y1501204D03*
Y1498704D03*
Y1496204D03*
Y1493704D03*
X956402D03*
X958902D03*
X961402D03*
X963402Y1501204D03*
X958402D03*
X959584Y1550824D03*
X949195Y1655145D03*
X951798Y1660762D03*
X975691Y161220D03*
X962673Y170263D03*
Y167763D03*
X967943Y204813D03*
X971943D03*
X975749Y202049D03*
X977221Y205399D03*
X964807Y205125D03*
X973997Y320848D03*
X966278Y556736D03*
X964114Y554704D03*
X976528Y801041D03*
Y803541D03*
Y806041D03*
Y808541D03*
X963500Y854719D03*
X973562Y859767D03*
X964075Y900500D03*
X966804Y1155658D03*
X969907Y1219520D03*
Y1222520D03*
X966907D03*
Y1219520D03*
Y1225520D03*
X969907D03*
X969691Y1229920D03*
Y1232920D03*
X963991Y1238920D03*
X969691Y1235920D03*
X963992Y1229940D03*
Y1232940D03*
Y1235940D03*
X979091Y1229920D03*
X963991Y1241920D03*
X964000Y1267000D03*
X966441Y1278145D03*
X972408Y1312557D03*
X973650Y1431424D03*
X969785Y1447987D03*
X967002Y1448013D03*
X964503Y1448097D03*
X969519Y1452784D03*
X973255Y1456714D03*
X975703Y1451367D03*
X967268Y1491204D03*
X969768D03*
X972268D03*
X974768D03*
X977268D03*
X963902D03*
X967268Y1501204D03*
Y1498704D03*
Y1496204D03*
Y1493704D03*
X969768D03*
Y1496204D03*
Y1498704D03*
Y1501204D03*
X972268Y1493704D03*
Y1496204D03*
Y1498704D03*
Y1501204D03*
X974768Y1493704D03*
Y1496204D03*
Y1498704D03*
Y1501204D03*
X977268Y1493704D03*
Y1496204D03*
Y1498704D03*
Y1501204D03*
X963902Y1493704D03*
X962584Y1550824D03*
X990579Y155248D03*
X981112Y161204D03*
X988751Y167541D03*
X986447Y158209D03*
X989605Y175400D03*
X985922Y171861D03*
X985445Y185389D03*
X986021Y195099D03*
X979849Y202049D03*
X983879Y202162D03*
X990221Y199699D03*
X987321Y198599D03*
Y202099D03*
X990221Y206699D03*
Y203199D03*
X987321Y205599D03*
X980406Y218283D03*
X980377Y215740D03*
X978269Y264929D03*
X982455Y260781D03*
Y271443D03*
X978827Y303412D03*
X984509Y303623D03*
X989582Y303563D03*
X988460Y358405D03*
X993460D03*
X984272Y349293D03*
X980346Y353527D03*
X981019Y349387D03*
X992460Y370659D03*
X985668Y389311D03*
X980690Y387784D03*
X984605Y408480D03*
X987581Y408332D03*
X988190Y424626D03*
X983358Y449026D03*
X991664Y446372D03*
X993650Y465315D03*
X988650D03*
X991270Y470212D03*
X990292Y494420D03*
X988125Y485193D03*
X986790Y480140D03*
X987440Y504742D03*
X982806Y498606D03*
X986056Y516014D03*
X994056Y521014D03*
Y516014D03*
Y526074D03*
Y531074D03*
X992125Y1061434D03*
X989125D03*
X986125D03*
X983125D03*
X992125Y1064984D03*
Y1067984D03*
X989125D03*
Y1064984D03*
X992125Y1074534D03*
Y1070984D03*
X989125D03*
Y1074534D03*
X986125D03*
X983125D03*
X979091Y1235920D03*
Y1232920D03*
Y1238920D03*
Y1241920D03*
X985396Y1268154D03*
X982665Y1265474D03*
X978318Y1263128D03*
X988242Y1273193D03*
X979228Y1297918D03*
X982000Y1307500D03*
X978026Y1459998D03*
X980779Y1451545D03*
X990634Y1491204D03*
X979768D03*
X982268D03*
X984768D03*
X987268D03*
X990634Y1493704D03*
Y1496204D03*
Y1498704D03*
Y1501204D03*
X979768Y1493704D03*
X982268D03*
X984768D03*
X987268D03*
X986768Y1501204D03*
X981768D03*
X991196Y1550840D03*
X1006221Y164799D03*
X1002721D03*
X1005307Y155043D03*
X995181Y157689D03*
X999580Y154895D03*
X994257D03*
X996416Y176579D03*
X1002921Y178799D03*
X1002827Y172479D03*
X999221Y189299D03*
X1002721D03*
X1006161Y189019D03*
X1008918Y192994D03*
X1008121Y203525D03*
X1000611Y215039D03*
X1005641Y214969D03*
X1001196Y223898D03*
X1008707Y230423D03*
X997300Y234876D03*
X1006468Y301857D03*
X1003460Y358405D03*
X998460D03*
X994409Y349813D03*
X1000460Y369535D03*
X996889Y374156D03*
X1007080Y367087D03*
X999320Y394480D03*
X1006763Y396206D03*
X1003651Y433426D03*
X998859Y437141D03*
X998359Y451675D03*
X994900Y446192D03*
X998359Y462675D03*
Y457175D03*
X1003909Y454662D03*
Y460162D03*
X998359Y479175D03*
Y468175D03*
Y473675D03*
X996320Y470364D03*
X998359Y484675D03*
X1007077Y484937D03*
X998326Y499675D03*
X995530Y500034D03*
X1006206Y510304D03*
X1002056Y521014D03*
Y516014D03*
Y526074D03*
Y531074D03*
X1004527Y541924D03*
Y553224D03*
X1005270Y625710D03*
X1003090Y1037329D03*
X999350Y1310500D03*
Y1315000D03*
Y1319420D03*
Y1323840D03*
Y1328260D03*
Y1332740D03*
Y1341580D03*
Y1337160D03*
Y1346000D03*
X995500Y1368000D03*
X998000Y1365500D03*
X995000Y1362000D03*
X1000634Y1491204D03*
X998134D03*
X995634D03*
X993134D03*
X1003134D03*
X1005634D03*
X993134Y1496204D03*
Y1493704D03*
X1003134D03*
X1005634D03*
X1000634Y1501204D03*
Y1498704D03*
Y1496204D03*
Y1493704D03*
X998134Y1501204D03*
Y1498704D03*
Y1496204D03*
Y1493704D03*
X995634Y1501204D03*
Y1498704D03*
Y1496204D03*
Y1493704D03*
X993134Y1501204D03*
Y1498704D03*
X1005134Y1501204D03*
X994196Y1550840D03*
X1009721Y164799D03*
X1013221D03*
X1014301Y179699D03*
X1017201D03*
X1019901Y179799D03*
X1011991Y189019D03*
X1014901Y189299D03*
X1017701Y189059D03*
X1011120Y198114D03*
X1020521Y194499D03*
X1011068Y207667D03*
X1021440Y226423D03*
X1019356Y222423D03*
X1010909Y213708D03*
X1011721Y233699D03*
X1019531Y230423D03*
X1018220Y243638D03*
X1015220D03*
X1009220D03*
X1014828Y268427D03*
Y258970D03*
X1013396Y280806D03*
X1011423Y282889D03*
X1023110Y287311D03*
X1017835Y291236D03*
X1023000Y298311D03*
X1016764Y350082D03*
X1010252Y363440D03*
X1009815Y404896D03*
X1020748Y420902D03*
Y425902D03*
X1023420Y462921D03*
X1017220Y464155D03*
X1023515Y454397D03*
X1019205Y457687D03*
X1023420Y468039D03*
X1017350Y472155D03*
X1022874Y474545D03*
X1019210Y480155D03*
X1013306Y518146D03*
Y532501D03*
X1017718Y541201D03*
X1019161Y554757D03*
X1024161D03*
X1017961Y545074D03*
X1009611Y550074D03*
Y545074D03*
X1021425Y568614D03*
X1012925Y558000D03*
X1011602Y568473D03*
X1016000Y563107D03*
X1019261Y571324D03*
X1007587Y761546D03*
Y772480D03*
Y775880D03*
Y764946D03*
Y783482D03*
Y786882D03*
Y794484D03*
Y797884D03*
X1016000Y1303000D03*
X1009905Y1305500D03*
X1009896Y1301500D03*
X1013605Y1316050D03*
X1013529Y1318950D03*
X1012500Y1322500D03*
Y1328500D03*
Y1341580D03*
X1013500Y1332740D03*
Y1337160D03*
X1016000Y1361000D03*
X1012500Y1347500D03*
X1021500Y1491204D03*
X1019000D03*
X1016500D03*
X1014000D03*
X1008134D03*
X1010634D03*
X1021500Y1501204D03*
Y1498704D03*
Y1496204D03*
Y1493704D03*
X1019000Y1501204D03*
Y1498704D03*
Y1496204D03*
Y1493704D03*
X1016500Y1501204D03*
Y1498704D03*
Y1496204D03*
Y1493704D03*
X1014000D03*
Y1496204D03*
Y1498704D03*
Y1501204D03*
X1008134Y1493704D03*
X1010634D03*
X1010134Y1501204D03*
X1022796Y1550840D03*
X1022801Y179799D03*
X1027690Y237902D03*
X1024220Y243638D03*
X1033590Y298311D03*
Y287311D03*
X1029200Y351614D03*
X1022674Y357848D03*
X1028146Y355960D03*
X1034214Y351601D03*
X1029601Y394387D03*
X1034855Y411704D03*
X1034409Y429618D03*
X1024443Y424051D03*
X1039015Y444404D03*
X1034899D03*
X1025830Y449022D03*
X1023320Y451112D03*
X1035860Y485976D03*
X1027504Y485637D03*
X1024509Y500168D03*
X1024546Y511254D03*
X1037254Y521014D03*
X1036708Y514883D03*
X1037254Y526074D03*
X1025631Y540104D03*
X1036021Y534990D03*
X1030000Y554500D03*
X1034412Y567416D03*
X1031000Y568500D03*
X1028500Y563000D03*
X1024000D03*
X1029431Y587342D03*
X1032055Y587260D03*
X1028540Y621000D03*
X1035269Y735474D03*
X1032736Y735320D03*
X1030190Y735023D03*
X1025493Y761819D03*
X1035026Y756009D03*
X1036427Y770532D03*
X1038867Y774960D03*
X1025493Y765719D03*
X1033236Y1279287D03*
X1033184Y1275996D03*
X1036411Y1275658D03*
X1036463Y1278949D03*
X1024000Y1491204D03*
X1026500D03*
X1029000D03*
X1031500D03*
X1034000D03*
X1024000Y1501204D03*
Y1498704D03*
Y1496204D03*
Y1493704D03*
X1026500D03*
X1029000D03*
X1031500D03*
X1034000D03*
X1033500Y1501204D03*
X1028500D03*
X1025796Y1550840D03*
X1046384Y269814D03*
X1049451Y266747D03*
X1040060Y313528D03*
X1051873Y305482D03*
X1049573Y406586D03*
X1042015Y444404D03*
X1047515D03*
X1043377Y452740D03*
X1040836Y510894D03*
X1045254Y516014D03*
Y534074D03*
Y526074D03*
X1043991Y540979D03*
X1047335Y549574D03*
X1047200Y543090D03*
X1037301Y539685D03*
X1039407Y547723D03*
X1039000Y555000D03*
X1039718Y563268D03*
X1042628Y556845D03*
X1050956Y591090D03*
X1040626Y668441D03*
X1042389Y733426D03*
X1044056Y736188D03*
X1040915Y766870D03*
X1037566Y1047135D03*
X1037895Y1251517D03*
X1039546Y1275474D03*
X1039598Y1278765D03*
X1042855Y1275552D03*
X1042649Y1279152D03*
X1047366Y1491204D03*
X1044866D03*
X1037366D03*
X1042366D03*
X1039866D03*
X1049866D03*
X1047366Y1498704D03*
Y1496204D03*
Y1493704D03*
X1044866Y1496204D03*
Y1493704D03*
X1037366D03*
Y1496204D03*
Y1498704D03*
X1047366Y1501204D03*
X1044866D03*
Y1498704D03*
X1042366Y1501204D03*
Y1498704D03*
Y1496204D03*
Y1493704D03*
X1039866Y1501204D03*
Y1498704D03*
Y1496204D03*
Y1493704D03*
X1037366Y1501204D03*
X1049866Y1493704D03*
X1051866Y1501204D03*
X1053290Y1652082D03*
X1045545Y1663089D03*
X1066231Y165078D03*
Y167578D03*
X1062704Y270875D03*
X1056941Y259176D03*
X1054613Y261586D03*
X1062923Y295053D03*
X1063356Y318297D03*
X1055934Y388988D03*
X1068143Y380188D03*
X1055934Y381988D03*
X1052505Y406576D03*
X1057798Y427059D03*
Y429618D03*
X1062642Y444859D03*
X1062640Y449155D03*
X1062741Y457959D03*
X1057276Y458155D03*
X1062173Y479655D03*
X1062873Y490180D03*
X1055905Y492537D03*
X1062250Y484672D03*
X1056960Y482262D03*
X1057450Y509242D03*
X1058231Y523238D03*
X1060719Y512359D03*
Y516059D03*
X1061817Y736362D03*
X1065154Y736282D03*
X1057057Y767299D03*
Y771099D03*
X1055171Y1307203D03*
Y1311203D03*
X1058143Y1433809D03*
X1065732Y1491204D03*
X1063232D03*
X1060732D03*
X1052366D03*
X1054866D03*
X1057366D03*
X1065732Y1501204D03*
Y1498704D03*
Y1496204D03*
Y1493704D03*
X1063232Y1501204D03*
Y1498704D03*
Y1496204D03*
Y1493704D03*
X1060732D03*
Y1496204D03*
Y1498704D03*
Y1501204D03*
X1052366Y1493704D03*
X1054866D03*
X1057366D03*
X1056866Y1501204D03*
X1057396Y1550840D03*
X1054396D03*
X1071698Y270702D03*
X1078823Y269400D03*
X1071656Y366726D03*
X1078400Y391226D03*
X1074654Y380188D03*
X1078400Y383226D03*
X1074249Y387795D03*
X1082866Y403068D03*
X1074736Y396929D03*
X1072135Y396908D03*
X1072738Y411322D03*
Y416763D03*
Y421922D03*
X1072673Y428791D03*
X1077873Y463444D03*
X1080453Y457959D03*
X1071470Y475525D03*
X1080640Y467000D03*
X1080574Y471500D03*
X1071667D03*
Y467000D03*
X1080416Y482772D03*
X1080420Y487782D03*
X1071710Y483655D03*
Y488782D03*
X1081730Y509172D03*
X1078499Y648202D03*
X1072232Y667749D03*
X1068378Y736795D03*
X1070616Y766870D03*
X1076903Y1300361D03*
Y1302861D03*
X1079403D03*
Y1300361D03*
X1074403Y1302861D03*
Y1300361D03*
X1076903Y1305361D03*
X1079403D03*
X1074403D03*
Y1307861D03*
Y1310361D03*
Y1312861D03*
X1079403Y1307861D03*
Y1310361D03*
Y1312861D03*
X1076903D03*
Y1310361D03*
Y1307861D03*
X1079403Y1315361D03*
X1076903D03*
Y1317861D03*
X1079403D03*
X1074403D03*
Y1315361D03*
X1069839Y1368999D03*
Y1371540D03*
X1076601Y1382574D03*
X1071332Y1379914D03*
X1076601Y1380066D03*
X1080555Y1380511D03*
X1073612Y1376389D03*
X1081005Y1425458D03*
X1071117Y1445005D03*
X1077031Y1451498D03*
X1070312Y1452028D03*
X1073307Y1451931D03*
X1070732Y1491204D03*
X1068232D03*
X1073232D03*
X1075732D03*
X1078232D03*
X1080732D03*
X1070732Y1501204D03*
Y1498704D03*
Y1496204D03*
Y1493704D03*
X1068232Y1501204D03*
Y1498704D03*
Y1496204D03*
Y1493704D03*
X1073232D03*
X1075732D03*
X1078232D03*
X1080732D03*
X1080232Y1501204D03*
X1075232D03*
X1072134Y1647920D03*
X1081011Y1685499D03*
X1078011D03*
X1081011Y1682499D03*
X1078011D03*
X1077172Y1676686D03*
X1077881Y1688252D03*
X1080933Y1688245D03*
X1078016Y1691207D03*
X1080966Y1691320D03*
X1087421Y149716D03*
X1086714Y353515D03*
X1090086Y370417D03*
X1090061Y428019D03*
X1087963Y440605D03*
Y446105D03*
X1084840Y438234D03*
Y443515D03*
X1087963Y462605D03*
Y457105D03*
X1087940Y452110D03*
X1084840Y460005D03*
X1085851Y465978D03*
X1087963Y468105D03*
X1095448Y479426D03*
X1084000Y477500D03*
X1090000D03*
X1087963Y484605D03*
Y494641D03*
Y489641D03*
X1083434Y481500D03*
X1085730Y509362D03*
X1091730D03*
X1095730D03*
X1082622Y520652D03*
X1082438Y524033D03*
X1085438D03*
X1085622Y520652D03*
X1083281Y651601D03*
X1091270Y668286D03*
X1086758Y767299D03*
Y771099D03*
X1090203Y1307861D03*
Y1310361D03*
Y1312861D03*
X1092703D03*
Y1310361D03*
Y1307861D03*
Y1300361D03*
Y1302861D03*
X1090203D03*
Y1300361D03*
X1095203Y1302861D03*
Y1300361D03*
X1092703Y1305361D03*
X1090203D03*
X1095203D03*
Y1307861D03*
Y1310361D03*
Y1312861D03*
X1090203Y1315361D03*
X1092703D03*
Y1317861D03*
X1090203D03*
X1095203D03*
Y1315361D03*
X1087059Y1372853D03*
X1089489D03*
X1091919D03*
X1092889Y1367278D03*
Y1370178D03*
X1084043Y1382111D03*
X1083293Y1379543D03*
X1094683Y1379188D03*
Y1376288D03*
X1091598Y1491204D03*
X1089098D03*
X1086598D03*
X1084098D03*
X1091598Y1501204D03*
Y1498704D03*
Y1496204D03*
Y1493704D03*
X1089098Y1501204D03*
Y1498704D03*
Y1496204D03*
Y1493704D03*
X1086598Y1501204D03*
Y1498704D03*
Y1496204D03*
Y1493704D03*
X1084098D03*
Y1498704D03*
Y1501204D03*
Y1496204D03*
X1089934Y1550784D03*
X1092934D03*
X1097000Y1629500D03*
X1096500Y1639000D03*
X1096768Y1635080D03*
X1090958Y1646528D03*
Y1649928D03*
X1084629Y1673002D03*
X1087141Y1688914D03*
X1092980Y1699179D03*
X1089030Y1717841D03*
Y1722841D03*
X1099500Y318000D03*
X1111001Y361272D03*
X1107300Y456944D03*
X1111076Y464388D03*
X1108076Y646774D03*
X1104443Y646983D03*
X1100316Y766870D03*
X1109503Y1302861D03*
X1107003D03*
Y1300361D03*
X1109503Y1305361D03*
X1107003D03*
Y1307861D03*
Y1310361D03*
Y1312861D03*
X1109503Y1307861D03*
Y1310361D03*
Y1312861D03*
Y1300361D03*
Y1315361D03*
Y1317861D03*
X1107003D03*
Y1315361D03*
X1102439Y1368999D03*
Y1371540D03*
X1098949Y1373158D03*
X1109201Y1382574D03*
X1103932Y1379914D03*
X1109201Y1380066D03*
X1106212Y1376389D03*
X1098949Y1378958D03*
X1096849Y1377558D03*
X1098949Y1376058D03*
X1096749Y1374558D03*
X1099098Y1501204D03*
X1102248Y1496186D03*
X1106700Y1526591D03*
X1112529Y1547661D03*
X1111701Y1558640D03*
X1107181Y1615917D03*
X1109811D03*
X1098549Y1625749D03*
X1100961Y1622543D03*
X1109000Y1671107D03*
X1105148Y1696029D03*
X1099108Y1691229D03*
X1100998Y1715841D03*
Y1725991D03*
X1119676Y54132D03*
X1124834Y56805D03*
X1124270Y404640D03*
X1121628Y401915D03*
X1121077Y511498D03*
X1125077D03*
X1126387Y615658D03*
X1118435Y625307D03*
X1114467Y640802D03*
X1120321Y635832D03*
X1116540Y651070D03*
X1112190Y651962D03*
X1116459Y767299D03*
Y771099D03*
X1112003Y1302861D03*
Y1300361D03*
Y1305361D03*
X1122803Y1307861D03*
X1125303D03*
Y1310361D03*
Y1312861D03*
X1122803D03*
Y1310361D03*
X1112003Y1312861D03*
Y1310361D03*
Y1307861D03*
X1125303Y1300361D03*
Y1302861D03*
X1122803D03*
Y1300361D03*
X1125303Y1305361D03*
X1122803D03*
X1125303Y1315361D03*
X1122803D03*
X1112003D03*
Y1317861D03*
X1125303D03*
X1122803D03*
X1124519Y1372853D03*
X1119659D03*
X1122089D03*
X1125469Y1367108D03*
Y1370008D03*
X1116643Y1382111D03*
X1113155Y1380511D03*
X1115893Y1379543D03*
X1124375Y1423488D03*
X1124415Y1426168D03*
Y1428668D03*
Y1431168D03*
Y1433668D03*
X1115098Y1468871D03*
Y1472271D03*
X1124875Y1490042D03*
X1125498Y1487292D03*
X1116917Y1506823D03*
X1119912Y1506936D03*
X1116917Y1509898D03*
X1119912Y1509891D03*
Y1515644D03*
X1116917D03*
X1119912Y1512644D03*
X1116917D03*
X1114617Y1526318D03*
X1113887Y1543447D03*
X1119459Y1556343D03*
X1118133Y1587998D03*
Y1591398D03*
X1115027Y1598788D03*
X1117247Y1604554D03*
X1113847D03*
X1124532Y1634915D03*
X1114286Y1630507D03*
X1117136Y1630441D03*
X1113490Y1651862D03*
X1112500Y1671107D03*
X1125784Y1662705D03*
X1124394Y1658967D03*
X1120595D03*
X1126000Y1672419D03*
X1122610Y1677976D03*
X1124091Y1683983D03*
X1114414Y1698859D03*
X1114394Y1695936D03*
X1119361Y1713734D03*
X1113948Y1711244D03*
X1126902Y60805D03*
X1142144Y63186D03*
X1132340Y468202D03*
Y471702D03*
X1141267Y500296D03*
X1134567Y513870D03*
X1139360Y516031D03*
X1129387Y615658D03*
X1138387D03*
X1132855Y609373D03*
X1135387Y615658D03*
X1130017Y766870D03*
X1127803Y1302861D03*
Y1300361D03*
Y1305361D03*
Y1307861D03*
Y1310361D03*
Y1312861D03*
X1139703Y1302861D03*
Y1300361D03*
Y1305361D03*
Y1307861D03*
Y1310361D03*
Y1312861D03*
X1127803Y1317861D03*
Y1315361D03*
X1139703Y1317861D03*
Y1315361D03*
X1135139Y1368999D03*
Y1371540D03*
X1131549Y1373158D03*
X1136632Y1379914D03*
X1138912Y1376389D03*
X1127283Y1379188D03*
X1129449Y1377558D03*
X1127283Y1376288D03*
X1129349Y1374558D03*
X1131549Y1378958D03*
Y1376058D03*
X1129965Y1403877D03*
X1127465D03*
X1129965Y1401377D03*
X1127465D03*
X1132465Y1403877D03*
Y1401377D03*
X1129925Y1398737D03*
X1127425D03*
X1134925D03*
X1132425D03*
X1137425D03*
X1137465Y1401377D03*
X1134965D03*
Y1403877D03*
X1137465D03*
X1137275Y1424138D03*
X1134775D03*
X1132275D03*
X1126875Y1423488D03*
X1129775Y1424138D03*
X1140175Y1423488D03*
X1140215Y1428668D03*
Y1426168D03*
X1134815Y1433668D03*
X1137315D03*
X1140215D03*
Y1431168D03*
X1132315Y1433668D03*
X1137315Y1426818D03*
X1134815D03*
X1137345Y1431058D03*
X1134845D03*
X1132315Y1426818D03*
X1132345Y1431058D03*
X1126915Y1428668D03*
Y1426168D03*
X1129815Y1433668D03*
X1126915D03*
Y1431168D03*
X1129815Y1426818D03*
X1129845Y1431058D03*
X1131478Y1485427D03*
X1134183Y1483926D03*
X1126951Y1484646D03*
X1140960Y1489434D03*
Y1491934D03*
X1141045Y1534952D03*
Y1537452D03*
Y1544952D03*
Y1542452D03*
Y1539952D03*
X1135033Y1556112D03*
X1142639Y1562789D03*
X1133765Y1568952D03*
X1140655Y1569256D03*
X1137755Y1569543D03*
X1138480Y1576364D03*
X1140422Y1595455D03*
X1139037Y1611383D03*
X1131824Y1600593D03*
Y1603993D03*
X1140325Y1598697D03*
X1139037Y1614153D03*
X1139142Y1618859D03*
X1139188Y1621603D03*
X1132981Y1634531D03*
X1141084Y1646672D03*
Y1643272D03*
X1137542Y1647925D03*
X1134207Y1669230D03*
X1129184Y1662705D03*
X1132406Y1658967D03*
X1136575Y1676239D03*
X1141356Y1676542D03*
X1133206Y1675383D03*
X1132176Y1690038D03*
X1142643Y74738D03*
X1151679Y72258D03*
X1150118Y207344D03*
X1155268D03*
Y212344D03*
X1150118D03*
X1155890Y478812D03*
X1150577Y478840D03*
X1144663Y492319D03*
Y500319D03*
X1151036Y501627D03*
X1143060Y516476D03*
X1154145Y583339D03*
Y586339D03*
X1146160Y767299D03*
Y771099D03*
X1155282Y766806D03*
X1142203Y1300361D03*
Y1302861D03*
X1144703D03*
Y1300361D03*
X1142203Y1305361D03*
X1144703D03*
X1155503Y1312861D03*
Y1310361D03*
Y1307861D03*
X1142203D03*
Y1310361D03*
Y1312861D03*
X1144703D03*
Y1310361D03*
Y1307861D03*
X1155503Y1302861D03*
Y1300361D03*
Y1305361D03*
Y1315361D03*
X1142203D03*
X1144703D03*
X1142203Y1317861D03*
X1144703D03*
X1155503D03*
X1152359Y1372853D03*
X1154789D03*
X1141901Y1382574D03*
Y1380066D03*
X1149343Y1382111D03*
X1145855Y1380511D03*
X1148593Y1379543D03*
X1142675Y1423488D03*
X1145715Y1423555D03*
X1145755Y1426235D03*
Y1428735D03*
Y1431235D03*
Y1433735D03*
X1142715Y1426168D03*
Y1428668D03*
Y1431168D03*
Y1433668D03*
X1150718Y1462792D03*
X1153724Y1462695D03*
X1154824Y1471134D03*
X1145960Y1491934D03*
X1148460D03*
X1150960D03*
X1153460D03*
X1155960D03*
X1145960Y1489434D03*
X1148460D03*
X1150960D03*
X1153460D03*
X1155960D03*
X1143460D03*
Y1491934D03*
X1153545Y1534952D03*
X1151045D03*
X1148545D03*
X1146045D03*
X1143545D03*
X1153545Y1537452D03*
X1151045D03*
X1148545D03*
X1146045D03*
X1143545D03*
X1151045Y1544952D03*
X1148545D03*
X1146045D03*
X1143545D03*
X1153545D03*
X1143545Y1542452D03*
X1146045D03*
X1148545D03*
X1151045D03*
X1153545D03*
Y1539952D03*
X1151045D03*
X1148545D03*
X1146045D03*
X1143545D03*
X1155253Y1559176D03*
X1147814Y1562823D03*
X1154336Y1555979D03*
X1149467Y1568988D03*
X1142917Y1583314D03*
Y1586714D03*
X1155180Y1655534D03*
X1146501Y1655608D03*
Y1652208D03*
X1158343Y1658514D03*
X1152198Y1669629D03*
X1151985Y1666685D03*
X1151707Y1663655D03*
X1152114Y1672517D03*
X1154500Y1677000D03*
X1142033Y1682412D03*
X1152211Y1682373D03*
X1162086Y76509D03*
X1162144Y487630D03*
X1158764Y489516D03*
X1162067Y570050D03*
X1166131Y580602D03*
X1157038Y583298D03*
Y586298D03*
X1166026Y669006D03*
X1159718Y766870D03*
X1158003Y1307861D03*
Y1310361D03*
Y1312861D03*
Y1300361D03*
Y1302861D03*
Y1305361D03*
X1160503Y1302861D03*
Y1300361D03*
Y1305361D03*
Y1307861D03*
Y1310361D03*
Y1312861D03*
X1158003Y1315361D03*
Y1317861D03*
X1160503D03*
Y1315361D03*
X1168039Y1368999D03*
Y1371540D03*
X1157219Y1372853D03*
X1158059Y1367018D03*
Y1369918D03*
X1164249Y1373158D03*
X1169532Y1379914D03*
X1164249Y1376058D03*
X1159983Y1376288D03*
X1162049Y1374558D03*
X1164249Y1378958D03*
X1159983Y1379188D03*
X1162149Y1377558D03*
X1160163Y1445627D03*
X1163422Y1445000D03*
X1166350Y1454234D03*
X1160750Y1463250D03*
X1164300Y1463300D03*
X1159283Y1471132D03*
X1158460Y1491934D03*
Y1489434D03*
X1169061Y1543800D03*
X1170061Y1551040D03*
X1163485Y1546195D03*
X1161492Y1551175D03*
X1164528Y1565578D03*
X1170404Y1556331D03*
Y1559731D03*
X1166873Y1561431D03*
X1157255Y1556000D03*
X1170539Y1595621D03*
X1168023Y1586251D03*
X1170539Y1588751D03*
X1168023D03*
X1170539Y1586251D03*
Y1583751D03*
Y1600621D03*
Y1598121D03*
X1170339Y1603121D03*
X1165806Y1658934D03*
X1159688Y1665427D03*
X1169098Y1666278D03*
X1159703Y1673000D03*
X1159500Y1679000D03*
Y1682500D03*
X1177404Y11689D03*
Y8289D03*
X1184194Y57015D03*
Y61515D03*
X1185913Y93634D03*
X1174031Y403519D03*
X1181000Y402500D03*
X1175181Y447841D03*
Y442341D03*
X1185952Y444202D03*
Y436202D03*
X1178340Y447734D03*
Y442234D03*
X1176000Y436500D03*
X1180000Y436000D03*
X1175181Y458841D03*
Y464341D03*
Y453341D03*
X1185952Y452202D03*
X1178340Y458734D03*
X1178254Y453142D03*
X1178340Y461615D03*
X1175181Y469841D03*
X1186040Y481691D03*
X1178340Y467165D03*
X1175181Y481691D03*
X1182950Y577030D03*
X1178000Y572602D03*
X1182594Y587759D03*
X1178000Y592673D03*
X1183811Y640682D03*
X1182256Y632368D03*
X1182713Y733815D03*
X1175860Y767299D03*
Y771099D03*
X1184960Y766870D03*
X1172603Y1302861D03*
Y1300361D03*
Y1305361D03*
Y1307861D03*
Y1310361D03*
Y1312861D03*
X1175103Y1300361D03*
Y1302861D03*
X1177603D03*
Y1300361D03*
X1175103Y1305361D03*
X1177603D03*
X1175103Y1307861D03*
Y1310361D03*
Y1312861D03*
X1177603D03*
Y1310361D03*
Y1307861D03*
X1175103Y1315361D03*
X1177603D03*
X1172603Y1317861D03*
Y1315361D03*
X1175103Y1317861D03*
X1177603D03*
X1185259Y1372853D03*
X1174801Y1382574D03*
Y1380066D03*
X1182243Y1382111D03*
X1178755Y1380511D03*
X1181493Y1379543D03*
X1171812Y1376389D03*
X1184900Y1428500D03*
X1183000Y1422900D03*
X1184175Y1435600D03*
X1176500Y1457071D03*
X1180200Y1457100D03*
X1178039Y1595621D03*
X1175539D03*
X1173039D03*
X1180923Y1588751D03*
Y1586251D03*
X1173039Y1588751D03*
X1175539D03*
X1178039D03*
Y1586251D03*
X1175539D03*
X1173039D03*
X1178039Y1583751D03*
X1175539D03*
X1173039D03*
X1178039Y1600621D03*
X1175539D03*
X1173039D03*
X1178039Y1598121D03*
X1175539D03*
X1173039D03*
X1175339Y1603121D03*
X1172839D03*
X1177839D03*
X1184362Y1670254D03*
X1181385Y1670312D03*
X1175726Y1686726D03*
X1195488Y93550D03*
X1190587Y99694D03*
X1199756Y128748D03*
X1189727Y164987D03*
Y160987D03*
X1200037Y177187D03*
X1200012Y181187D03*
X1186821Y185430D03*
Y181930D03*
X1195767Y460202D03*
Y470392D03*
Y465272D03*
X1193040Y481691D03*
X1191087Y573809D03*
X1199370Y578154D03*
X1195236Y581407D03*
X1188267Y571807D03*
X1199392Y590500D03*
X1195336Y586606D03*
X1200923Y601734D03*
Y606134D03*
X1199539Y638492D03*
X1197039D03*
X1194539D03*
X1192039D03*
X1195108Y668148D03*
X1198456Y668138D03*
X1190903Y1307861D03*
Y1310361D03*
Y1312861D03*
X1188403D03*
Y1310361D03*
Y1307861D03*
Y1302861D03*
Y1300361D03*
Y1305361D03*
X1190903Y1300361D03*
Y1302861D03*
X1193403D03*
Y1300361D03*
X1190903Y1305361D03*
X1193403D03*
Y1307861D03*
Y1310361D03*
Y1312861D03*
X1190903Y1315361D03*
X1188403D03*
Y1317861D03*
X1190903D03*
X1193403D03*
Y1315361D03*
X1200839Y1368999D03*
Y1371540D03*
X1190119Y1372853D03*
X1191049Y1367188D03*
Y1370088D03*
X1187689Y1372853D03*
X1197149Y1373158D03*
X1192883Y1379188D03*
X1195049Y1377558D03*
X1197149Y1378958D03*
X1192883Y1376288D03*
X1194949Y1374558D03*
X1197149Y1376058D03*
X1194296Y1396500D03*
X1194000Y1401000D03*
Y1414500D03*
X1203242Y1417440D03*
X1194366Y1405500D03*
X1193929Y1410000D03*
X1202548Y1407453D03*
X1202857Y1412454D03*
X1191000Y1425900D03*
X1198800Y1421500D03*
X1202411Y1427410D03*
X1194000Y1424000D03*
X1203117Y1422452D03*
X1202475Y1432468D03*
X1188000Y1419800D03*
X1194000Y1437500D03*
X1203040D03*
X1194000Y1442500D03*
Y1447500D03*
X1188960Y1609135D03*
X1186455Y1608390D03*
Y1602590D03*
Y1605490D03*
X1190174Y1615418D03*
X1190616Y1670641D03*
X1190314Y1661630D03*
X1199299Y1675517D03*
X1197746Y1680914D03*
X1199272Y1683025D03*
X1189263Y1682551D03*
X1190830Y1675710D03*
X1197612Y1703334D03*
X1192612D03*
X1199612Y1691366D03*
X1189462Y1700334D03*
X1194478Y1699936D03*
X1189407Y1717518D03*
X1205929Y86872D03*
X1206580Y94846D03*
X1208431Y133866D03*
Y128748D03*
X1214094Y258633D03*
Y269008D03*
Y282948D03*
Y287948D03*
X1205625Y313758D03*
X1210698Y313671D03*
X1207447Y341381D03*
X1202508Y341424D03*
X1212700Y475712D03*
X1206590Y481403D03*
X1203269Y481237D03*
X1212051Y559827D03*
X1208733Y585986D03*
X1205900Y582443D03*
X1206191Y588400D03*
X1205679Y594148D03*
X1209796Y668115D03*
X1204334Y668138D03*
X1205630Y766600D03*
X1207903Y1300361D03*
Y1302861D03*
X1210403D03*
Y1300361D03*
X1207903Y1305361D03*
X1210403D03*
X1207903Y1307861D03*
Y1310361D03*
Y1312861D03*
X1210403D03*
Y1310361D03*
Y1307861D03*
X1205403Y1302861D03*
Y1300361D03*
Y1305361D03*
Y1307861D03*
Y1310361D03*
Y1312861D03*
X1207903Y1315361D03*
X1210403D03*
X1205403Y1317861D03*
Y1315361D03*
X1207903Y1317861D03*
X1210403D03*
X1202332Y1379914D03*
X1207601Y1380066D03*
X1215043Y1382111D03*
X1211555Y1380511D03*
X1214293Y1379543D03*
X1207601Y1382574D03*
X1204612Y1376389D03*
X1211000Y1392125D03*
X1211075Y1395200D03*
X1210100Y1436500D03*
X1213000Y1435000D03*
X1210400Y1440000D03*
X1214900Y1439800D03*
X1202697Y1673059D03*
X1205604Y1685400D03*
Y1682200D03*
Y1679000D03*
Y1675800D03*
X1212954Y1703343D03*
X1214954Y1691375D03*
X1204804Y1700343D03*
X1207954Y1703343D03*
X1207770Y1706861D03*
Y1720861D03*
X1205638Y1732766D03*
X1227803Y94210D03*
X1221411Y134230D03*
X1221512Y128239D03*
X1220931Y131307D03*
X1222094Y258633D03*
X1230094D03*
Y269008D03*
X1222094D03*
X1230094Y287948D03*
Y282948D03*
X1222094D03*
Y297066D03*
Y292066D03*
Y314216D03*
Y305216D03*
X1226094Y314216D03*
X1218430Y421012D03*
X1219325Y438151D03*
X1216300Y475682D03*
X1228372Y688501D03*
X1221203Y1312861D03*
Y1310361D03*
Y1307861D03*
X1223703D03*
Y1310361D03*
Y1312861D03*
Y1300361D03*
Y1302861D03*
Y1305361D03*
X1221203Y1302861D03*
Y1300361D03*
Y1305361D03*
Y1315361D03*
X1223703D03*
Y1317861D03*
X1221203D03*
X1222919Y1372853D03*
X1220489D03*
X1223889Y1367188D03*
Y1370088D03*
X1218059Y1372853D03*
X1229949Y1373158D03*
X1228800Y1391300D03*
X1225683Y1379188D03*
X1227849Y1377558D03*
X1225683Y1376288D03*
X1227749Y1374558D03*
X1229949Y1378958D03*
Y1376058D03*
X1227000Y1401300D03*
X1219650Y1392050D03*
X1219500Y1398900D03*
X1224200Y1393500D03*
X1227000Y1404500D03*
X1219500Y1436000D03*
X1221837Y1438800D03*
X1229661Y1442000D03*
X1226200Y1444300D03*
X1222700Y1446300D03*
X1220200Y1449100D03*
X1219738Y1713861D03*
Y1708861D03*
X1216738Y1717011D03*
X1219738Y1722861D03*
Y1727861D03*
X1216738Y1731011D03*
X1238769Y75320D03*
X1233668Y132739D03*
Y128239D03*
X1247834Y159844D03*
X1238094Y258633D03*
X1246094Y269008D03*
X1238094D03*
X1234000Y385500D03*
X1233468Y419742D03*
X1242429Y431255D03*
Y427255D03*
Y435255D03*
X1236879Y449755D03*
X1242429Y439255D03*
X1232081Y460580D03*
X1242692Y483435D03*
X1236100Y773844D03*
X1233084Y772582D03*
X1235215Y777213D03*
X1231397Y769667D03*
X1243207Y779428D03*
X1241057Y782278D03*
X1244986Y787578D03*
X1244127Y784598D03*
X1238257Y779728D03*
X1243294Y1269197D03*
Y1266697D03*
Y1261697D03*
Y1264197D03*
X1243308Y1271754D03*
X1238830Y1322853D03*
Y1325394D03*
X1240323Y1333768D03*
X1245592Y1333920D03*
Y1336428D03*
X1242603Y1330243D03*
X1239800Y1389500D03*
X1235400Y1391200D03*
X1238500Y1400900D03*
X1234900Y1404400D03*
X1233700Y1395600D03*
X1238200Y1395500D03*
X1244300Y1403500D03*
X1235679Y1418908D03*
X1239242Y1418462D03*
X1238731Y1422362D03*
X1239550Y1437050D03*
X1249152Y72895D03*
X1253152Y84895D03*
X1255661Y90470D03*
X1253152Y95525D03*
X1259472Y92864D03*
X1252693Y124739D03*
X1249431Y137739D03*
X1249065Y241594D03*
Y236594D03*
Y251594D03*
Y246594D03*
X1246094Y258633D03*
X1254094D03*
X1262094Y269008D03*
X1254094D03*
X1262094Y282948D03*
X1254094D03*
X1262094Y287948D03*
X1250285Y303307D03*
X1259659Y389456D03*
X1260107Y399125D03*
X1260227Y415128D03*
X1256137Y459182D03*
Y453872D03*
X1245752Y470733D03*
X1250975Y474945D03*
X1248130Y783354D03*
X1251177Y784488D03*
X1254981Y787578D03*
X1256447Y798828D03*
X1259297Y798784D03*
X1251177Y794878D03*
X1257527Y808938D03*
X1260427Y809008D03*
X1259194Y1251697D03*
Y1246697D03*
Y1254197D03*
Y1249197D03*
X1248294Y1259197D03*
Y1256697D03*
X1245794Y1259197D03*
X1259194Y1269215D03*
Y1261715D03*
Y1264215D03*
Y1266715D03*
X1245894Y1269215D03*
X1248394D03*
X1245894Y1261715D03*
Y1264215D03*
Y1266715D03*
X1248394D03*
Y1264215D03*
Y1261715D03*
X1259194Y1256697D03*
Y1259197D03*
X1248308Y1271754D03*
X1245808D03*
X1259108D03*
X1256050Y1326707D03*
X1258480D03*
X1253034Y1335965D03*
X1249546Y1334365D03*
X1252284Y1333397D03*
X1249600Y1403425D03*
X1257594Y1417000D03*
X1253100Y1413500D03*
X1256224Y1430075D03*
X1256600Y1434500D03*
X1275981Y85114D03*
X1263472Y92864D03*
X1269146Y121022D03*
X1263146D03*
X1267037Y180565D03*
Y175030D03*
X1268941Y206017D03*
X1269360Y219632D03*
X1261969Y219505D03*
X1262094Y258633D03*
X1270094D03*
Y269008D03*
Y282948D03*
Y292066D03*
X1268174Y395125D03*
X1275585Y393597D03*
X1269840Y411128D03*
X1270483Y433148D03*
Y435648D03*
X1265227Y454372D03*
X1262457Y798814D03*
X1266677Y802988D03*
X1266568Y809078D03*
X1275177Y808963D03*
X1263647Y809118D03*
X1271177Y808963D03*
X1261694Y1251697D03*
X1264194D03*
Y1246697D03*
X1261694D03*
Y1254197D03*
X1264194D03*
X1261694Y1249197D03*
X1264194D03*
X1261694Y1269215D03*
Y1266715D03*
Y1264215D03*
Y1261715D03*
X1264194Y1269197D03*
Y1256697D03*
Y1259197D03*
Y1261697D03*
X1261694Y1256697D03*
Y1259197D03*
X1264194Y1264197D03*
Y1266697D03*
X1264108Y1271754D03*
X1261608D03*
X1271726Y1322825D03*
Y1325366D03*
X1260910Y1326707D03*
X1262050Y1320878D03*
Y1323778D03*
X1267940Y1327012D03*
X1265740Y1328412D03*
X1273219Y1333740D03*
X1275499Y1330215D03*
X1267940Y1332812D03*
Y1329912D03*
X1265840Y1331412D03*
X1263674Y1330142D03*
Y1333042D03*
X1271042Y1418748D03*
X1266996Y1423617D03*
X1262310Y1428303D03*
X1275195Y1552250D03*
X1275170Y1579519D03*
X1269310Y1583170D03*
X1287486Y134165D03*
X1278050Y152912D03*
X1278137Y166051D03*
X1278211Y161030D03*
Y156030D03*
X1278137Y180565D03*
Y176051D03*
Y171551D03*
Y184987D03*
X1279447Y213292D03*
X1286094Y258633D03*
X1278094D03*
Y269008D03*
X1286094D03*
X1278094Y282948D03*
X1286094D03*
X1278094Y287948D03*
X1286094Y292066D03*
X1290127Y401125D03*
Y410635D03*
X1289352Y418550D03*
Y421950D03*
X1281190Y1254112D03*
X1276190D03*
X1278690D03*
X1281190Y1249112D03*
Y1251612D03*
X1276190D03*
X1278690D03*
X1276190Y1249112D03*
X1278690D03*
X1281190Y1246612D03*
X1276190D03*
X1278690D03*
X1276190Y1269112D03*
Y1266612D03*
X1281190Y1259112D03*
Y1256612D03*
X1276190D03*
Y1259112D03*
Y1261612D03*
Y1264112D03*
X1278690Y1256612D03*
Y1259112D03*
X1278790Y1269130D03*
X1281290D03*
X1278790Y1261630D03*
Y1264130D03*
Y1266630D03*
X1281290D03*
Y1264130D03*
Y1261630D03*
X1281204Y1271669D03*
X1278704D03*
X1276204D03*
X1288946Y1326679D03*
X1278488Y1333892D03*
X1285930Y1335937D03*
X1282442Y1334337D03*
X1285180Y1333369D03*
X1278488Y1336400D03*
X1287600Y1423100D03*
Y1427600D03*
X1276500Y1432000D03*
X1279525D03*
X1287700Y1431700D03*
X1287961Y1542469D03*
X1287372Y1552845D03*
X1287647Y1545220D03*
Y1549120D03*
X1277017Y1544953D03*
Y1547453D03*
Y1549953D03*
X1281470Y1552845D03*
X1281347Y1549120D03*
Y1545220D03*
X1284497Y1549120D03*
Y1545220D03*
X1284510Y1554436D03*
X1277702D03*
X1289919Y1582295D03*
Y1574795D03*
Y1579795D03*
Y1577295D03*
X1287419Y1582295D03*
Y1579795D03*
X1284919D03*
Y1582295D03*
X1282419D03*
Y1579795D03*
X1299196Y76209D03*
X1305685Y74748D03*
X1296200Y66911D03*
X1305091Y123680D03*
Y127830D03*
Y131750D03*
X1301582Y166051D03*
X1301743Y162055D03*
X1301582Y171551D03*
Y184051D03*
X1302094Y258633D03*
X1294094D03*
Y269008D03*
X1302094D03*
X1294094Y287948D03*
Y282948D03*
X1302094D03*
Y292066D03*
X1302069Y303184D03*
X1299026Y389355D03*
X1302226D03*
X1295519Y389561D03*
X1304347Y523237D03*
X1302160Y524916D03*
X1304566Y525743D03*
X1301642Y537299D03*
X1293581Y542716D03*
X1294938Y561331D03*
X1300400Y599413D03*
X1297400D03*
X1298000Y657500D03*
X1303250Y655149D03*
X1295000Y655200D03*
X1292297Y657206D03*
X1302500Y664500D03*
X1305100Y662100D03*
X1301900Y660699D03*
X1294590Y1254112D03*
X1297090D03*
X1292090D03*
Y1249112D03*
X1294590D03*
X1297090D03*
X1292090Y1251612D03*
X1294590D03*
X1297090D03*
X1292090Y1246612D03*
X1297090D03*
X1294590D03*
X1292090Y1269130D03*
X1294590D03*
X1292090Y1261630D03*
Y1264130D03*
Y1266630D03*
X1294590D03*
Y1264130D03*
Y1261630D03*
X1297090Y1269112D03*
Y1256612D03*
Y1259112D03*
Y1261612D03*
X1294590Y1256612D03*
Y1259112D03*
X1297090Y1264112D03*
Y1266612D03*
X1292090Y1256612D03*
Y1259112D03*
X1297004Y1271669D03*
X1292004D03*
X1294504D03*
X1304630Y1322768D03*
Y1325309D03*
X1293806Y1326679D03*
X1291376D03*
X1294956Y1320934D03*
Y1323834D03*
X1300836Y1326984D03*
X1298636Y1328384D03*
X1296570Y1330114D03*
Y1333014D03*
X1298736Y1331384D03*
X1300836Y1329884D03*
Y1332784D03*
X1296000Y1427700D03*
X1301900D03*
X1295700Y1421800D03*
X1300800D03*
X1291700Y1431700D03*
X1302390Y1530430D03*
X1297490Y1526910D03*
X1297620Y1529534D03*
X1291897Y1545076D03*
X1290461Y1542469D03*
X1291897Y1547576D03*
X1302915Y1563596D03*
X1298466Y1556331D03*
Y1559731D03*
X1292419Y1582295D03*
Y1579795D03*
Y1574795D03*
Y1577295D03*
X1294919D03*
Y1574795D03*
X1294387Y1571682D03*
X1291887D03*
X1301789Y1574795D03*
X1304289D03*
X1301789Y1577295D03*
X1304289D03*
Y1579795D03*
X1301789D03*
X1304289Y1582295D03*
X1301789D03*
X1299289Y1574795D03*
Y1582295D03*
Y1579795D03*
Y1577295D03*
X1295877Y1581199D03*
X1298382Y1584844D03*
X1295877Y1584099D03*
X1293459Y1584844D03*
X1320020Y66979D03*
X1308110Y66911D03*
X1307857Y103353D03*
X1313951Y104739D03*
X1311045D03*
X1313011Y135820D03*
Y139845D03*
X1306300Y203917D03*
X1318094Y258633D03*
X1310094D03*
Y269008D03*
X1318094D03*
X1310094Y287948D03*
Y282948D03*
X1318094D03*
X1305426Y389355D03*
X1308926Y524111D03*
X1306815Y522726D03*
X1307117Y525897D03*
X1309870Y552788D03*
X1309776Y559831D03*
X1317266Y597213D03*
X1310544Y613100D03*
X1313544Y610100D03*
X1310544D03*
X1313544Y607100D03*
X1310544D03*
X1313544Y604100D03*
X1310544D03*
X1307544Y610100D03*
Y613100D03*
Y604100D03*
Y607100D03*
X1317266Y600213D03*
X1309166Y601713D03*
X1308776Y599181D03*
X1313544Y613100D03*
X1310544Y616100D03*
X1313544D03*
X1307544D03*
X1308800Y619200D03*
Y622200D03*
Y625200D03*
X1318300D03*
Y622200D03*
Y619200D03*
X1307700Y664600D03*
X1309600Y667700D03*
X1315657Y1199532D03*
Y1196132D03*
X1311715Y1221042D03*
X1318776Y1219566D03*
X1311594Y1251612D03*
X1309094D03*
X1311594Y1254112D03*
X1309094D03*
X1311594Y1246612D03*
X1309094D03*
X1311594Y1249112D03*
X1309094D03*
X1314094Y1246612D03*
Y1251612D03*
Y1249112D03*
Y1254112D03*
X1309090Y1269169D03*
Y1266669D03*
Y1261669D03*
Y1264169D03*
X1314194Y1269130D03*
Y1266630D03*
Y1264130D03*
Y1261630D03*
X1311694Y1269130D03*
Y1261630D03*
Y1264130D03*
Y1266630D03*
X1311594Y1259112D03*
Y1256612D03*
X1309094Y1259112D03*
Y1256612D03*
X1314094D03*
Y1259112D03*
X1309090Y1271669D03*
X1311590D03*
X1314090D03*
X1306123Y1333683D03*
X1311392Y1333835D03*
X1318834Y1335880D03*
X1315346Y1334280D03*
X1318084Y1333312D03*
X1311392Y1336343D03*
X1308403Y1330158D03*
X1308900Y1525510D03*
X1306789Y1574795D03*
Y1582295D03*
Y1579795D03*
Y1577295D03*
X1310914Y1577299D03*
X1331930Y66945D03*
X1327541Y105227D03*
X1337399Y98084D03*
X1333399D03*
X1334094Y258633D03*
X1326094D03*
Y269008D03*
X1334094D03*
Y287948D03*
X1326094Y282948D03*
X1334094D03*
X1326094Y292066D03*
X1328427Y349452D03*
X1329585Y561806D03*
X1325366Y597213D03*
Y600213D03*
X1321300Y619200D03*
Y622200D03*
Y625200D03*
X1326636Y656800D03*
X1322420Y656867D03*
X1332812Y856383D03*
X1325543Y871161D03*
X1329244D03*
X1334301Y867765D03*
X1328992Y1209788D03*
X1327029Y1206788D03*
X1331202Y1206478D03*
X1323169Y1208995D03*
X1333977Y1222158D03*
X1325137Y1210653D03*
X1324901Y1216419D03*
X1322141Y1217365D03*
X1327494Y1246612D03*
Y1251612D03*
Y1249112D03*
Y1254112D03*
X1324994Y1246612D03*
Y1251612D03*
Y1249112D03*
Y1254112D03*
X1329994Y1246612D03*
Y1251612D03*
Y1249112D03*
Y1254112D03*
X1324994Y1269130D03*
Y1261630D03*
Y1264130D03*
Y1266630D03*
X1327494Y1269130D03*
Y1266630D03*
Y1264130D03*
Y1261630D03*
Y1259112D03*
Y1256612D03*
X1324994Y1259112D03*
Y1256612D03*
X1329994Y1259112D03*
Y1256612D03*
Y1266612D03*
Y1264112D03*
Y1261612D03*
Y1269112D03*
X1327490Y1271669D03*
X1324990D03*
X1329990D03*
X1326710Y1326622D03*
X1324280D03*
X1321850D03*
X1327876Y1320934D03*
Y1323834D03*
X1333740Y1326927D03*
X1331540Y1328327D03*
X1333740Y1329827D03*
Y1332727D03*
X1331640Y1331327D03*
X1329474Y1330057D03*
Y1332957D03*
X1322539Y1411278D03*
X1322499Y1413788D03*
X1325499D03*
X1325539Y1411278D03*
Y1416446D03*
X1322539D03*
X1328539Y1411278D03*
X1328499Y1413788D03*
X1328539Y1416446D03*
X1331509Y1416486D03*
X1334509D03*
X1331509Y1408818D03*
X1334509Y1411318D03*
X1334469Y1413828D03*
X1334509Y1408818D03*
X1331469Y1413828D03*
X1331509Y1411318D03*
X1325579Y1418976D03*
X1322579D03*
X1325609Y1421496D03*
X1322609D03*
X1328579Y1418976D03*
X1328609Y1421496D03*
X1331579Y1421536D03*
X1331549Y1419016D03*
X1334579Y1421536D03*
X1334549Y1419016D03*
X1343840Y66911D03*
X1341399Y98084D03*
X1348199D03*
X1342094Y258633D03*
Y269008D03*
X1350094D03*
Y287948D03*
X1342094Y282948D03*
X1350094D03*
X1342094Y292066D03*
X1340257Y677765D03*
Y675111D03*
X1336812Y856383D03*
X1341301Y867765D03*
X1337801D03*
X1341301Y871265D03*
X1344801D03*
X1348301D03*
X1340948Y1177681D03*
X1342507Y1187848D03*
X1340948Y1181681D03*
X1349012Y1204971D03*
X1342036Y1206429D03*
Y1203029D03*
X1346063Y1217729D03*
Y1214329D03*
X1341590Y1254169D03*
Y1251669D03*
Y1249169D03*
Y1246669D03*
X1344090Y1254169D03*
Y1251669D03*
Y1249169D03*
Y1246669D03*
X1346590Y1254169D03*
Y1249169D03*
Y1251669D03*
Y1246669D03*
X1341690Y1269269D03*
Y1264269D03*
Y1266769D03*
Y1261769D03*
X1341590Y1256669D03*
Y1259169D03*
X1344190Y1269187D03*
X1346690D03*
X1344190Y1261687D03*
Y1264187D03*
Y1266687D03*
X1346690D03*
Y1264187D03*
Y1261687D03*
X1344090Y1256669D03*
Y1259169D03*
X1346590D03*
Y1256669D03*
X1341690Y1271769D03*
X1346690D03*
X1344190D03*
X1337430Y1322968D03*
Y1325509D03*
X1338923Y1333883D03*
X1344192Y1334035D03*
X1348146Y1334480D03*
X1344192Y1336543D03*
X1341203Y1330358D03*
X1340556Y1383674D03*
Y1386674D03*
X1337556D03*
Y1383674D03*
X1346556Y1386674D03*
Y1383674D03*
X1343556Y1386674D03*
Y1383674D03*
X1349556D03*
Y1386674D03*
X1337555Y1389658D03*
X1343712Y1389804D03*
X1348712D03*
X1346212D03*
X1341212D03*
X1348823Y1409626D03*
X1348853Y1413866D03*
X1346323Y1409626D03*
X1346353Y1413866D03*
X1343823Y1409626D03*
X1343853Y1413866D03*
X1346509Y1416486D03*
X1349509D03*
X1343509D03*
X1341323Y1409626D03*
X1341353Y1413866D03*
X1337509Y1416486D03*
Y1411318D03*
X1337469Y1413828D03*
X1337509Y1408818D03*
X1340509Y1416486D03*
X1349579Y1421536D03*
X1349549Y1419016D03*
X1346579Y1421536D03*
X1346549Y1419016D03*
X1343549D03*
X1343579Y1421536D03*
X1337579D03*
X1337549Y1419016D03*
X1340579Y1421536D03*
X1340549Y1419016D03*
X1355750Y66886D03*
X1360109Y98050D03*
X1352199D03*
X1364369Y120380D03*
X1358094Y258633D03*
X1350094D03*
X1358094Y269008D03*
X1366094D03*
Y287948D03*
X1358094Y282948D03*
X1366094D03*
X1358094Y292066D03*
X1363857Y626579D03*
X1361427D03*
X1354397Y623374D03*
Y626274D03*
X1356597Y624874D03*
X1358663Y623144D03*
X1356497Y621874D03*
X1354397Y620474D03*
X1358663Y620244D03*
X1360964Y629514D03*
Y632414D03*
X1358461Y684151D03*
Y686651D03*
X1360961Y684073D03*
Y686573D03*
X1363461D03*
Y684073D03*
X1363435Y681573D03*
X1358435D03*
X1360935D03*
X1358461Y694151D03*
X1363461D03*
X1360961D03*
X1358461Y689151D03*
Y691651D03*
X1363461Y696651D03*
X1360961D03*
X1363461Y699151D03*
X1360961Y691573D03*
X1363461D03*
X1360961Y689073D03*
X1363461D03*
X1362523Y1015473D03*
Y1022559D03*
Y1019016D03*
X1355222Y1200561D03*
X1361285Y1206718D03*
X1355641Y1210674D03*
X1362810Y1211071D03*
X1357490Y1254169D03*
Y1249169D03*
Y1251669D03*
Y1246669D03*
X1359990Y1254169D03*
X1362490D03*
X1359990Y1249169D03*
X1362490D03*
X1359990Y1251669D03*
X1362490D03*
Y1246669D03*
X1359990D03*
Y1269187D03*
Y1266687D03*
Y1264187D03*
Y1261687D03*
X1357490Y1269187D03*
Y1261687D03*
Y1264187D03*
Y1266687D03*
Y1256669D03*
Y1259169D03*
X1362490Y1269269D03*
Y1261769D03*
Y1266769D03*
Y1264269D03*
Y1256669D03*
Y1259169D03*
X1359990Y1256669D03*
Y1259169D03*
X1357490Y1271769D03*
X1362490D03*
X1359990D03*
X1359510Y1326822D03*
X1360724Y1321184D03*
Y1324084D03*
X1357080Y1326822D03*
X1354650D03*
X1364340Y1328527D03*
X1351634Y1336080D03*
X1350884Y1333512D03*
X1364440Y1337527D03*
Y1331527D03*
Y1334527D03*
X1362274Y1330257D03*
Y1333157D03*
Y1336057D03*
X1352226Y1386804D03*
Y1383804D03*
X1352225Y1389788D03*
X1358509Y1416486D03*
Y1413818D03*
Y1411318D03*
Y1408818D03*
X1352509Y1416486D03*
Y1411318D03*
Y1413818D03*
Y1408818D03*
X1355509Y1416486D03*
Y1411318D03*
Y1413818D03*
Y1408818D03*
X1352579Y1421536D03*
X1352549Y1419016D03*
X1355549D03*
X1367950Y66886D03*
X1377682Y87587D03*
X1368109Y98000D03*
X1366094Y258633D03*
X1373862Y485552D03*
Y511052D03*
X1381457Y511050D03*
X1376757Y619497D03*
X1369303Y617321D03*
X1372791Y618921D03*
X1370053Y619889D03*
X1376745Y616858D03*
X1379734Y623043D03*
X1366287Y626579D03*
X1376761Y686573D03*
Y684073D03*
X1374261D03*
Y686573D03*
X1374245Y681573D03*
X1376745D03*
X1376761Y694151D03*
X1374261D03*
X1376761Y696651D03*
X1374261D03*
X1376761Y699151D03*
X1374261D03*
X1376761Y701651D03*
X1374261D03*
X1376761Y691573D03*
Y689073D03*
X1374261Y691573D03*
Y689073D03*
X1376761Y706651D03*
Y704151D03*
X1374261Y706651D03*
Y704151D03*
X1377483Y1015473D03*
X1370003D03*
X1377483Y1022559D03*
Y1019016D03*
X1370003Y1022559D03*
Y1019016D03*
X1370685Y1223032D03*
Y1226432D03*
X1374476Y1266143D03*
X1376976D03*
X1379476D03*
X1374476Y1268643D03*
X1376976D03*
X1379476D03*
X1374476Y1273643D03*
Y1271143D03*
X1374576Y1283743D03*
Y1281243D03*
X1374476Y1276143D03*
Y1278643D03*
X1376976Y1273643D03*
Y1271143D03*
X1379476Y1273643D03*
Y1271143D03*
X1377076Y1281161D03*
Y1283661D03*
X1379576D03*
Y1281161D03*
X1376976Y1276143D03*
Y1278643D03*
X1379476D03*
Y1276143D03*
X1379576Y1288661D03*
X1377076Y1286161D03*
X1379576D03*
X1377076Y1288661D03*
X1379576Y1291243D03*
X1377076D03*
X1374576Y1288743D03*
Y1286243D03*
Y1291243D03*
X1370012Y1342299D03*
X1371505Y1353214D03*
X1376774Y1353366D03*
X1370012Y1344840D03*
X1376774Y1355874D03*
X1373785Y1349689D03*
X1382045Y1700038D03*
X1379804Y1733118D03*
X1383715Y236594D03*
Y241594D03*
X1381457Y485550D03*
X1382014Y619518D03*
X1383507Y627892D03*
Y630433D03*
X1387097Y656274D03*
X1389297Y657774D03*
X1391363Y656044D03*
X1387097Y653374D03*
X1389197Y654774D03*
X1391363Y653144D03*
X1394127Y659479D03*
X1387097Y659174D03*
X1393664Y662384D03*
Y665284D03*
X1393343Y716971D03*
X1390807Y717053D03*
X1390817Y714471D03*
X1393317D03*
X1393343Y719471D03*
X1390807Y719553D03*
X1393367Y727023D03*
Y729523D03*
X1393343Y724471D03*
Y721971D03*
X1390807Y722053D03*
Y724553D03*
X1390853Y727053D03*
X1391460Y1009764D03*
Y1006024D03*
Y1013504D03*
Y1020985D03*
Y1024725D03*
Y1028465D03*
Y1017244D03*
X1390376Y1268643D03*
X1392876D03*
Y1283661D03*
Y1281161D03*
X1390376D03*
Y1283661D03*
Y1273643D03*
Y1271143D03*
Y1276143D03*
Y1278643D03*
X1392876Y1273643D03*
Y1271143D03*
Y1276143D03*
Y1278643D03*
Y1288661D03*
Y1286161D03*
X1390376Y1288661D03*
Y1286161D03*
Y1291243D03*
X1392876D03*
X1393306Y1340515D03*
Y1343415D03*
X1384216Y1355411D03*
X1380728Y1353811D03*
X1383466Y1352843D03*
X1392092Y1346153D03*
X1389662D03*
X1387232D03*
X1385068Y1664907D03*
X1390738Y1664938D03*
X1392068Y1676875D03*
X1381918D03*
X1391750Y1697747D03*
X1382045Y1704038D03*
X1390045Y1712038D03*
X1390179Y1733118D03*
X1404917Y116911D03*
X1395302Y251136D03*
Y256136D03*
X1411000Y460362D03*
X1406500Y458362D03*
X1400500Y458377D03*
X1409445Y652266D03*
X1402003Y650221D03*
X1405491Y651821D03*
X1402753Y652789D03*
X1409445Y649758D03*
X1398987Y659479D03*
X1396557D03*
X1409143Y716971D03*
X1395843D03*
X1406643D03*
X1409127Y714471D03*
X1395817D03*
X1406627D03*
X1409143Y719471D03*
X1395843D03*
X1406643D03*
X1395867Y732023D03*
Y727023D03*
Y729523D03*
X1406667Y727023D03*
X1409167Y732023D03*
Y729523D03*
X1406667Y732023D03*
Y729523D03*
X1409167Y727023D03*
X1409143Y724471D03*
Y721971D03*
X1395843Y724471D03*
Y721971D03*
X1406643Y724471D03*
Y721971D03*
X1409167Y739523D03*
Y734523D03*
Y737023D03*
X1406667Y734523D03*
Y737023D03*
Y739523D03*
X1401015Y1014744D03*
X1399953Y1005799D03*
X1403693D03*
X1407433D03*
X1401015Y1023012D03*
Y1018878D03*
X1407433Y1032430D03*
X1403693D03*
X1395060Y1032205D03*
X1399953Y1032430D03*
X1395376Y1268643D03*
Y1273643D03*
Y1271143D03*
Y1281243D03*
Y1283743D03*
Y1276143D03*
Y1278643D03*
Y1288743D03*
Y1286243D03*
Y1291243D03*
X1399122Y1352258D03*
X1394856Y1352488D03*
X1399122Y1346458D03*
Y1349358D03*
X1396922Y1347858D03*
X1394856Y1349588D03*
X1397022Y1350858D03*
X1405811Y1430021D03*
X1409532Y1552845D03*
X1409409Y1549120D03*
Y1545220D03*
X1403257Y1552250D03*
X1405079Y1549953D03*
Y1544953D03*
Y1547453D03*
X1405764Y1554436D03*
X1403232Y1579519D03*
X1397030Y1594060D03*
X1409286Y1605796D03*
X1406666Y1616332D03*
X1400029Y1615796D03*
X1406447Y1619572D03*
X1396783Y1617170D03*
X1408023Y1638705D03*
X1398058Y1628651D03*
X1408208D03*
X1406814Y1652439D03*
X1399599Y1657583D03*
X1398883Y1680341D03*
X1410750Y244583D03*
X1417000Y460362D03*
X1419335Y533958D03*
X1414714Y653008D03*
X1412434Y655943D03*
X1416207Y663333D03*
Y660792D03*
X1421797Y687354D03*
X1423963Y685724D03*
X1419697Y685954D03*
X1421897Y690354D03*
X1423963Y688624D03*
X1419697Y688854D03*
Y691754D03*
X1423417Y747051D03*
X1423407Y757133D03*
Y749633D03*
Y752133D03*
Y754633D03*
X1416301Y970340D03*
Y977840D03*
Y985340D03*
X1414576Y989765D03*
X1414501Y993765D03*
Y997765D03*
X1410858Y1014744D03*
X1418653Y1005799D03*
X1414913D03*
X1411173D03*
X1414501Y1001765D03*
X1419716Y1014744D03*
X1422394Y1005799D03*
X1410858Y1023012D03*
X1419716D03*
X1410858Y1018878D03*
X1419716D03*
X1422394Y1032430D03*
X1419026Y1038765D03*
Y1042765D03*
X1414913Y1032430D03*
X1418653D03*
X1411173D03*
X1417301Y1051540D03*
X1418982Y1175144D03*
X1414165Y1289564D03*
X1414172Y1286188D03*
X1415434Y1552845D03*
X1415709Y1545220D03*
Y1549120D03*
X1418523Y1542469D03*
X1419959Y1545076D03*
Y1547576D03*
X1416023Y1542469D03*
X1412559Y1549120D03*
Y1545220D03*
X1412572Y1554436D03*
X1417981Y1568680D03*
X1423531Y1574795D03*
Y1582295D03*
Y1579795D03*
Y1577295D03*
X1424621Y1571911D03*
Y1569411D03*
X1416862Y1582871D03*
X1419811Y1599084D03*
X1416709Y1592819D03*
X1413836Y1586944D03*
X1412467Y1602234D03*
X1419914Y1602777D03*
X1418000Y1607500D03*
X1422154Y1626270D03*
X1423722Y1616780D03*
X1419622Y1616000D03*
X1422266Y1628947D03*
X1411113Y1637767D03*
X1421890Y1635500D03*
X1418755Y1654999D03*
X1410315Y1646967D03*
X1424315D03*
X1434262Y52892D03*
X1438262D03*
X1431262Y61392D03*
X1439049Y107443D03*
X1429169Y107313D03*
X1431300Y538800D03*
X1435400Y536200D03*
X1431400Y533400D03*
X1435400Y530800D03*
X1434603Y682801D03*
X1438091Y684401D03*
X1435353Y685369D03*
X1431617Y692359D03*
X1429187D03*
X1426757D03*
X1426264Y694954D03*
Y697854D03*
X1439227Y747051D03*
X1425917D03*
X1428417D03*
X1428407Y762133D03*
Y759633D03*
X1425907D03*
X1439257Y762133D03*
Y759633D03*
X1425943Y757051D03*
X1428443D03*
X1425943Y749551D03*
Y752051D03*
Y754551D03*
X1428443D03*
Y752051D03*
Y749551D03*
X1439243Y757051D03*
Y749551D03*
Y752051D03*
Y754551D03*
X1439257Y764633D03*
Y769633D03*
Y767133D03*
X1429952Y1014744D03*
X1433614Y1005799D03*
X1426134D03*
X1429874D03*
X1429952Y1023012D03*
Y1018878D03*
X1426134Y1032430D03*
X1433614D03*
X1429874D03*
X1434235Y1550240D03*
X1433235Y1543800D03*
X1430735D03*
X1431735Y1550240D03*
X1434578Y1556331D03*
Y1559731D03*
X1430213Y1553652D03*
X1427713D03*
X1426031Y1582295D03*
X1431031Y1574795D03*
Y1577295D03*
X1426031Y1579795D03*
Y1577295D03*
Y1574795D03*
X1428531D03*
Y1577295D03*
Y1579795D03*
Y1582295D03*
X1430431Y1570595D03*
X1427931D03*
X1437901Y1579795D03*
Y1577295D03*
Y1574795D03*
Y1582295D03*
X1435401D03*
Y1579795D03*
Y1577295D03*
Y1574795D03*
X1431989Y1581199D03*
X1434494Y1584844D03*
X1431989Y1584099D03*
X1429571Y1584844D03*
X1430244Y1609966D03*
X1438565Y1612583D03*
X1434316Y1616909D03*
X1430238Y1617137D03*
X1437594Y1616845D03*
X1426899Y1616990D03*
X1429072Y1643655D03*
X1433911Y1649037D03*
X1433618Y1659331D03*
X1433157Y1651977D03*
X1436311Y1665948D03*
X1438078Y1669992D03*
X1439316Y1675080D03*
X1435904Y1694335D03*
X1443049Y107443D03*
X1448549Y114643D03*
X1446040Y120218D03*
X1452040Y113018D03*
X1440871Y152166D03*
X1454769Y163842D03*
X1444769D03*
Y174217D03*
X1453974Y174414D03*
X1449769Y174217D03*
X1439769D03*
Y182217D03*
X1449769D03*
X1456500Y457000D03*
X1441053Y560535D03*
X1441898Y576755D03*
X1452708Y610954D03*
Y607954D03*
X1449708Y610954D03*
X1446708D03*
Y607954D03*
X1449708D03*
X1440708Y610954D03*
X1443708D03*
X1440708Y607954D03*
X1443708D03*
X1452708Y613954D03*
X1446708Y616954D03*
Y619954D03*
X1440708D03*
Y616954D03*
X1443708D03*
Y619954D03*
X1449708Y613954D03*
X1446708D03*
X1440708D03*
X1443708D03*
X1446708Y622954D03*
X1440708D03*
X1443708D03*
X1452938Y617364D03*
X1450438D03*
X1452898Y621844D03*
X1450398D03*
X1448996Y645270D03*
Y647770D03*
X1451496Y645270D03*
X1453996D03*
Y647770D03*
X1451496D03*
X1449046Y650370D03*
X1454046D03*
X1451546D03*
X1446426D03*
X1443926D03*
X1443876Y645270D03*
Y647770D03*
X1446376Y645270D03*
Y647770D03*
X1447314Y684998D03*
X1442091Y684846D03*
X1442045Y682338D03*
X1448807Y695913D03*
Y693372D03*
X1445034Y688523D03*
X1452615Y705531D03*
X1441727Y747051D03*
X1444257Y757133D03*
Y759633D03*
Y762133D03*
X1441757Y759633D03*
Y762133D03*
X1441743Y757051D03*
Y754551D03*
Y752051D03*
Y749551D03*
X1444257Y772133D03*
Y764633D03*
Y769633D03*
Y767133D03*
X1441757Y772133D03*
Y764633D03*
Y769633D03*
Y767133D03*
X1442107Y1013504D03*
Y1009764D03*
Y1006024D03*
Y1020985D03*
Y1024725D03*
Y1028465D03*
Y1017244D03*
Y1032205D03*
X1439850Y1541470D03*
X1440401Y1574795D03*
Y1582295D03*
Y1579795D03*
Y1577295D03*
X1442901Y1582295D03*
Y1579795D03*
Y1577295D03*
Y1574795D03*
X1447026Y1577299D03*
X1448061Y1593055D03*
X1451000Y1601000D03*
X1446000Y1600500D03*
X1450500Y1614500D03*
Y1624000D03*
X1445500Y1614500D03*
X1441000D03*
X1440027Y1667945D03*
X1455579Y1665701D03*
X1453553Y1686892D03*
X1445079Y1686678D03*
X1449070Y1686722D03*
X1448000Y1676000D03*
X1464830Y59054D03*
X1466681Y78590D03*
X1454549Y107443D03*
X1455667Y125733D03*
X1463017Y139518D03*
X1456226Y152166D03*
X1462682Y450372D03*
X1456982Y437362D03*
X1466609Y458608D03*
X1465395Y487582D03*
X1465832Y530656D03*
X1463647Y544977D03*
X1464257Y560977D03*
Y557498D03*
X1462497Y555021D03*
X1464257Y568977D03*
Y572977D03*
Y580977D03*
Y576977D03*
X1467708Y610954D03*
Y607954D03*
X1464708Y610954D03*
Y607954D03*
X1458708Y610954D03*
X1455708D03*
X1461708D03*
Y607954D03*
X1455708D03*
X1458708D03*
X1467708Y616954D03*
Y619954D03*
Y613954D03*
X1461708Y616954D03*
Y619954D03*
X1464708Y616954D03*
Y619954D03*
Y613954D03*
X1458708D03*
X1455708D03*
X1461708D03*
X1467708Y622954D03*
X1461708D03*
X1464708D03*
X1455438Y617364D03*
X1457938D03*
X1455398Y621844D03*
X1457898D03*
X1456496Y645270D03*
X1459396D03*
X1456496Y647770D03*
X1459396D03*
X1456546Y650370D03*
X1459446D03*
X1467521Y702378D03*
X1454715Y700931D03*
X1468271Y704946D03*
X1462045Y711826D03*
X1464475D03*
X1459615D03*
X1456881Y708201D03*
Y705301D03*
X1454715Y706931D03*
Y703931D03*
X1454815Y709931D03*
X1458777Y714194D03*
Y717094D03*
X1456335Y771710D03*
Y766628D03*
X1458861Y776628D03*
X1461361D03*
X1458861Y769128D03*
Y771628D03*
Y774128D03*
X1461361D03*
Y771628D03*
Y769128D03*
X1461335Y766628D03*
X1458835D03*
X1456335Y776710D03*
Y774210D03*
Y769210D03*
X1461371Y791696D03*
Y789196D03*
X1458871Y779196D03*
X1461371D03*
X1458871Y784196D03*
Y781696D03*
Y786696D03*
X1461371Y784196D03*
Y786696D03*
Y781696D03*
X1456371Y779210D03*
Y781710D03*
Y784210D03*
X1456945Y1015473D03*
X1464526D03*
X1456945Y1019016D03*
Y1022559D03*
X1464526Y1019016D03*
Y1022559D03*
X1468102Y1670817D03*
X1458795Y1687083D03*
X1457940Y1675710D03*
X1463038Y1687060D03*
X1466111Y1685098D03*
X1472129Y56083D03*
X1483820Y132405D03*
X1471395Y487582D03*
X1473947Y492169D03*
X1472647Y539478D03*
X1475257Y530656D03*
X1473444Y555208D03*
X1473408Y547948D03*
X1478147Y547728D03*
X1478257Y543977D03*
X1481257Y544977D03*
X1482044Y542517D03*
X1472257Y551241D03*
X1472757Y561264D03*
X1473362Y558380D03*
X1472257Y564977D03*
X1481898Y585476D03*
X1484347Y580388D03*
X1478258Y588108D03*
Y584142D03*
X1474963Y701915D03*
X1480232Y704575D03*
X1475009Y704488D03*
X1481725Y715490D03*
X1471009Y703978D03*
X1481725Y712949D03*
X1477952Y708100D03*
X1477171Y774196D03*
Y771696D03*
Y769196D03*
Y776696D03*
X1474661Y776628D03*
Y774128D03*
Y771628D03*
Y769128D03*
X1472161Y776628D03*
Y769128D03*
Y771628D03*
Y774128D03*
X1472145Y766628D03*
X1474645D03*
X1477145D03*
X1477171Y791696D03*
X1474671D03*
X1472171D03*
X1477171Y786696D03*
X1474671D03*
X1477171Y781696D03*
X1474671D03*
X1472171Y789196D03*
Y779196D03*
Y784196D03*
Y786696D03*
Y781696D03*
X1477171Y789196D03*
X1474671D03*
X1477171Y779196D03*
X1474671D03*
X1477171Y784196D03*
X1474671D03*
X1481177Y803488D03*
X1469950Y813232D03*
X1473728Y813552D03*
X1480677Y813488D03*
X1484177Y812988D03*
X1474177Y816872D03*
X1471526Y1015473D03*
Y1019016D03*
Y1022559D03*
X1482798Y1685982D03*
X1469588Y1673342D03*
X1486000Y1686000D03*
X1470500Y1685500D03*
X1494891Y121171D03*
X1488647Y134562D03*
X1497386Y464980D03*
X1495682Y473302D03*
X1484395Y487582D03*
X1492514Y539657D03*
X1484416Y541658D03*
X1488510Y542816D03*
X1490602Y544755D03*
X1497310Y543960D03*
X1494967Y541898D03*
X1487660Y585748D03*
X1491677Y583588D03*
X1490677Y580688D03*
X1492789Y576602D03*
X1495236Y612838D03*
X1495486Y599938D03*
X1497986Y602438D03*
Y599938D03*
X1495236Y605338D03*
X1495486Y602438D03*
X1495236Y607838D03*
Y610338D03*
X1492636Y605258D03*
Y607758D03*
Y610258D03*
Y612758D03*
X1497986Y612838D03*
Y605338D03*
Y607838D03*
Y610338D03*
X1495486Y615988D03*
Y618488D03*
X1497986Y615988D03*
Y618488D03*
X1492886Y618408D03*
Y615908D03*
X1497587Y711636D03*
X1495157D03*
X1492727D03*
X1489963Y705301D03*
X1487797Y706931D03*
X1487897Y709931D03*
X1489963Y708201D03*
X1485697Y708431D03*
Y705531D03*
Y711331D03*
X1492264Y714544D03*
Y717444D03*
X1491943Y776628D03*
X1494443D03*
X1491943Y769128D03*
Y771628D03*
Y774128D03*
X1494443D03*
Y771628D03*
Y769128D03*
X1494417Y766628D03*
X1491917D03*
X1489417Y776710D03*
Y774210D03*
Y769210D03*
Y771710D03*
Y766628D03*
X1494487Y779210D03*
Y784210D03*
Y786710D03*
Y781710D03*
X1491987Y779210D03*
Y784210D03*
Y786710D03*
Y781710D03*
X1489487Y779210D03*
Y784210D03*
Y786710D03*
Y781710D03*
X1500500Y809063D03*
X1496532Y803513D03*
X1485177Y803488D03*
X1489177Y812988D03*
X1487923Y816770D03*
X1490973Y825557D03*
X1498177Y829359D03*
X1495670Y826073D03*
X1486761Y826279D03*
X1493260Y1167390D03*
X1496960D03*
X1488875Y1677385D03*
X1503785Y464815D03*
X1505974Y470636D03*
X1511917Y483878D03*
X1499752Y488424D03*
X1502085Y545432D03*
X1507109Y550059D03*
X1507644Y554372D03*
X1507468Y564357D03*
X1506337Y561677D03*
X1502757Y570977D03*
X1508281Y559390D03*
X1509757Y575477D03*
X1501821Y577664D03*
X1502986Y602438D03*
Y599938D03*
X1500486Y602438D03*
Y599938D03*
X1502486Y605338D03*
Y607838D03*
Y610338D03*
Y612838D03*
X1500486Y615988D03*
Y618488D03*
X1502986Y615988D03*
Y618488D03*
X1500603Y702378D03*
X1508045Y701915D03*
X1513314Y704575D03*
X1508045Y704423D03*
X1504091Y703978D03*
X1501353Y704946D03*
X1511034Y708100D03*
X1510287Y771710D03*
Y769210D03*
Y774210D03*
Y776710D03*
X1507743Y776628D03*
Y774128D03*
Y771628D03*
Y769128D03*
X1505243Y776628D03*
Y769128D03*
Y771628D03*
Y774128D03*
X1505227Y766628D03*
X1507727D03*
X1510227D03*
X1507787Y786710D03*
Y781710D03*
X1505287Y779210D03*
Y784210D03*
Y786710D03*
Y781710D03*
X1510287Y779210D03*
Y784210D03*
Y786710D03*
Y781710D03*
X1507787Y779210D03*
Y784210D03*
X1508177Y803488D03*
X1501500Y799948D03*
X1510261Y814611D03*
X1500422Y814180D03*
X1512523Y809679D03*
X1502177Y817013D03*
X1512539Y812920D03*
X1505016Y817107D03*
X1501636Y828796D03*
X1499469Y860322D03*
Y863322D03*
X1504362Y1167390D03*
X1508063D03*
X1515854Y119810D03*
X1517708Y216505D03*
X1527392Y238017D03*
X1519120Y479215D03*
X1515936Y484412D03*
X1516757Y537477D03*
X1516257Y547977D03*
X1516336Y551977D03*
X1519457Y556338D03*
X1519317Y561977D03*
X1527853Y560264D03*
X1524777Y605488D03*
Y607988D03*
X1527277Y605488D03*
Y607988D03*
X1524777Y610588D03*
X1527277D03*
X1524777Y613088D03*
X1527277D03*
X1524777Y615618D03*
X1527277D03*
X1524777Y618118D03*
X1527277D03*
X1514807Y715490D03*
Y712949D03*
X1525527Y711636D03*
X1527957D03*
X1522763Y708201D03*
Y705301D03*
X1518497Y705531D03*
X1520597Y706931D03*
X1518497Y708431D03*
X1520697Y709931D03*
X1518497Y711331D03*
X1525064Y714544D03*
Y717444D03*
X1522217Y771710D03*
X1527217Y766628D03*
X1522217Y769210D03*
X1524717Y766628D03*
X1522217D03*
Y774210D03*
Y776710D03*
X1524743Y776628D03*
X1527243D03*
X1524743Y769128D03*
Y771628D03*
Y774128D03*
X1527243D03*
Y771628D03*
Y769128D03*
X1527217Y779210D03*
Y784210D03*
Y786710D03*
Y781710D03*
X1524717Y779210D03*
X1522217D03*
X1524717Y784210D03*
Y786710D03*
X1522217Y784210D03*
Y786710D03*
X1524717Y781710D03*
X1522217D03*
X1517431Y811466D03*
X1521003Y1169488D03*
X1521217Y1190088D03*
X1524425Y1185241D03*
X1539134Y-35912D03*
Y-32512D03*
X1538342Y28406D03*
X1540342Y48720D03*
X1537450Y226293D03*
X1533160Y231250D03*
X1536538Y296819D03*
X1536422Y292816D03*
X1536542Y308819D03*
X1534584Y467067D03*
X1539693Y543613D03*
X1532824Y555981D03*
X1539693Y558943D03*
X1532730Y562949D03*
X1534565Y564945D03*
X1533403Y702378D03*
X1540845Y701915D03*
Y704423D03*
X1536891Y703978D03*
X1534153Y704946D03*
X1543834Y708100D03*
X1530387Y711636D03*
X1538027Y766628D03*
X1540527D03*
X1540543Y776628D03*
Y774128D03*
Y771628D03*
Y769128D03*
X1538043Y776628D03*
Y769128D03*
Y771628D03*
Y774128D03*
X1538027Y784710D03*
Y779210D03*
X1540527D03*
X1538027Y781710D03*
X1540527D03*
X1539972Y807319D03*
X1529306Y1177468D03*
X1540801Y1178265D03*
X1537301D03*
X1539301Y1175765D03*
X1532896Y1234836D03*
X1542747Y1253602D03*
X1538587Y1245065D03*
X1543772Y1241016D03*
X1543519Y1248205D03*
X1536916Y1240844D03*
X1543582Y1524562D03*
X1541191Y1544953D03*
Y1547453D03*
Y1549953D03*
X1539369Y1552250D03*
X1541876Y1554436D03*
X1539344Y1579519D03*
X1554360Y207251D03*
X1556960Y287478D03*
X1551900Y287288D03*
X1544489Y288816D03*
X1546789Y287116D03*
X1548772Y291916D03*
X1553154Y479063D03*
X1558198Y486791D03*
X1551779Y530698D03*
X1546149Y541169D03*
X1545987Y562012D03*
X1553657Y678965D03*
X1553827Y687991D03*
X1556027Y680391D03*
X1555893Y686261D03*
Y683361D03*
X1553657Y681965D03*
X1553727Y684991D03*
X1558657Y689696D03*
X1558194Y695501D03*
Y692501D03*
X1546114Y704575D03*
X1547607Y715490D03*
Y712949D03*
X1556708Y747282D03*
X1556688Y744688D03*
X1556708Y749782D03*
Y754782D03*
Y752282D03*
Y757282D03*
Y762282D03*
Y759782D03*
Y764782D03*
Y769782D03*
Y767282D03*
X1556121Y798542D03*
X1551124Y801289D03*
X1551961Y807269D03*
X1556361D03*
X1547561D03*
X1551113Y1238088D03*
X1548360Y1234750D03*
X1550517Y1232905D03*
X1545627Y1254068D03*
X1545480Y1245090D03*
X1544911Y1260654D03*
X1543980Y1258312D03*
X1554692Y1269688D03*
X1557559Y1269095D03*
X1557510Y1280291D03*
X1554377Y1278763D03*
X1560454Y1279004D03*
X1553226Y1288814D03*
X1553548Y1284991D03*
X1556515Y1292232D03*
X1555222Y1302757D03*
X1547195Y1478165D03*
X1547216Y1480812D03*
X1545473Y1522117D03*
X1547548Y1520070D03*
X1551821Y1549120D03*
Y1545220D03*
X1551546Y1552845D03*
X1556071Y1547576D03*
X1554635Y1542469D03*
X1552135D03*
X1556071Y1545076D03*
X1545644Y1552845D03*
X1545521Y1549120D03*
Y1545220D03*
X1548671Y1549120D03*
Y1545220D03*
X1548684Y1554436D03*
X1554093Y1582295D03*
Y1574795D03*
Y1579795D03*
Y1577295D03*
X1551593Y1582295D03*
Y1579795D03*
X1556593Y1582295D03*
Y1579795D03*
Y1574795D03*
Y1577295D03*
X1549093Y1579795D03*
Y1582295D03*
X1546593D03*
Y1579795D03*
X1558560Y1571682D03*
X1556060D03*
X1557633Y1584844D03*
X1572502Y254250D03*
X1572549Y257491D03*
X1566442Y294816D03*
X1564506Y310334D03*
Y313734D03*
X1571516Y319099D03*
X1568070Y497847D03*
X1573070D03*
X1570570D03*
X1570068Y534095D03*
X1573326Y543351D03*
X1573487Y546996D03*
X1572436Y578933D03*
X1568446Y582733D03*
X1572436Y582433D03*
X1564946Y582733D03*
X1561246Y580393D03*
X1572436Y574022D03*
X1568936Y585933D03*
Y589433D03*
X1565436Y585933D03*
Y589433D03*
X1562016Y584283D03*
Y587783D03*
X1572436Y589433D03*
Y585933D03*
X1566533Y680438D03*
X1570021Y682038D03*
X1567283Y683006D03*
X1563517Y689696D03*
X1561087D03*
X1572514Y747188D03*
X1561714D03*
X1559214D03*
X1561688Y744688D03*
X1559188D03*
X1572498D03*
X1572588Y757282D03*
Y759782D03*
X1561708Y757282D03*
X1559208D03*
X1561708Y759782D03*
X1559208D03*
X1561708Y762282D03*
X1559208D03*
X1572514Y752188D03*
Y749688D03*
Y754688D03*
X1561714Y749688D03*
Y752188D03*
X1559214D03*
Y749688D03*
X1561714Y754688D03*
X1559214D03*
X1561708Y769782D03*
X1559208D03*
X1561708Y767282D03*
X1559208D03*
X1561708Y764782D03*
X1559208D03*
X1570583Y800104D03*
X1572668Y806778D03*
X1567737Y1271411D03*
X1561927Y1269901D03*
X1559181Y1287165D03*
X1568100Y1290418D03*
X1567000Y1293446D03*
X1562820Y1309360D03*
X1568456Y1311533D03*
X1572416Y1303160D03*
X1564268Y1338440D03*
X1562937Y1341609D03*
X1572331Y1348205D03*
X1566901Y1347726D03*
X1564758Y1367834D03*
X1572906Y1366759D03*
X1563967Y1363205D03*
X1572860Y1495595D03*
X1569460D03*
X1563222Y1516590D03*
Y1513190D03*
Y1534990D03*
Y1538390D03*
X1567089Y1563596D03*
X1562640Y1556331D03*
Y1559731D03*
X1559093Y1577295D03*
Y1574795D03*
X1565963D03*
X1568463D03*
X1565963Y1577295D03*
X1568463D03*
Y1579795D03*
X1565963D03*
X1568463Y1582295D03*
X1565963D03*
X1570963Y1574795D03*
Y1582295D03*
Y1579795D03*
Y1577295D03*
X1563463Y1574795D03*
Y1582295D03*
Y1579795D03*
Y1577295D03*
X1560051Y1581199D03*
X1574966Y1577038D03*
X1562556Y1584844D03*
X1560051Y1584099D03*
X1586291Y303596D03*
X1586621Y484304D03*
X1580519Y497650D03*
X1575570Y497847D03*
X1584397Y655622D03*
X1586497Y651222D03*
X1586597Y654222D03*
X1584397Y652722D03*
Y649822D03*
X1573975Y679975D03*
X1579244Y682635D03*
X1573975Y682483D03*
X1576964Y686160D03*
X1580737Y693550D03*
Y691009D03*
X1577588Y747282D03*
X1575014Y747188D03*
X1577498Y744688D03*
X1574998D03*
X1575088Y757282D03*
X1577588Y749782D03*
Y754782D03*
Y752282D03*
X1575014Y749688D03*
Y752188D03*
Y754688D03*
X1578690Y1283310D03*
X1585290Y1285098D03*
X1574168Y1283300D03*
X1577077Y1270937D03*
X1580577D03*
X1584068Y1271198D03*
X1580010Y1296100D03*
X1574560Y1296410D03*
X1580520Y1289900D03*
X1586167Y1295478D03*
X1575024Y1306373D03*
X1586557Y1304509D03*
X1578336Y1359253D03*
X1578411Y1348623D03*
X1578020Y1344773D03*
X1584156Y1381419D03*
X1586000Y1387641D03*
X1590723Y1381589D03*
X1579560Y1485895D03*
X1576160D03*
X1603970Y222956D03*
X1593303Y234250D03*
Y239250D03*
X1598303Y234250D03*
X1596462Y229790D03*
X1593658Y252010D03*
X1593303Y244250D03*
X1593349Y248160D03*
X1597481Y271991D03*
X1600918Y521688D03*
X1604890Y531226D03*
X1596299Y536344D03*
X1599303Y646669D03*
X1602791Y648269D03*
X1600053Y649237D03*
X1596287Y655927D03*
X1591427D03*
X1593857D03*
X1588663Y649592D03*
Y652492D03*
X1590964Y661741D03*
Y658741D03*
X1594844Y713419D03*
Y715919D03*
X1592344D03*
Y713419D03*
X1594818Y710919D03*
X1594844Y718419D03*
X1592344D03*
X1594844Y720919D03*
X1592344D03*
X1594688Y723512D03*
Y726012D03*
Y728512D03*
Y731012D03*
X1592188Y723512D03*
Y726012D03*
Y728512D03*
Y731012D03*
X1594688Y736012D03*
X1592188D03*
X1594688Y733512D03*
X1592188D03*
X1594900Y780112D03*
X1598467Y1267539D03*
X1588832Y1269083D03*
X1597177Y1282288D03*
X1594152Y1282578D03*
X1598883Y1270766D03*
X1590827Y1271378D03*
X1593397Y1271458D03*
X1596273Y1271472D03*
X1591005Y1288892D03*
X1596363Y1286296D03*
X1590921Y1309276D03*
X1599241Y1306622D03*
X1589845Y1305289D03*
X1599007Y1309762D03*
X1597621Y1365384D03*
X1595438Y1370603D03*
X1592788Y1388318D03*
X1597234Y1382689D03*
X1600531Y1404710D03*
X1597992Y1433183D03*
X1595716Y1431861D03*
X1602782Y1435920D03*
X1600442Y1434535D03*
X1602960Y1485895D03*
X1592960Y1505295D03*
X1599660Y1495595D03*
X1589560Y1505295D03*
X1596260Y1495595D03*
X1615020Y183050D03*
X1619909Y298742D03*
Y293742D03*
X1612144Y418552D03*
X1614701Y422587D03*
X1616464Y457509D03*
X1616250Y465042D03*
X1609166Y527300D03*
X1611775D03*
X1609166Y524700D03*
X1611775D03*
X1613169Y531819D03*
X1604991Y536344D03*
X1616084Y549105D03*
X1616198Y556364D03*
X1618859Y542820D03*
X1618356Y612137D03*
Y609137D03*
X1618434Y605753D03*
X1609044Y600986D03*
X1617397Y630822D03*
Y636622D03*
Y633722D03*
X1606745Y646206D03*
X1612014Y648866D03*
X1606745Y648714D03*
X1613507Y657240D03*
X1609734Y652391D03*
X1613507Y659781D03*
X1605644Y715919D03*
Y713419D03*
X1608144D03*
Y715919D03*
X1605628Y710919D03*
X1608128D03*
X1610628D03*
X1610718Y713513D03*
Y716013D03*
X1605644Y718419D03*
Y720919D03*
X1608144Y718419D03*
Y720919D03*
X1610718Y721013D03*
Y718513D03*
X1608118Y723512D03*
X1605618D03*
X1608118Y726012D03*
X1605618D03*
X1610618Y723512D03*
X1605618Y728512D03*
X1617200Y766870D03*
X1607267Y1271978D03*
X1604137Y1271358D03*
X1605801Y1286168D03*
X1608901Y1285887D03*
X1605360Y1294595D03*
X1608652Y1303338D03*
X1608341Y1313269D03*
X1608418Y1333589D03*
Y1331089D03*
X1614767Y1443512D03*
X1605648Y1437305D03*
X1606360Y1485895D03*
X1616360Y1505295D03*
X1622329Y28261D03*
X1623189Y48720D03*
X1631200Y164110D03*
X1631455Y167875D03*
X1627152Y168920D03*
X1629597Y227157D03*
X1627156Y238303D03*
X1627986Y282728D03*
X1627909Y286742D03*
Y298742D03*
Y294742D03*
Y290742D03*
X1619909Y303596D03*
X1627909Y302742D03*
X1621680Y366920D03*
X1625000Y383399D03*
X1631657Y392925D03*
X1632012Y603015D03*
X1621512D03*
X1625012D03*
X1628512D03*
X1632303Y627669D03*
X1633053Y630237D03*
X1626857Y636927D03*
X1629287D03*
X1624427D03*
X1621663Y630592D03*
X1619597Y635222D03*
X1621663Y633492D03*
X1619497Y632222D03*
X1623964Y642741D03*
Y639741D03*
X1627643Y694419D03*
Y696919D03*
Y699419D03*
X1625143D03*
Y696919D03*
Y694419D03*
X1627643Y701919D03*
X1625143D03*
X1627617Y691919D03*
X1625117D03*
Y709512D03*
Y704512D03*
Y707012D03*
Y712012D03*
X1627617Y709512D03*
Y704512D03*
Y707012D03*
Y712012D03*
X1628046Y763765D03*
X1626928Y1260917D03*
X1629428D03*
X1631928D03*
X1626333Y1311091D03*
Y1308091D03*
X1627174Y1420450D03*
X1625285Y1433384D03*
X1635281Y1422450D03*
X1627217Y1428366D03*
X1622697Y1440797D03*
X1625170Y1444016D03*
X1635227Y1436528D03*
X1633160Y1485895D03*
X1629760D03*
X1619760Y1505295D03*
X1626460Y1495595D03*
X1623060D03*
X1636047Y224597D03*
Y229912D03*
X1647310Y408922D03*
Y411422D03*
X1635697Y561253D03*
X1635944Y609510D03*
Y612510D03*
X1636022Y606126D03*
X1647158Y618971D03*
X1639745Y627206D03*
X1646507Y640781D03*
X1645014Y629866D03*
X1639745Y629714D03*
X1635791Y629269D03*
X1646507Y638240D03*
X1642734Y633391D03*
X1638443Y699419D03*
Y696919D03*
Y694419D03*
Y701919D03*
X1640943Y694419D03*
Y696919D03*
Y699419D03*
Y701919D03*
X1643517Y702013D03*
Y699513D03*
Y694513D03*
Y697013D03*
X1643427Y691919D03*
X1640927D03*
X1638427D03*
X1640877Y706972D03*
Y709472D03*
X1638377D03*
Y704472D03*
Y706972D03*
X1640877Y704472D03*
X1643377Y709510D03*
Y704510D03*
Y707010D03*
X1640877Y711972D03*
X1638377D03*
X1643377Y712010D03*
X1635088Y767205D03*
Y771005D03*
X1644188Y766870D03*
X1634428Y1260917D03*
X1645163Y1276184D03*
X1641677Y1341488D03*
Y1344488D03*
X1641087Y1396118D03*
X1641065Y1403393D03*
X1644001Y1408069D03*
X1646483Y1412741D03*
X1641065Y1406393D03*
X1635619Y1430536D03*
X1639834Y1434478D03*
X1636167Y1446746D03*
X1642400Y1439674D03*
X1645979Y1437950D03*
X1650400Y1437820D03*
X1641167Y1446746D03*
X1646560Y1505295D03*
X1643160D03*
X1646879Y1681738D03*
X1645029Y1715609D03*
Y1710609D03*
X1648029Y1708609D03*
Y1723759D03*
X1645029Y1725759D03*
Y1730759D03*
X1652525Y146762D03*
Y151762D03*
Y161762D03*
X1650023Y221842D03*
X1654419Y224597D03*
X1659419D03*
X1650023Y227157D03*
X1654419Y229912D03*
X1661928Y230172D03*
X1650020Y408952D03*
Y411452D03*
X1654110Y434177D03*
X1657545Y434506D03*
X1650035Y434750D03*
X1657194Y599956D03*
X1651194D03*
X1660194Y609450D03*
X1654194D03*
X1660194Y599956D03*
X1657194Y609450D03*
X1654194Y599956D03*
X1651194Y609450D03*
X1654147Y616523D03*
X1662377Y696300D03*
Y693300D03*
X1651072Y1314137D03*
X1660572Y1313837D03*
X1660635Y1329166D03*
X1651072Y1323137D03*
Y1320137D03*
Y1317137D03*
X1660572Y1322837D03*
Y1319837D03*
X1660635Y1326466D03*
X1660572Y1316837D03*
X1658015Y1328966D03*
X1658115Y1326466D03*
X1660635Y1331666D03*
Y1334166D03*
Y1339166D03*
Y1336666D03*
X1650177Y1341488D03*
X1658277Y1341888D03*
X1658015Y1336466D03*
Y1338966D03*
Y1331466D03*
Y1333966D03*
X1650177Y1344488D03*
X1658677D03*
X1653390Y1386316D03*
Y1388857D03*
X1649197Y1396743D03*
X1654883Y1397231D03*
X1660152Y1397383D03*
X1664106Y1397828D03*
X1660152Y1399891D03*
X1657163Y1393706D03*
X1661807Y1416948D03*
X1663777Y1421568D03*
X1662487Y1424178D03*
X1658089Y1437444D03*
X1649380Y1446713D03*
X1659960Y1485895D03*
X1656560D03*
X1653260Y1495595D03*
X1649860D03*
X1659975Y1592929D03*
X1656101Y1671720D03*
X1651101Y1671833D03*
X1653930Y1660640D03*
X1656180Y1659220D03*
X1656849Y1664949D03*
X1651698Y1665045D03*
X1661125Y1690751D03*
X1656101Y1701094D03*
X1656997Y1718759D03*
Y1733909D03*
X1673100Y121762D03*
Y136762D03*
Y131762D03*
X1673403Y199997D03*
X1664335Y210191D03*
X1663310Y215488D03*
X1664789Y767265D03*
Y771065D03*
X1673889Y766870D03*
X1674972Y1313837D03*
X1675134Y1329219D03*
X1675234Y1326519D03*
X1674972Y1316837D03*
X1672623Y1326476D03*
X1663437Y1326526D03*
X1674972Y1319837D03*
Y1322837D03*
X1677754Y1326519D03*
Y1329019D03*
X1663437Y1334726D03*
X1672623Y1334676D03*
X1663437Y1329726D03*
X1672623Y1332176D03*
X1663437Y1332226D03*
X1672623Y1329676D03*
X1675134Y1331719D03*
Y1334219D03*
Y1336719D03*
Y1339219D03*
X1677754Y1339019D03*
Y1336519D03*
Y1331519D03*
Y1334019D03*
X1675931Y1384335D03*
Y1387235D03*
X1667594Y1399428D03*
X1666844Y1396860D03*
X1675470Y1390170D03*
X1673040D03*
X1670610D03*
X1672501Y1416678D03*
X1675641Y1432891D03*
X1672401Y1423365D03*
X1664237Y1426278D03*
X1671079Y1435069D03*
X1663239Y1428592D03*
X1670147Y1444311D03*
X1673360Y1485895D03*
X1669960D03*
X1676685Y1537893D03*
X1671034Y1549734D03*
Y1552234D03*
X1668703Y1550898D03*
X1671034Y1546934D03*
X1668827Y1553551D03*
X1671034Y1557234D03*
Y1554734D03*
X1673706Y1560425D03*
X1671006Y1576744D03*
Y1574244D03*
Y1571744D03*
X1668826Y1575498D03*
Y1572998D03*
X1676176Y1580650D03*
X1674923Y1582973D03*
X1677556Y1656405D03*
X1674356D03*
X1671156D03*
X1666168Y1667688D03*
X1670202Y1663150D03*
X1675290Y1663157D03*
X1674338Y1677832D03*
X1671902Y1676267D03*
X1669377Y1675241D03*
X1670773Y1688827D03*
X1680029Y1710609D03*
Y1715609D03*
X1672500Y1708927D03*
X1675360Y1721252D03*
X1695100Y121762D03*
X1683275Y120762D03*
X1695100Y136762D03*
Y131762D03*
X1684925D03*
Y136762D03*
Y123762D03*
Y126762D03*
Y145762D03*
X1695100Y146762D03*
X1684925Y141762D03*
X1695100Y156762D03*
Y161762D03*
Y166762D03*
X1684925Y157762D03*
Y166762D03*
X1678809Y206451D03*
X1682433Y220857D03*
X1682408Y228337D03*
X1689000Y234000D03*
X1692429Y403985D03*
X1694050Y416643D03*
X1690208Y421855D03*
X1690140Y434160D03*
X1692450Y436772D03*
X1692974Y553115D03*
X1685890Y708610D03*
X1684672Y1313837D03*
X1690697Y1329066D03*
Y1326566D03*
X1684672Y1322837D03*
Y1319837D03*
Y1316837D03*
X1690697Y1336566D03*
Y1334066D03*
Y1331566D03*
X1679028Y1341733D03*
X1687234Y1341533D03*
Y1344033D03*
X1679028Y1344233D03*
X1690697Y1339066D03*
X1686172Y1386416D03*
Y1388957D03*
X1687665Y1397331D03*
X1692934Y1397483D03*
Y1399991D03*
X1689945Y1393806D03*
X1682500Y1390475D03*
X1680300Y1391875D03*
X1682500Y1396275D03*
X1680400Y1394875D03*
X1678234Y1393605D03*
Y1396505D03*
X1682500Y1393375D03*
X1683741Y1443075D03*
X1681538Y1451522D03*
X1689062Y1451496D03*
X1687783Y1472068D03*
X1680730Y1517082D03*
Y1513682D03*
Y1530482D03*
Y1527082D03*
X1685745Y1552579D03*
X1686219Y1549994D03*
X1685745Y1555079D03*
Y1557579D03*
X1685995Y1561516D03*
X1680589Y1559626D03*
Y1563526D03*
X1690353Y1591494D03*
X1680695Y1656307D03*
X1686675Y1659287D03*
X1692415Y1663740D03*
X1685500Y1663599D03*
X1680367Y1663367D03*
X1691952Y1698947D03*
X1689184Y1702095D03*
X1683029Y1708609D03*
X1680877Y1723593D03*
X1692218Y1717539D03*
X1685383Y1729559D03*
X1707186Y15708D03*
X1703583Y26505D03*
X1700183D03*
X1703536Y50649D03*
X1700136D03*
X1695100Y126762D03*
Y141762D03*
Y151762D03*
X1705120Y143610D03*
X1693000Y234000D03*
X1698220Y369652D03*
X1699809Y403985D03*
X1695579D03*
X1702959Y404243D03*
X1697161Y406602D03*
X1706500Y415862D03*
Y413362D03*
X1707780Y410738D03*
X1695455Y422287D03*
X1707568Y420370D03*
X1701124Y423802D03*
X1707544Y431745D03*
X1704974Y553115D03*
X1700974D03*
X1696974D03*
X1693490Y620672D03*
X1697530Y636369D03*
X1701661Y644554D03*
X1705561D03*
X1699500Y654738D03*
Y673738D03*
X1694490Y767265D03*
Y771065D03*
X1708049Y766870D03*
X1699072Y1313737D03*
X1696047Y1326576D03*
X1705383D03*
X1693417Y1329266D03*
X1693217Y1326566D03*
X1699072Y1322737D03*
Y1319737D03*
Y1316737D03*
X1693417Y1334266D03*
Y1331766D03*
X1705383Y1334676D03*
X1696047D03*
X1705383Y1329676D03*
X1696047Y1332176D03*
Y1329676D03*
X1705383Y1332176D03*
X1693417Y1336766D03*
Y1339266D03*
X1700376Y1399528D03*
X1696888Y1397928D03*
X1699626Y1396960D03*
X1703392Y1390270D03*
X1705822D03*
X1700272Y1460547D03*
X1702281Y1449801D03*
X1705108Y1451774D03*
X1695020Y1465621D03*
X1698440Y1466590D03*
X1705246Y1465325D03*
X1701348Y1466557D03*
X1709964Y1597490D03*
X1709833Y1612940D03*
Y1606340D03*
X1701984Y1671618D03*
X1695987D03*
X1700156Y1698830D03*
X1702750Y1696185D03*
X1706086Y1691568D03*
X1717148Y19910D03*
X1712977Y19986D03*
X1722148Y19910D03*
X1722085Y25908D03*
X1717055D03*
X1710106Y39768D03*
X1723241Y48822D03*
X1710106Y48978D03*
X1721646Y68115D03*
X1716558Y67866D03*
X1715861Y72593D03*
X1712486Y117908D03*
X1712686Y111908D03*
X1719909Y112713D03*
Y116713D03*
X1713399Y132858D03*
X1721384Y135373D03*
X1717384D03*
X1716609Y141297D03*
X1721628Y147312D03*
X1714293Y156278D03*
X1711293D03*
X1716893D03*
X1719493D03*
X1722093D03*
X1711293Y158878D03*
X1714293D03*
X1711293Y161478D03*
X1714293D03*
X1711293Y163978D03*
X1714293D03*
X1711293Y166478D03*
X1714293D03*
X1722093Y158878D03*
X1719493D03*
X1716893D03*
X1722093Y161478D03*
Y163978D03*
Y166478D03*
X1719493Y161478D03*
X1716893D03*
X1719493Y163978D03*
X1716893D03*
Y166478D03*
X1719493D03*
X1719200Y371162D03*
X1717220Y381152D03*
X1713720D03*
X1717220Y384652D03*
Y388152D03*
X1713720D03*
Y384652D03*
X1717220Y391652D03*
X1713720D03*
X1709000Y415862D03*
Y413362D03*
X1709339Y637251D03*
X1718465Y657982D03*
X1720050Y649142D03*
X1716030Y668182D03*
X1709759Y670221D03*
X1718686Y676154D03*
X1722672Y1313237D03*
X1708672Y1313737D03*
X1707916Y1329319D03*
X1722672Y1316237D03*
X1708672Y1322737D03*
Y1319737D03*
X1710536Y1329119D03*
X1708016Y1326619D03*
X1710536D03*
X1722672Y1319237D03*
Y1322237D03*
X1719916Y1326559D03*
X1717396D03*
X1719916Y1329059D03*
X1717396D03*
X1708672Y1316737D03*
X1707916Y1334319D03*
Y1331819D03*
Y1339319D03*
Y1336819D03*
X1710536Y1336619D03*
Y1339119D03*
X1719916Y1339059D03*
X1717396D03*
X1719916Y1336559D03*
X1717396D03*
X1710536Y1334119D03*
Y1331619D03*
X1719916Y1331559D03*
Y1334059D03*
X1717396D03*
Y1331559D03*
X1710176Y1342089D03*
X1718706Y1341629D03*
Y1344129D03*
X1710176Y1344589D03*
X1708713Y1384435D03*
Y1387335D03*
X1708252Y1390270D03*
X1715282Y1396375D03*
X1713082Y1391975D03*
X1715282Y1390575D03*
X1711016Y1393705D03*
Y1396605D03*
X1713182Y1394975D03*
X1715282Y1393475D03*
X1717447Y1417213D03*
X1714447D03*
X1717447Y1423213D03*
Y1420213D03*
X1714447D03*
Y1423213D03*
X1722334Y1468146D03*
X1718425Y1468245D03*
X1722347Y1471246D03*
X1716070Y1472037D03*
X1712870Y1586615D03*
X1715693Y1597190D03*
X1713593Y1609640D03*
Y1603040D03*
X1720845Y1668498D03*
X1719181Y1706712D03*
X1721172Y1712115D03*
X1710360Y1706502D03*
X1721912Y1705115D03*
X1719218Y1727265D03*
X1719148Y1721530D03*
X1722149Y1720265D03*
X1710230Y1729654D03*
X1729557Y-35912D03*
Y-32512D03*
X1736006Y41838D03*
Y44338D03*
X1729836Y54524D03*
X1727336D03*
X1724685Y51454D03*
X1727225Y51424D03*
X1729895Y51354D03*
X1726741Y48822D03*
X1730241D03*
X1737617Y75640D03*
Y73140D03*
Y79140D03*
Y81640D03*
X1722984Y101713D03*
X1723184Y93313D03*
X1736731Y102293D03*
X1728965Y112941D03*
X1729046Y118178D03*
X1739686Y120938D03*
X1725093Y156278D03*
Y158878D03*
Y161478D03*
Y163978D03*
Y166478D03*
X1735471Y293682D03*
Y290682D03*
Y296682D03*
Y299682D03*
X1730331Y293722D03*
Y296722D03*
X1732831D03*
X1730331Y299722D03*
X1732831D03*
Y293722D03*
X1723492Y293068D03*
X1732751Y305732D03*
X1730251D03*
X1732751Y302732D03*
X1730251D03*
X1735391Y305692D03*
Y302692D03*
X1725344Y359334D03*
X1728300Y377787D03*
X1733043Y657091D03*
X1736848Y650974D03*
X1726409Y653641D03*
X1737002Y671494D03*
X1724191Y767299D03*
Y771099D03*
X1737850Y766794D03*
X1732702Y1313007D03*
Y1316007D03*
Y1322007D03*
Y1319007D03*
X1732766Y1410562D03*
Y1413062D03*
X1735266Y1410562D03*
Y1413062D03*
X1732766Y1426362D03*
Y1428862D03*
X1735266Y1426362D03*
Y1428862D03*
X1730004Y1540968D03*
X1726604Y1540970D03*
X1735379Y1566282D03*
X1735354Y1580480D03*
X1735351Y1569832D03*
X1736479Y1584330D03*
X1730202Y1602093D03*
X1735463Y1651965D03*
X1730381Y1647386D03*
X1726381D03*
X1734500Y1656965D03*
X1734589Y1666203D03*
X1734962Y1662965D03*
X1734963Y1673465D03*
X1724263Y1672465D03*
X1734763Y1680465D03*
X1735463Y1694465D03*
X1725423Y1692656D03*
X1731936Y1690165D03*
X1731117Y1715265D03*
X1732251Y1708265D03*
X1731117Y1730415D03*
X1748708Y26641D03*
X1751031Y39063D03*
X1738093Y53103D03*
Y55603D03*
X1741621Y76613D03*
Y74113D03*
Y82613D03*
Y80113D03*
X1743491Y92827D03*
X1738435Y100244D03*
X1741935D03*
X1745435D03*
X1740231Y102293D03*
X1743731D03*
X1748686Y97408D03*
X1740091Y92827D03*
X1750786Y120018D03*
X1744976Y122998D03*
X1754339Y128242D03*
X1752022Y269794D03*
Y266794D03*
X1742971Y293682D03*
Y290682D03*
X1737971D03*
X1740471Y293682D03*
Y290682D03*
Y299682D03*
X1737971D03*
X1740471Y296682D03*
X1737971D03*
Y293682D03*
X1751352Y293386D03*
X1745671Y290682D03*
Y293682D03*
X1737891Y302692D03*
X1740391D03*
X1737891Y305692D03*
X1740391D03*
X1744510Y377452D03*
X1744380Y382892D03*
X1742398Y484304D03*
X1742306Y661032D03*
X1745484Y668216D03*
X1751490Y713890D03*
X1748990D03*
X1746490D03*
X1743990D03*
X1751490Y706390D03*
X1748990D03*
X1746490D03*
X1743990D03*
X1751490Y708890D03*
X1748990D03*
X1746490D03*
X1743990D03*
X1751490Y711390D03*
X1748990D03*
X1746490D03*
X1743990D03*
X1742766Y1418462D03*
Y1415962D03*
X1737766Y1410562D03*
Y1413062D03*
X1740266Y1410562D03*
Y1413062D03*
X1742766D03*
Y1410562D03*
X1740266Y1415962D03*
Y1418462D03*
X1737766Y1426362D03*
Y1428862D03*
X1742766Y1423462D03*
X1740266Y1426362D03*
Y1423462D03*
Y1420962D03*
X1742766D03*
X1741329Y1506405D03*
Y1503405D03*
Y1509405D03*
Y1512405D03*
X1745543Y1518678D03*
X1742758Y1521239D03*
X1745746D03*
X1751120Y1521223D03*
X1751087Y1518704D03*
X1748346Y1521223D03*
X1748313Y1518704D03*
X1739565Y1528105D03*
X1751132Y1526748D03*
Y1524248D03*
Y1529248D03*
X1742810Y1524534D03*
X1745410D03*
X1748358Y1526748D03*
Y1524248D03*
Y1529248D03*
X1746779Y1583378D03*
X1751558Y1579332D03*
X1746079Y1587705D03*
X1750463Y1654465D03*
X1744963Y1656465D03*
X1744463Y1651229D03*
X1747986Y1686215D03*
X1751340Y1686140D03*
X1744620Y1716018D03*
X1750380Y1707468D03*
X1747120Y1710824D03*
X1749480Y1718158D03*
X1765920Y17031D03*
X1765980Y27031D03*
X1765920Y22031D03*
X1758638Y26477D03*
X1755238D03*
X1767266Y48748D03*
X1763010Y51223D03*
X1765527Y53692D03*
X1758635Y50649D03*
X1755235D03*
X1757923Y72637D03*
X1767956Y76843D03*
X1767136Y83653D03*
X1761417Y90017D03*
X1760444Y106173D03*
X1763644D03*
X1755944Y111073D03*
Y108473D03*
X1760944Y116773D03*
X1757944D03*
X1760124Y128246D03*
X1755504Y202263D03*
X1758030D03*
X1762564Y202326D03*
X1765090D03*
X1761573Y266657D03*
X1764573D03*
X1761573Y269657D03*
X1764573D03*
X1758022Y269794D03*
Y266794D03*
X1755022Y269794D03*
Y266794D03*
X1755772Y278859D03*
X1758772D03*
X1761772D03*
X1755772Y281859D03*
X1758772D03*
X1761772D03*
X1752772Y278859D03*
Y281859D03*
X1756800Y364048D03*
Y368048D03*
X1756933Y372452D03*
X1759379Y507927D03*
X1753566Y512968D03*
X1768041Y556537D03*
X1753990Y711390D03*
Y708890D03*
Y706390D03*
Y713890D03*
X1753891Y767305D03*
Y771105D03*
X1767450Y766870D03*
X1759949Y1297324D03*
X1764267Y1460080D03*
X1756329Y1506405D03*
Y1503405D03*
X1764029Y1506405D03*
Y1503405D03*
X1756329Y1509405D03*
Y1512405D03*
X1764029Y1509405D03*
Y1512405D03*
X1765286Y1518471D03*
X1765176Y1515902D03*
X1765286Y1521095D03*
X1765246Y1524001D03*
Y1526601D03*
X1765334Y1529342D03*
X1764679Y1572105D03*
X1765679Y1575405D03*
X1762679D03*
X1766079Y1578705D03*
X1763079D03*
X1753512Y1583478D03*
X1763706Y1616451D03*
X1760206D03*
X1767206D03*
X1765854Y1646456D03*
X1755463Y1654465D03*
X1767888Y1664465D03*
X1762263Y1671765D03*
X1765163Y1670543D03*
X1765463Y1677465D03*
X1761463Y1683465D03*
X1775920Y17031D03*
X1770920D03*
X1775920Y27068D03*
X1770920Y22031D03*
X1775920D03*
X1768956Y37558D03*
X1777720Y37792D03*
X1773830Y49000D03*
X1779377Y50738D03*
X1774294Y60133D03*
X1774291Y57191D03*
X1769240Y50788D03*
X1769200Y54300D03*
X1780300Y54400D03*
X1775546Y73376D03*
X1774294Y63033D03*
X1779744Y72973D03*
Y70073D03*
X1770334Y72737D03*
X1778205Y90982D03*
X1781451Y88238D03*
X1773577Y88339D03*
X1778544Y97973D03*
X1769244Y113773D03*
Y110973D03*
Y108073D03*
X1781368Y162824D03*
X1780929Y179408D03*
X1776930Y179051D03*
X1773581Y194120D03*
X1771055D03*
X1771931Y200920D03*
X1769405D03*
X1777170Y201002D03*
X1774644D03*
X1778796Y261633D03*
X1767573Y266657D03*
X1775633Y261666D03*
X1767573Y269657D03*
X1778796Y266633D03*
Y269133D03*
Y264133D03*
X1775633Y269166D03*
Y266666D03*
Y264166D03*
X1778796Y271633D03*
X1775633Y271666D03*
X1770280Y372452D03*
X1770220Y382952D03*
Y377452D03*
X1782324Y403932D03*
Y410432D03*
Y418932D03*
Y425432D03*
X1779376Y558324D03*
X1782376D03*
X1773963Y557537D03*
X1776986Y749023D03*
X1776550Y763765D03*
X1769650Y1280200D03*
X1771000Y1278060D03*
X1782369Y1447581D03*
X1782385Y1450095D03*
X1782337Y1453191D03*
X1775682Y1466568D03*
X1779029Y1506405D03*
Y1503405D03*
Y1509405D03*
Y1512405D03*
X1780012Y1518631D03*
Y1516031D03*
Y1521231D03*
X1777152Y1518631D03*
Y1516031D03*
Y1521231D03*
X1774552D03*
Y1516031D03*
Y1518631D03*
X1768176Y1515902D03*
X1768286Y1518471D03*
Y1521095D03*
X1770886D03*
Y1518471D03*
X1770776Y1515902D03*
X1780039Y1523860D03*
Y1526360D03*
X1779997Y1528888D03*
X1777179Y1526360D03*
Y1523860D03*
X1774579D03*
Y1526360D03*
X1768246Y1526601D03*
Y1524001D03*
X1768334Y1529342D03*
X1770846Y1524001D03*
Y1526601D03*
X1771079Y1566782D03*
X1770404Y1575330D03*
X1780579Y1582178D03*
X1771094Y1570332D03*
X1778794Y1585332D03*
X1768105Y1595925D03*
X1775794Y1585332D03*
X1768030Y1599249D03*
X1768180Y1606549D03*
X1768030Y1603149D03*
X1780154Y1615026D03*
X1777454D03*
X1780154Y1617726D03*
X1777454D03*
X1773349Y1631938D03*
Y1634438D03*
Y1636938D03*
X1770649Y1631938D03*
Y1634438D03*
X1781423Y1634394D03*
Y1636894D03*
X1778723Y1634294D03*
X1776023D03*
Y1636894D03*
X1778723D03*
X1773929Y1657465D03*
Y1654956D03*
X1768929Y1651956D03*
X1774338Y1676865D03*
X1771038Y1692956D03*
X1787826Y37548D03*
X1783700Y50011D03*
X1794099Y50461D03*
X1788204Y74958D03*
X1785108Y76078D03*
X1787756Y85178D03*
X1788204Y82338D03*
Y78108D03*
X1784144Y113973D03*
Y111173D03*
Y108273D03*
X1797692Y146285D03*
X1784006Y137395D03*
X1788950Y142750D03*
X1787390Y165834D03*
Y156834D03*
Y151834D03*
X1793444Y178083D03*
X1785320Y193072D03*
X1784915Y186053D03*
X1783896Y266633D03*
Y269133D03*
X1794174Y274499D03*
X1790674D03*
X1783896Y271633D03*
X1789771Y367866D03*
X1797929Y385293D03*
X1786260Y379059D03*
X1792507Y403932D03*
X1792335Y418775D03*
X1792450Y410615D03*
X1792220Y425432D03*
X1785376Y558324D03*
X1788376D03*
X1792895Y683536D03*
X1783592Y767565D03*
Y771365D03*
X1792692Y766870D03*
X1794362Y1275546D03*
X1785336Y1447565D03*
Y1450065D03*
X1785634Y1456326D03*
X1782530Y1456229D03*
X1785408Y1453385D03*
X1788029Y1506405D03*
Y1503405D03*
Y1509405D03*
Y1512405D03*
X1794265Y1518262D03*
Y1520862D03*
Y1523462D03*
Y1526062D03*
X1794268Y1528720D03*
X1784601Y1578967D03*
X1787239Y1579406D03*
X1789294Y1583278D03*
X1797118Y1596588D03*
X1797143Y1607014D03*
X1797076Y1603662D03*
X1797043Y1599811D03*
X1791979Y1616550D03*
X1795479D03*
X1782654Y1615026D03*
Y1617726D03*
X1784048Y1636875D03*
Y1634375D03*
X1786615Y1631800D03*
X1786588Y1634472D03*
X1786624Y1637021D03*
X1802565Y156557D03*
X1800554Y177229D03*
X1808622Y170869D03*
X1806470Y186866D03*
X1802570Y186913D03*
X1811274Y198098D03*
X1807596Y264133D03*
Y266633D03*
Y269133D03*
X1797674Y274499D03*
X1801174D03*
X1807596Y271633D03*
X1800160Y362542D03*
X1808962Y698055D03*
Y700555D03*
Y703055D03*
X1798462Y698055D03*
X1801962D03*
X1805462D03*
Y700555D03*
X1801962D03*
X1798462D03*
X1805462Y703055D03*
X1801962D03*
X1798462D03*
X1808962Y705555D03*
Y708055D03*
X1798462Y705555D03*
X1801962D03*
X1805462D03*
X1798462Y708055D03*
X1801962D03*
X1805462D03*
X1809002Y710945D03*
Y713445D03*
Y715945D03*
X1805502Y710945D03*
Y713445D03*
Y715945D03*
X1802050Y710940D03*
X1811526Y1281671D03*
X1803029Y1506405D03*
Y1503405D03*
X1812029Y1506405D03*
Y1503405D03*
X1803029Y1509405D03*
Y1512405D03*
X1812029Y1509405D03*
Y1512405D03*
X1797362Y1518304D03*
X1799882Y1520912D03*
Y1518312D03*
X1797362Y1520904D03*
X1804049Y1528031D03*
X1799882Y1523512D03*
X1797362Y1523504D03*
X1799882Y1526112D03*
X1797362Y1526104D03*
X1799994Y1528674D03*
X1797450Y1528768D03*
X1809890Y1524532D03*
X1807290D03*
X1798479Y1575605D03*
X1798879Y1578905D03*
X1801479Y1575605D03*
X1800479Y1572305D03*
X1801879Y1578905D03*
X1798979Y1616550D03*
X1815005Y149325D03*
X1817196Y163797D03*
Y159947D03*
X1818828Y175241D03*
X1817275Y180619D03*
X1813224Y194699D03*
X1816190Y208879D03*
X1817157Y373829D03*
X1828669Y379552D03*
X1816994Y398052D03*
X1816224Y410432D03*
X1822724Y424948D03*
X1815724Y423932D03*
X1825874Y424948D03*
X1822394Y436225D03*
X1827073Y565157D03*
X1824073D03*
X1821073D03*
X1812462Y698055D03*
Y700555D03*
Y703055D03*
Y705555D03*
Y708055D03*
X1812502Y710945D03*
Y713445D03*
Y715945D03*
X1827029Y1506405D03*
Y1503405D03*
Y1509405D03*
Y1512405D03*
X1818475Y1524682D03*
X1815875D03*
X1823649Y1525144D03*
X1831166Y149986D03*
X1827580Y151834D03*
X1829732Y371329D03*
X1828483Y431678D03*
X1833288Y1469639D03*
X1850791Y170287D03*
G54D30*
X180780Y1507509D03*
X178580D03*
X177487Y1521612D03*
X177086Y1518121D03*
X178745Y1513218D03*
X177533Y1535698D03*
Y1537898D03*
X178980Y1540317D03*
X183051Y1544625D03*
X188155Y1516970D03*
X192879D03*
X197604D03*
X189730Y1519698D03*
X194454D03*
X199178D03*
X202328Y1516970D03*
X207052D03*
X211777D03*
X216501D03*
X203903Y1519698D03*
X208627D03*
X213352D03*
X221226Y1516970D03*
X225950D03*
X230674D03*
X218076Y1519698D03*
X222800D03*
X227525D03*
X235399Y1516970D03*
X240123D03*
X244848D03*
X236974Y1519698D03*
X241698D03*
X246422D03*
X232249D03*
X249572Y1516970D03*
X254297D03*
X259021D03*
X251147Y1519698D03*
X255871D03*
X260596D03*
X265421Y1507355D03*
X263321D03*
X266828Y1514073D03*
X266772Y1516336D03*
X267123Y1536640D03*
Y1534540D03*
X267124Y1531618D03*
X267035Y1528698D03*
X266538Y1538658D03*
X305549Y1521612D03*
X305148Y1518121D03*
X305595Y1535698D03*
Y1537898D03*
X316107Y895569D03*
X314256Y905135D03*
Y924269D03*
X316107Y914702D03*
Y933836D03*
Y952970D03*
X314256Y943403D03*
Y962537D03*
X316107Y972104D03*
X314256Y981671D03*
Y1000805D03*
X316107Y991238D03*
X317957Y988049D03*
X317288Y1028056D03*
X313587D03*
X320988D03*
X315437Y1037623D03*
X319138Y1031245D03*
X315437Y1056757D03*
X317288Y1047190D03*
X319138Y1056757D03*
X320988Y1047190D03*
X317288Y1066324D03*
Y1085458D03*
X315437Y1075891D03*
X317288Y1104592D03*
X315437Y1095025D03*
Y1114159D03*
Y1133293D03*
X317288Y1123726D03*
Y1142859D03*
X315437Y1158804D03*
Y1152426D03*
X319138Y1158804D03*
X308893Y1507460D03*
X306807Y1513218D03*
X311113Y1544625D03*
X307042Y1540317D03*
X327209Y882813D03*
X323508D03*
X332760Y988049D03*
X323508Y991238D03*
Y1010372D03*
X324689Y1028056D03*
X332091D03*
X333941Y1031245D03*
X326540Y1044001D03*
X333941Y1056757D03*
X332091Y1047190D03*
X324689Y1053568D03*
X332091Y1161993D03*
X333941Y1165182D03*
X326539D03*
X324689Y1161993D03*
X343862Y886002D03*
X349414Y889191D03*
X345713D03*
Y895569D03*
X349414D03*
X343862Y892380D03*
X342012Y895569D03*
X345713Y908325D03*
X343862Y898758D03*
X349414Y901947D03*
X345713D03*
X343862Y905135D03*
X349414Y908325D03*
X343862Y911513D03*
X340162Y905135D03*
X343862Y917891D03*
X349414Y921080D03*
X345713D03*
X343862Y924269D03*
X345713Y914702D03*
X349414D03*
X340162Y924269D03*
X342012Y914702D03*
X349414Y927458D03*
X345713D03*
X343862Y937025D03*
X349414Y940214D03*
X345713D03*
Y933836D03*
X349414D03*
X343862Y930647D03*
X342012Y933836D03*
X343862Y943403D03*
X349414Y946592D03*
X345713D03*
X343862Y956159D03*
X345713Y952970D03*
X349414D03*
X343862Y949781D03*
X342012Y952970D03*
X340162Y943403D03*
X343862Y962537D03*
X349414Y965726D03*
X345713D03*
X349414Y959348D03*
X345713D03*
X343862Y968915D03*
X340162Y962537D03*
X349414Y984860D03*
X343862Y975293D03*
X349414Y978482D03*
X345713D03*
Y972104D03*
X349414D03*
X342012D03*
X340162Y981671D03*
X343862Y994427D03*
X345713Y997616D03*
X349414D03*
X343862Y1000805D03*
X345713Y991238D03*
X340162Y1000805D03*
X342012Y991238D03*
X338311D03*
X349414D03*
X343862Y988049D03*
X345713Y1010372D03*
X343862Y1007183D03*
X345713Y1003994D03*
X349414D03*
X338311Y1010372D03*
X349414D03*
X343193Y1028056D03*
X350595D03*
X339492D03*
X346894D03*
X350595Y1034434D03*
X346894D03*
X345043Y1037623D03*
X350595Y1040812D03*
X346894D03*
X345043Y1044001D03*
X341343Y1037623D03*
X337642Y1044001D03*
X345043Y1031245D03*
X346894Y1059946D03*
X350595Y1047190D03*
X345043Y1050379D03*
X346894Y1053568D03*
X341343Y1056757D03*
X343193Y1047190D03*
X339492Y1053568D03*
X345043Y1056757D03*
X346894Y1047190D03*
X350595Y1053568D03*
X346894Y1072702D03*
X345043Y1063135D03*
X350595Y1066324D03*
X345043Y1069513D03*
X350595Y1072702D03*
X346894Y1066324D03*
X343193D03*
X345043Y1075891D03*
X350595Y1079080D03*
X346894D03*
X345043Y1082269D03*
X350595Y1085458D03*
X345043Y1088647D03*
X346894Y1085458D03*
X343193D03*
X341343Y1075891D03*
X345043Y1101403D03*
X350595Y1104592D03*
X346894Y1091836D03*
X345043Y1095025D03*
X350595Y1098214D03*
X346894D03*
Y1104592D03*
X350595Y1091836D03*
X341343Y1095025D03*
X343193Y1104592D03*
X346894Y1110970D03*
X345043Y1114159D03*
X350595Y1117348D03*
X346894D03*
X345043Y1107781D03*
X350595Y1110970D03*
X341343Y1114159D03*
X345043Y1120537D03*
X350595Y1123726D03*
X346894Y1130103D03*
X345043Y1133293D03*
Y1126915D03*
X346894Y1123726D03*
X350595Y1130103D03*
X343193Y1123726D03*
X341343Y1133293D03*
X350595Y1136481D03*
X346894D03*
X345043Y1139670D03*
X350595Y1142859D03*
X346894Y1149237D03*
X345043Y1146048D03*
X346894Y1142859D03*
X350595Y1149237D03*
X343193Y1142859D03*
X345043Y1152426D03*
X350595Y1155615D03*
X339492Y1161993D03*
X341343Y1165182D03*
X350595Y1161993D03*
X341343Y1152426D03*
X345043Y1158804D03*
X364217Y876435D03*
X358665Y879624D03*
X351264Y892380D03*
Y911513D03*
Y905135D03*
Y898758D03*
Y924269D03*
Y917891D03*
Y930647D03*
Y937025D03*
Y943403D03*
Y949781D03*
Y956159D03*
Y968915D03*
Y962537D03*
Y981671D03*
Y975293D03*
Y988049D03*
Y1000805D03*
Y994427D03*
X364217Y991238D03*
X358666Y988049D03*
X351264Y1007183D03*
X364217Y1010372D03*
X365398Y1028056D03*
X357996D03*
X352445Y1031245D03*
Y1037623D03*
X363547Y1044001D03*
X359847Y1031245D03*
X352445Y1044001D03*
Y1050379D03*
X359847Y1056757D03*
X357996Y1047190D03*
X365398Y1053568D03*
X352445Y1063135D03*
Y1069513D03*
Y1075891D03*
Y1082269D03*
Y1088647D03*
Y1095025D03*
Y1101403D03*
Y1114159D03*
Y1107781D03*
Y1120537D03*
Y1133293D03*
Y1126915D03*
Y1139670D03*
Y1146048D03*
Y1152426D03*
X359847Y1165182D03*
X357996Y1161993D03*
X352445Y1165182D03*
X365398Y1161993D03*
X367917Y876435D03*
X371618D03*
X379020D03*
X369768Y873246D03*
X373469D03*
X377169D03*
X371618Y882813D03*
X375319D03*
X379020Y889191D03*
X367917Y895569D03*
X366067Y905135D03*
X379020Y901947D03*
X366067Y924269D03*
X367917Y914702D03*
X379020D03*
X367917Y933836D03*
X379020Y927458D03*
X366067Y943403D03*
X367917Y952970D03*
X379020Y946592D03*
X366067Y962537D03*
X379020Y959348D03*
X366067Y981671D03*
X367917Y972104D03*
X379020D03*
X366067Y1000805D03*
X367917Y991238D03*
X375319D03*
X369768Y988049D03*
X379020Y1010372D03*
X375319D03*
X369099Y1028056D03*
X376500D03*
X372799D03*
X367248Y1037623D03*
X378351Y1044001D03*
X370949Y1031245D03*
X367248Y1056757D03*
X369099Y1047190D03*
X370949Y1056757D03*
X372799Y1047190D03*
X376500Y1053568D03*
X369099Y1066324D03*
X380201D03*
X367248Y1075891D03*
X369099Y1085458D03*
X380201Y1079080D03*
Y1091836D03*
X367248Y1095025D03*
X369099Y1104592D03*
X367248Y1114159D03*
X380201Y1110970D03*
X369099Y1123726D03*
X367248Y1133293D03*
X380201Y1123726D03*
Y1149237D03*
X369099Y1142859D03*
X380201Y1136481D03*
X378351Y1165182D03*
X374650D03*
X367248Y1158804D03*
X370949D03*
X369099Y1161993D03*
X372799D03*
X380201D03*
X367248Y1152426D03*
X393823Y876435D03*
X382721D03*
X390122D03*
X380870Y879624D03*
X384571D03*
X380870Y873246D03*
X391973D03*
X395673D03*
Y879624D03*
X391973D03*
Y886002D03*
X393823Y895569D03*
X380870Y886002D03*
X382721Y895569D03*
X390122Y889191D03*
X386421Y895569D03*
X395673Y886002D03*
X393823Y908325D03*
X386421D03*
X382721D03*
X393823Y921080D03*
X382721D03*
X386421D03*
X393823Y940214D03*
X382721D03*
X386421D03*
X380870Y937025D03*
X395673D03*
X388272D03*
X391973D03*
X384571D03*
X393823Y952970D03*
X382721D03*
X386421D03*
X393823Y965726D03*
X382721D03*
X386421D03*
X380870Y981671D03*
X382721Y984860D03*
X388272Y981671D03*
X390122Y984860D03*
X386421Y978482D03*
X393823D03*
X395673Y981671D03*
X382721Y978482D03*
X395673Y994427D03*
Y988049D03*
Y1000805D03*
X380870Y988049D03*
Y994427D03*
X382721Y997616D03*
Y991238D03*
X380870Y1000805D03*
X388272Y994427D03*
X390122Y997616D03*
X388272Y988049D03*
X390122Y991238D03*
X388272Y1000805D03*
X380870Y1007183D03*
X382721Y1003994D03*
X388272Y1007183D03*
X390122Y1003994D03*
X393823Y1010372D03*
X386421D03*
X391303Y1028056D03*
X383902D03*
X382051Y1031245D03*
Y1037623D03*
Y1044001D03*
X391303Y1034434D03*
X389453Y1037623D03*
X391303Y1040812D03*
X389453Y1044001D03*
Y1031245D03*
X383902Y1040812D03*
Y1034434D03*
X395004Y1059946D03*
X383902D03*
X387603D03*
X389453Y1056757D03*
X382051Y1050379D03*
X391303Y1047190D03*
X383902D03*
X391303Y1053568D03*
X389453Y1050379D03*
X383902Y1053568D03*
X385752Y1056757D03*
X382051D03*
X395004Y1072702D03*
X383902D03*
X387603D03*
X395004Y1085458D03*
X383902D03*
X387603D03*
X395004Y1098214D03*
X383902D03*
X387603D03*
X382051Y1101403D03*
X393154D03*
X389453D03*
X385752D03*
X395004Y1117348D03*
X387603D03*
X383902D03*
X395004Y1130103D03*
X387603D03*
X383902D03*
X395004Y1142859D03*
X387603D03*
X383902D03*
X391303Y1149237D03*
X382051Y1152426D03*
X383902Y1161993D03*
X391303D03*
X395004D03*
X393154Y1152426D03*
X393483Y1507355D03*
X391383D03*
X394890Y1514073D03*
X394834Y1516336D03*
X395185Y1536640D03*
Y1534540D03*
X395186Y1531618D03*
X395097Y1528698D03*
X394600Y1538658D03*
X404925Y876435D03*
X401225D03*
X403075Y879624D03*
X406776D03*
X403075Y873246D03*
X397524Y895569D03*
X403075Y886002D03*
X401225Y889191D03*
X408626Y895569D03*
X404925D03*
X406776Y886002D03*
X410477D03*
X399374D03*
X397524Y908325D03*
X408626D03*
X404925Y908324D03*
X397524Y921080D03*
X408626D03*
X404925D03*
X397524Y940214D03*
X410477Y930647D03*
X406776D03*
X408626Y940214D03*
X404925D03*
X403075Y937025D03*
X404925Y933836D03*
X410477Y937025D03*
X408626Y933836D03*
X399374Y937025D03*
X406776D03*
X397524Y952970D03*
X408626D03*
X404925D03*
X397524Y965726D03*
X408626D03*
X404925D03*
X397524Y978482D03*
Y984860D03*
X404925Y978482D03*
X408626D03*
X410477Y981671D03*
X403075D03*
X404925Y984860D03*
X397524Y991238D03*
X410477Y988049D03*
X403075D03*
X404925Y991238D03*
X397524Y997616D03*
X403075Y994427D03*
Y1000805D03*
X401225Y1010372D03*
X397524Y1003994D03*
X406763Y1007175D03*
X403075Y1007183D03*
X406094Y1028064D03*
X402406Y1028056D03*
X406104Y1040820D03*
X404256Y1044001D03*
X398705Y1040812D03*
X406094Y1034442D03*
X404256Y1037623D03*
Y1031245D03*
X402406Y1034434D03*
X396855Y1044001D03*
Y1031245D03*
Y1037623D03*
X398705Y1047190D03*
X406107D03*
X404256Y1050379D03*
X398705Y1059946D03*
Y1053568D03*
X396855Y1050379D03*
Y1056757D03*
X409807Y1059946D03*
X406107D03*
Y1053568D03*
X404256Y1056757D03*
X398705Y1072702D03*
X406107D03*
X409807D03*
X398705Y1085458D03*
X406107D03*
X409807D03*
X398705Y1098214D03*
X406107D03*
X409807D03*
Y1104592D03*
X407957Y1101403D03*
X404256D03*
X396855D03*
X406107Y1104592D03*
X400555Y1101403D03*
X398705Y1117348D03*
X407957Y1107781D03*
X406107Y1117348D03*
X409807D03*
X398705Y1130103D03*
X406107D03*
X409807D03*
X398705Y1142859D03*
X406107D03*
X409807D03*
X402406Y1149237D03*
X404256Y1152426D03*
X406107Y1161993D03*
X402406D03*
X416028Y876435D03*
X412327D03*
X423429D03*
X414177Y873246D03*
X412327Y889191D03*
X425280Y886002D03*
X423429Y889191D03*
X419729Y895569D03*
X416028D03*
X414177Y886002D03*
X419729Y908325D03*
X416028D03*
Y921080D03*
X419729D03*
X417878Y930647D03*
X421579D03*
X416028Y940214D03*
X419729D03*
X416028Y952970D03*
X419729D03*
Y965726D03*
X416028D03*
X412327Y984860D03*
X416028Y978482D03*
X419729D03*
X425280Y981671D03*
X417878D03*
X419729Y984860D03*
X417878Y988049D03*
X425280D03*
X412315Y997608D03*
X412327Y991238D03*
X419716Y997608D03*
X419729Y991238D03*
X413496Y1040820D03*
X420897D03*
X413508Y1047190D03*
X420910D03*
X419059Y1050379D03*
X411658D03*
X413508Y1053568D03*
X411658Y1056757D03*
X420910Y1053568D03*
X419059Y1056757D03*
X417209Y1059946D03*
X420910D03*
X417209Y1072702D03*
X420910D03*
X417209Y1085458D03*
X420910D03*
Y1098214D03*
X417209D03*
X411658Y1101403D03*
Y1107781D03*
X422760D03*
X419059D03*
X420910Y1117348D03*
X417209D03*
X420910Y1130103D03*
X417209D03*
Y1142859D03*
X420910D03*
X413508Y1149237D03*
X424610D03*
Y1161993D03*
X415358Y1152426D03*
X413508Y1161993D03*
X417209D03*
X427130Y876435D03*
X428981Y892380D03*
X432681D03*
X428981Y911513D03*
X432681D03*
X428981Y898758D03*
X432681D03*
X428981Y924269D03*
X432681D03*
X427130Y933836D03*
X430831D03*
X428981Y943403D03*
Y956159D03*
X432681Y943403D03*
Y956159D03*
X428981Y968915D03*
X432681D03*
X427130Y984860D03*
X432681Y981671D03*
X434532Y984860D03*
X432681Y988049D03*
X434532Y991238D03*
X427118Y997608D03*
X427130Y991238D03*
X434519Y997608D03*
X428299Y1040820D03*
X428311Y1047190D03*
X435713D03*
X433862Y1050379D03*
X426461D03*
Y1056757D03*
X428311Y1053568D03*
X433862Y1056757D03*
X435713Y1053568D03*
X430162Y1069513D03*
X433862D03*
X430162Y1082269D03*
X433862D03*
X430162Y1095025D03*
X428311Y1104592D03*
X433862Y1095025D03*
X432012Y1104592D03*
X430162Y1114159D03*
X433862D03*
X430162Y1126915D03*
X433862D03*
X430162Y1139670D03*
Y1146048D03*
X433862Y1139670D03*
Y1146048D03*
Y1158804D03*
X432012Y1161993D03*
X428311D03*
X426461Y1152426D03*
X430162D03*
X433862D03*
X432012Y1155615D03*
X426461Y1158804D03*
X428311Y1155615D03*
X454861Y873246D03*
X453011Y876435D03*
X449310D03*
X451160Y879624D03*
X454861D03*
X451160Y873246D03*
Y886002D03*
X454861D03*
X451160Y892380D03*
X447460D03*
Y886002D03*
X449310Y882813D03*
X451160Y911513D03*
X447460D03*
X451160Y898758D03*
X447460D03*
X451160Y924269D03*
X447460D03*
X453011Y940214D03*
X449310D03*
Y933836D03*
X453011D03*
Y952970D03*
Y946592D03*
X449310Y952970D03*
Y946592D03*
X451160Y943403D03*
Y956159D03*
X447460Y943403D03*
Y956159D03*
X453011Y959348D03*
Y965726D03*
X449310Y959348D03*
Y965726D03*
X451160Y968915D03*
X447460D03*
X453011Y978482D03*
Y972104D03*
X449310Y978482D03*
Y972104D03*
X451160Y981671D03*
X449310Y984860D03*
X449323Y997608D03*
X451160Y988049D03*
X449310Y991238D03*
X450491Y1047190D03*
X452341Y1056757D03*
X450491Y1053568D03*
X452341Y1050379D03*
X448641Y1069513D03*
X452341D03*
X448641Y1082269D03*
X452341D03*
X448641Y1095025D03*
X452341D03*
X450491Y1104592D03*
X454192D03*
X448641Y1114159D03*
X452341D03*
X448641Y1126915D03*
X452341D03*
X448641Y1139670D03*
X452341D03*
X448641Y1146048D03*
X452341D03*
X450491Y1161993D03*
X452341Y1165182D03*
X454192Y1161993D03*
X452341Y1152426D03*
X448640Y1165182D03*
X448641Y1158804D03*
X452341D03*
X450491Y1155615D03*
X444953Y1507509D03*
X442753D03*
X442918Y1513218D03*
X441660Y1521612D03*
X441259Y1518121D03*
X441706Y1535698D03*
Y1537898D03*
X443153Y1540317D03*
X447224Y1544625D03*
X462263Y879624D03*
X458562D03*
Y873246D03*
X462263D03*
X456712Y876435D03*
X467814D03*
X464113D03*
X465964Y879624D03*
Y873246D03*
X460412Y882813D03*
X464113D03*
X469664Y886002D03*
X456712Y889191D03*
X460412Y895569D03*
X465964Y886002D03*
X467814Y889191D03*
X464113Y895569D03*
X462263Y886002D03*
X458562D03*
X456712Y882813D03*
X460412Y908325D03*
X464113D03*
X460412Y921080D03*
X464113D03*
X462263Y937025D03*
X458562D03*
X462263Y930647D03*
X458562D03*
X460412Y940214D03*
X469664Y930647D03*
X464113Y940214D03*
X465964Y930647D03*
X469664Y937025D03*
X462263Y956159D03*
Y943403D03*
Y949781D03*
X458562Y956159D03*
Y943403D03*
Y949781D03*
X469664Y956159D03*
Y943403D03*
Y949781D03*
X460412Y952970D03*
X464113D03*
X462263Y962537D03*
Y968915D03*
X458562Y962537D03*
Y968915D03*
X469664Y962537D03*
Y968915D03*
X460412Y965726D03*
X464113D03*
X462263Y975293D03*
X458562D03*
X469664D03*
X460412Y978482D03*
X458562Y981671D03*
X456712Y984860D03*
X464113Y978482D03*
X465964Y981671D03*
X464113Y984860D03*
X458562Y988049D03*
X456724Y997608D03*
X456712Y991238D03*
X464126Y997608D03*
X465964Y988049D03*
X464113Y991238D03*
X457905Y1040820D03*
X465307D03*
X457893Y1047190D03*
X465294D03*
X459743Y1050379D03*
X465294Y1053568D03*
X467145Y1056757D03*
Y1050379D03*
X457893Y1053568D03*
X461593Y1059946D03*
X459743Y1056757D03*
X465294Y1059946D03*
X461593Y1072702D03*
X465294D03*
X461593Y1085458D03*
X465294D03*
X461593Y1098214D03*
X465294D03*
X459743Y1107781D03*
X461593Y1117348D03*
X463444Y1107781D03*
X465294Y1117348D03*
X461593Y1130103D03*
X465294D03*
X461593Y1142859D03*
X457893Y1149237D03*
X465294Y1142859D03*
X468995Y1149237D03*
X467145Y1165182D03*
X468995Y1161993D03*
X465294D03*
X467145Y1152426D03*
X457893Y1161993D03*
X456042Y1152426D03*
X459743Y1165182D03*
X456042Y1158804D03*
X457893Y1155615D03*
X456042Y1165182D03*
X461593Y1161993D03*
Y1155615D03*
X463444Y1152426D03*
Y1158804D03*
X467145D03*
X468995Y1155615D03*
X463444Y1165182D03*
X484467Y873246D03*
X473365D03*
X477066D03*
X484467Y879624D03*
X477066D03*
X473365D03*
X475215Y876435D03*
X478916D03*
X484467Y886002D03*
X480767D03*
X473365D03*
X477066D03*
X475215Y895569D03*
X471515D03*
X478916Y889191D03*
X482617Y895569D03*
X475215Y908325D03*
X471515D03*
X482617D03*
X475215Y921080D03*
X471515D03*
X482617D03*
X473365Y930647D03*
X471515Y940214D03*
X475215D03*
X482617D03*
X477066Y937025D03*
X480767D03*
X475215Y933836D03*
X471515D03*
X484467Y937025D03*
X473365D03*
X484467Y956159D03*
Y943403D03*
Y949781D03*
X473365Y956159D03*
Y943403D03*
Y949781D03*
X480767Y956159D03*
Y943403D03*
Y949781D03*
X475215Y952970D03*
X471515D03*
X482617D03*
X484467Y962537D03*
Y968915D03*
X473365Y962537D03*
Y968915D03*
X480767Y962537D03*
Y968915D03*
X475215Y965726D03*
X471515D03*
X482617D03*
X484467Y975293D03*
X473365D03*
X480767D03*
X475215Y978482D03*
X471515D03*
X473365Y981671D03*
X471515Y984860D03*
X478916D03*
X482617Y978482D03*
X480767Y981671D03*
X473365Y988049D03*
X471527Y997608D03*
X471515Y991238D03*
X478916Y997616D03*
Y991238D03*
X480767Y994427D03*
Y988049D03*
Y1000805D03*
X478916Y1003994D03*
Y1010372D03*
X480767Y1007183D03*
X483798Y1028056D03*
X472708Y1040820D03*
X481948Y1044001D03*
Y1037623D03*
X480097Y1040812D03*
X483798Y1034434D03*
X478247Y1031245D03*
X472696Y1047190D03*
X480097D03*
X474546Y1050379D03*
Y1056757D03*
X472696Y1053568D03*
Y1059946D03*
X476397D03*
X483798D03*
X481948Y1056757D03*
X480097Y1053568D03*
X481948Y1050379D03*
X476397Y1072702D03*
X472696D03*
X483798D03*
X472696Y1085458D03*
X476397D03*
X483798D03*
X472696Y1098214D03*
X476397D03*
X483798D03*
X478247Y1101403D03*
X472696Y1104592D03*
X481948Y1101403D03*
X476397Y1104592D03*
X470845Y1101403D03*
X474546D03*
X470845Y1107781D03*
X474546D03*
X476397Y1117348D03*
X472696D03*
X483798D03*
X472696Y1130103D03*
X483798D03*
X476396D03*
X472696Y1142859D03*
X476397D03*
X483798D03*
X480097Y1149237D03*
X483798Y1155615D03*
X480097Y1161993D03*
X476397D03*
X478247Y1152426D03*
X470846Y1165182D03*
X481948D03*
X483798Y1161993D03*
X472696Y1155615D03*
X481948Y1152426D03*
X478247Y1158804D03*
X474546D03*
X478247Y1165182D03*
X480097Y1155615D03*
X474546Y1165182D03*
X470845Y1152426D03*
X472696Y1161993D03*
X499271Y879624D03*
X488168Y873246D03*
Y879624D03*
X486318Y876435D03*
X490019D03*
X497420D03*
X495570Y879624D03*
Y886002D03*
X491869D03*
X488168D03*
X490019Y889191D03*
X493719Y895569D03*
X486318D03*
X499271Y886002D03*
X497420Y895569D03*
Y882813D03*
X493719Y908325D03*
X486318D03*
X497420D03*
X493719Y921080D03*
X486318D03*
X497420D03*
X493719Y940214D03*
X486318D03*
X497420D03*
X499271Y937025D03*
X488168D03*
X491869D03*
X495570D03*
Y956159D03*
Y943403D03*
Y949781D03*
X491869Y956159D03*
Y943403D03*
Y949781D03*
X486318Y952970D03*
X493719D03*
X497420D03*
X495570Y962537D03*
Y968915D03*
X491869Y962537D03*
Y968915D03*
X493719Y965726D03*
X486318D03*
X497420D03*
X495570Y975293D03*
X491869D03*
X493719Y978482D03*
X486318D03*
X488168Y981671D03*
X493719Y984860D03*
X486318D03*
X495570Y981671D03*
X497420Y978482D03*
X488168Y988049D03*
Y994427D03*
X486318Y997616D03*
X493719D03*
X486318Y991238D03*
X493719D03*
X488168Y1000805D03*
X495570Y994427D03*
Y988049D03*
Y1000805D03*
X488168Y1007183D03*
X486318Y1003994D03*
Y1010372D03*
X493719Y1003994D03*
Y1010372D03*
X495570Y1007183D03*
X491200Y1028056D03*
X498601D03*
X494901Y1040812D03*
X489349Y1044001D03*
X487499Y1040812D03*
X489349Y1037623D03*
X496751Y1044001D03*
Y1037623D03*
X485649Y1031245D03*
X493050D03*
X491200Y1034434D03*
X498601D03*
X496751Y1050379D03*
X494901Y1047190D03*
X487499D03*
X489349Y1050379D03*
X494901Y1059946D03*
Y1053568D03*
X487499Y1059946D03*
X489349Y1056757D03*
X487499Y1053568D03*
X496751Y1056757D03*
X498601Y1059946D03*
X494901Y1072702D03*
X487499D03*
X498601D03*
X494901Y1085458D03*
X487499D03*
X498601D03*
X494901Y1098214D03*
X487499D03*
X498601D03*
X493050Y1101403D03*
X485649D03*
X489349D03*
X494901Y1117348D03*
X487499D03*
X498601D03*
X487499Y1130103D03*
X494901D03*
X498601D03*
X494901Y1142859D03*
X487499D03*
X491200Y1149237D03*
X498601Y1142859D03*
Y1161993D03*
X487499D03*
X491200D03*
X489349Y1152426D03*
X493050Y1165182D03*
X485649Y1158804D03*
Y1165182D03*
X496751D03*
Y1158804D03*
X489349D03*
X491200Y1155615D03*
X493050Y1152426D03*
X494901Y1161993D03*
Y1155615D03*
X489349Y1165182D03*
X510373Y879624D03*
X514074D03*
X508523Y876435D03*
X506672Y879624D03*
X512223Y876435D03*
X501121D03*
Y889191D03*
X512223Y895569D03*
X501121Y882813D03*
X514074Y905135D03*
X501121Y901947D03*
X512223Y914702D03*
X514074Y924269D03*
X501121Y914702D03*
X512223Y933836D03*
X501121Y927458D03*
X514074Y943403D03*
X512223Y952970D03*
X501121Y946592D03*
X514074Y962537D03*
X501121Y959348D03*
X514074Y981671D03*
X512223Y972104D03*
X501121D03*
Y984860D03*
Y997616D03*
Y991238D03*
X512223D03*
X514074Y1000805D03*
X502971Y994427D03*
X508523Y991238D03*
X501121Y1010372D03*
X512223D03*
X501121Y1003994D03*
X504822Y1010372D03*
X506003Y1028056D03*
X509704D03*
X502302Y1040812D03*
X500452Y1031245D03*
X511554Y1044001D03*
Y1031245D03*
X502302Y1047190D03*
Y1053568D03*
X513405Y1047190D03*
X511554Y1056757D03*
X509704Y1047190D03*
X506003Y1053568D03*
X513405Y1066324D03*
X502302D03*
X513405Y1085458D03*
X502302Y1079080D03*
X513405Y1104592D03*
X502302Y1091836D03*
X500452Y1101403D03*
X502302Y1110970D03*
X513405Y1123726D03*
X502302D03*
X513405Y1142859D03*
X502302Y1136481D03*
Y1149237D03*
X513405Y1161993D03*
X511554Y1158804D03*
X509704Y1161993D03*
X502302D03*
X500452Y1152426D03*
X506003Y1161993D03*
X500452Y1158804D03*
Y1165182D03*
X507853D03*
X504153D03*
X521475Y879624D03*
X519625Y876435D03*
X517775Y879624D03*
X521475Y873246D03*
X517775D03*
X527027Y876435D03*
X528877Y879624D03*
Y892380D03*
X515924Y882813D03*
X527027D03*
X528877Y911513D03*
Y905135D03*
Y898758D03*
Y924269D03*
Y917891D03*
Y930647D03*
Y937025D03*
Y943403D03*
Y949781D03*
Y956159D03*
Y968915D03*
Y962537D03*
Y981671D03*
Y975293D03*
Y988049D03*
Y1000805D03*
X517775Y994427D03*
X523326Y991238D03*
X528877Y994427D03*
Y1007183D03*
X515924Y1010372D03*
X517105Y1028056D03*
X524507D03*
X515255Y1037623D03*
X522656Y1044001D03*
Y1031245D03*
X515255Y1056757D03*
X522656D03*
X524507Y1047190D03*
X517105Y1053568D03*
X515255Y1075891D03*
Y1095025D03*
Y1114159D03*
Y1133293D03*
X528208Y1161993D03*
X515255Y1152426D03*
X524507Y1161993D03*
X520806D03*
X518956Y1158804D03*
X529594Y1507355D03*
X527494D03*
X530727Y876435D03*
X532578Y873246D03*
X536279Y886002D03*
X530727Y889191D03*
X534428D03*
Y895569D03*
X530727D03*
X536279Y892380D03*
X538129Y895569D03*
X539979Y886002D03*
X530727Y882813D03*
X541830D03*
X534428Y908325D03*
X536279Y898758D03*
X530727Y901947D03*
X534428D03*
X536279Y905135D03*
X530727Y908325D03*
X536279Y911513D03*
X539979Y905135D03*
X536279Y917891D03*
X530727Y921080D03*
X534428D03*
X536279Y924269D03*
X534428Y914702D03*
X530727D03*
X539979Y924269D03*
X538129Y914702D03*
X530727Y927458D03*
X534428D03*
X536279Y937025D03*
X530727Y940214D03*
X534428D03*
Y933836D03*
X530727D03*
X536279Y930647D03*
X538129Y933836D03*
X536279Y943403D03*
X530727Y946592D03*
X534428D03*
X536279Y956159D03*
X534428Y952970D03*
X530727D03*
X536279Y949781D03*
X538129Y952970D03*
X539979Y943403D03*
X536279Y962537D03*
X530727Y965726D03*
X534428D03*
X530727Y959348D03*
X534428D03*
X536279Y968915D03*
X539979Y962537D03*
X530727Y984860D03*
X536279Y975293D03*
X530727Y978482D03*
X534428D03*
Y972104D03*
X530727D03*
X538129D03*
X539979Y981671D03*
X536279Y994427D03*
X534428Y997616D03*
X530727D03*
X536279Y1000805D03*
Y988049D03*
X530727Y991238D03*
X539979Y1000805D03*
X538129Y991238D03*
X543680Y994427D03*
X534428Y991238D03*
Y1010372D03*
X536279Y1007183D03*
X534428Y1003994D03*
X530727D03*
X538129Y1010372D03*
X530727D03*
X541830D03*
X531908Y1028056D03*
X543011D03*
X535609D03*
X530058Y1031245D03*
X531908Y1034434D03*
X535609D03*
X537460Y1037623D03*
X530058D03*
X531908Y1040812D03*
X535609D03*
X530058Y1044001D03*
X541160Y1037623D03*
X537460Y1044001D03*
Y1031245D03*
X530058Y1050379D03*
X535609Y1059946D03*
X531908Y1047190D03*
X537460Y1050379D03*
X535609Y1053568D03*
X541160Y1056757D03*
X539310Y1047190D03*
X543011Y1053568D03*
X537460Y1056757D03*
X535609Y1047190D03*
X531908Y1053568D03*
X535609Y1072702D03*
X530058Y1063135D03*
X537460D03*
X531908Y1066324D03*
X530058Y1069513D03*
X537460D03*
X531908Y1072702D03*
X535609Y1066324D03*
X539310D03*
X530058Y1075891D03*
X537460D03*
X531908Y1079080D03*
X535609D03*
X530058Y1082269D03*
X537460D03*
X531908Y1085458D03*
X537460Y1088647D03*
X530058D03*
X535609Y1085458D03*
X539310D03*
X541160Y1075891D03*
X537460Y1101403D03*
X531908Y1104592D03*
X535609Y1091836D03*
X530058Y1095025D03*
X537460D03*
X531908Y1098214D03*
X535609D03*
X530058Y1101403D03*
X535609Y1104592D03*
X531908Y1091836D03*
X541160Y1095025D03*
X539310Y1104592D03*
X535609Y1110970D03*
X530058Y1114159D03*
X537460D03*
X531908Y1117348D03*
X535609D03*
X537460Y1107781D03*
X530058D03*
X531908Y1110970D03*
X541160Y1114159D03*
X530058Y1120537D03*
X537460D03*
X531908Y1123726D03*
X535609Y1130103D03*
X530058Y1133293D03*
X537460D03*
Y1126915D03*
X530058D03*
X535609Y1123726D03*
X531908Y1130103D03*
X539310Y1123726D03*
X541160Y1133293D03*
X531908Y1136481D03*
X535609D03*
X530058Y1139670D03*
X537460D03*
X531908Y1142859D03*
X535609Y1149237D03*
X537460Y1146048D03*
X530058D03*
X535609Y1142859D03*
X531908Y1149237D03*
X539310Y1142859D03*
X530058Y1152426D03*
X537460D03*
X531908Y1155615D03*
X541160Y1152426D03*
X531908Y1161993D03*
X535609D03*
X539310D03*
X537460Y1158804D03*
X541160D03*
X531001Y1514073D03*
X530945Y1516336D03*
X532310Y1536640D03*
X531926Y1534540D03*
X531537Y1531618D03*
X531208Y1528698D03*
X530711Y1538658D03*
X554783Y879624D03*
X556633Y882813D03*
X552932D03*
X554782Y994427D03*
X549231Y991238D03*
X556633Y1010372D03*
X557814Y1028056D03*
X550412D03*
X548562Y1044001D03*
Y1031245D03*
X557814Y1053568D03*
X548562Y1056757D03*
X550412Y1047190D03*
X546712Y1161993D03*
X557814D03*
X544861Y1158804D03*
X562184Y873246D03*
X565885Y879624D03*
X564034Y876435D03*
X573286Y879624D03*
X571436Y876435D03*
X569586Y879624D03*
X564034Y895569D03*
X565885Y886002D03*
X567735Y882813D03*
X565885Y905135D03*
Y924269D03*
X564034Y914702D03*
Y933836D03*
Y952970D03*
X565885Y943403D03*
Y962537D03*
Y981671D03*
X564034Y972104D03*
X565885Y1000805D03*
X564034Y991238D03*
X560334D03*
X564034Y1010372D03*
X567735D03*
X568916Y1028056D03*
X561515D03*
X567066Y1037623D03*
X563365Y1044001D03*
Y1031245D03*
X567066Y1056757D03*
X565215Y1047190D03*
X563365Y1056757D03*
X561515Y1047190D03*
X565215Y1066324D03*
Y1085458D03*
X567066Y1075891D03*
X565215Y1104592D03*
X567066Y1095025D03*
Y1114159D03*
Y1133293D03*
X565215Y1123726D03*
Y1142859D03*
X567066Y1158804D03*
X563365D03*
X567066Y1152426D03*
X572617Y1161993D03*
X570767Y1165182D03*
X567066D03*
X568916Y1161993D03*
X570815Y1507509D03*
X573066Y1507460D03*
X570980Y1513218D03*
X569722Y1521612D03*
X569321Y1518121D03*
X569768Y1535698D03*
Y1537898D03*
X571215Y1540317D03*
X575286Y1544625D03*
X657656Y1507355D03*
X655556D03*
X659063Y1514073D03*
X659007Y1516336D03*
X659358Y1536640D03*
Y1534540D03*
X659359Y1531618D03*
X659270Y1528698D03*
X662353Y1534413D03*
X660877Y1530158D03*
X658773Y1538658D03*
X1184959Y1551121D03*
X1185360Y1554612D03*
X1185406Y1568698D03*
Y1570898D03*
X1196028Y1549970D03*
X1197603Y1552698D03*
X1188653Y1540509D03*
X1186453D03*
X1186618Y1546218D03*
X1186853Y1573317D03*
X1190924Y1577625D03*
X1200752Y1549970D03*
X1205477D03*
X1210201D03*
X1214925D03*
X1202327Y1552698D03*
X1207051D03*
X1211776D03*
X1219650Y1549970D03*
X1224374D03*
X1229099D03*
X1216500Y1552698D03*
X1221225D03*
X1225949D03*
X1243272Y1549970D03*
X1233823D03*
X1238547D03*
X1244847Y1552698D03*
X1230673D03*
X1235398D03*
X1240122D03*
X1247996Y1549970D03*
X1252721D03*
X1257445D03*
X1249571Y1552698D03*
X1254295D03*
X1259020D03*
X1262170Y1549970D03*
X1266894D03*
X1263744Y1552698D03*
X1268469D03*
X1273294Y1540355D03*
X1271194D03*
X1274701Y1547073D03*
X1274645Y1549336D03*
X1274996Y1567540D03*
X1274997Y1564618D03*
X1274908Y1561698D03*
X1274411Y1571658D03*
X1274996Y1569640D03*
X1288549Y876434D03*
X1288548Y1010371D03*
X1289729Y1028055D03*
X1297800Y879623D03*
X1299650Y876434D03*
X1290399Y879623D03*
X1303351Y882812D03*
X1292249Y895568D03*
X1299650Y882812D03*
X1290398Y905134D03*
X1292249Y914701D03*
X1290398Y924268D03*
X1292249Y933835D03*
Y952969D03*
X1290398Y943402D03*
Y962536D03*
X1292249Y972103D03*
X1290398Y981670D03*
X1292249Y991237D03*
X1290398Y1000804D03*
X1299650Y991237D03*
X1294099Y988048D03*
X1299650Y1010371D03*
X1293430Y1028055D03*
X1300831D03*
X1297130D03*
X1291579Y1037622D03*
X1302682Y1044000D03*
X1295280Y1031244D03*
X1291579Y1056756D03*
X1293430Y1047189D03*
X1295280Y1056756D03*
X1297130Y1047189D03*
X1300831Y1053567D03*
X1293430Y1066323D03*
Y1085457D03*
X1291579Y1075890D03*
X1293430Y1104591D03*
X1291579Y1095024D03*
Y1114158D03*
Y1133292D03*
X1293430Y1123725D03*
Y1142858D03*
X1291579Y1158803D03*
X1295280D03*
X1291579Y1152425D03*
X1300831Y1161992D03*
X1302682Y1165181D03*
X1318154Y876434D03*
X1305201Y879623D03*
X1312603D03*
X1316304D03*
X1307052Y876434D03*
X1318154Y895568D03*
X1316304Y905134D03*
Y924268D03*
X1318154Y914701D03*
Y933835D03*
Y952969D03*
X1316304Y943402D03*
Y962536D03*
Y981670D03*
X1318154Y972103D03*
X1316304Y1000804D03*
X1318154Y991237D03*
X1314453D03*
X1308902Y988048D03*
X1314453Y1010371D03*
X1319335Y1028055D03*
X1315634D03*
X1308233D03*
X1317485Y1037622D03*
X1313784Y1044000D03*
X1310083Y1031244D03*
X1317485Y1056756D03*
X1319335Y1047189D03*
X1310083Y1056756D03*
X1308233Y1047189D03*
X1315634Y1053567D03*
X1319335Y1066323D03*
Y1085457D03*
X1317485Y1075890D03*
X1319335Y1104591D03*
X1317485Y1095024D03*
Y1114158D03*
Y1133292D03*
X1319335Y1123725D03*
Y1142858D03*
X1317485Y1152425D03*
X1308233Y1161992D03*
X1310083Y1165181D03*
X1317485D03*
X1315634Y1161992D03*
X1316766Y1540460D03*
X1314515Y1540509D03*
X1314680Y1546218D03*
X1313021Y1551121D03*
X1313422Y1554612D03*
X1313468Y1568698D03*
Y1570898D03*
X1318986Y1577625D03*
X1314915Y1573317D03*
X1323705Y879623D03*
X1327406D03*
X1321855Y876434D03*
X1332957D03*
X1329256D03*
X1334807Y879623D03*
X1320004Y886001D03*
X1325556Y889190D03*
X1321855D03*
X1327406Y892379D03*
X1321855Y895568D03*
X1325556D03*
X1320004Y892379D03*
X1321855Y908324D03*
X1327406Y911512D03*
X1320004Y898757D03*
X1325556Y901946D03*
X1321855D03*
X1327406Y905134D03*
X1320004D03*
X1325556Y908324D03*
X1320004Y911512D03*
X1327406Y898757D03*
X1320004Y917890D03*
X1325556Y921079D03*
X1321855D03*
X1327406Y924268D03*
X1320004D03*
X1321855Y914701D03*
X1325556D03*
X1327406Y917890D03*
X1325556Y927457D03*
X1321855D03*
X1327406Y930646D03*
X1320004Y937024D03*
X1325556Y940213D03*
X1321855D03*
Y933835D03*
X1325556D03*
X1320004Y930646D03*
X1327406Y937024D03*
Y943402D03*
X1320004D03*
X1325556Y946591D03*
X1321855D03*
X1327406Y949780D03*
X1320004Y956158D03*
X1321855Y952969D03*
X1325556D03*
X1320004Y949780D03*
X1327406Y956158D03*
X1320004Y962536D03*
X1325556Y965725D03*
X1321855D03*
X1327406Y968914D03*
X1325556Y959347D03*
X1321855D03*
X1327406Y962536D03*
X1320004Y968914D03*
X1325556Y984859D03*
X1320004Y975292D03*
X1325556Y978481D03*
X1321855D03*
X1327406Y981670D03*
X1321855Y972103D03*
X1325556D03*
X1327406Y975292D03*
Y988048D03*
X1320004Y994426D03*
X1321855Y997615D03*
X1325556D03*
X1327406Y1000804D03*
X1320004D03*
X1321855Y991237D03*
X1327406Y994426D03*
X1334808Y988048D03*
X1325556Y991237D03*
X1320004Y988048D03*
X1321855Y1010371D03*
X1320004Y1007182D03*
X1321855Y1003993D03*
X1325556D03*
X1327406Y1007182D03*
X1325556Y1010371D03*
X1326737Y1028055D03*
X1334138D03*
X1323036D03*
X1328587Y1031244D03*
X1326737Y1034433D03*
X1323036D03*
X1321185Y1037622D03*
X1328587D03*
X1326737Y1040811D03*
X1323036D03*
X1321185Y1044000D03*
X1328587D03*
X1321185Y1031244D03*
X1328587Y1050378D03*
X1323036Y1059945D03*
X1326737Y1047189D03*
X1321185Y1050378D03*
X1323036Y1053567D03*
X1334138Y1047189D03*
X1321185Y1056756D03*
X1323036Y1047189D03*
X1326737Y1053567D03*
X1323036Y1072701D03*
X1328587Y1063134D03*
X1321185D03*
X1326737Y1066323D03*
X1328587Y1069512D03*
X1321185D03*
X1326737Y1072701D03*
X1323036Y1066323D03*
X1328587Y1075890D03*
X1321185D03*
X1326737Y1079079D03*
X1323036D03*
X1328587Y1082268D03*
X1321185D03*
X1326737Y1085457D03*
X1321185Y1088646D03*
X1328587D03*
X1323036Y1085457D03*
X1321185Y1101402D03*
X1326737Y1104591D03*
X1323036Y1091835D03*
X1328587Y1095024D03*
X1321185D03*
X1326737Y1098213D03*
X1323036D03*
X1328587Y1101402D03*
X1323036Y1104591D03*
X1326737Y1091835D03*
X1323036Y1110969D03*
X1328587Y1114158D03*
X1321185D03*
X1326737Y1117347D03*
X1323036D03*
X1321185Y1107780D03*
X1328587D03*
X1326737Y1110969D03*
X1328587Y1120536D03*
X1321185D03*
X1326737Y1123725D03*
X1323036Y1130102D03*
X1328587Y1133292D03*
X1321185D03*
Y1126914D03*
X1328587D03*
X1323036Y1123725D03*
X1326737Y1130102D03*
Y1136480D03*
X1323036D03*
X1328587Y1139669D03*
X1321185D03*
X1326737Y1142858D03*
X1323036Y1149236D03*
X1321185Y1146047D03*
X1328587D03*
X1323036Y1142858D03*
X1326737Y1149236D03*
X1328587Y1152425D03*
X1321185D03*
X1326737Y1155614D03*
X1321185Y1158803D03*
X1334138Y1161992D03*
X1344059Y876434D03*
X1347760D03*
X1340359D03*
X1347760Y882812D03*
X1344059Y895568D03*
X1342209Y905134D03*
X1344059Y914701D03*
X1342209Y924268D03*
X1344059Y933835D03*
X1342209Y943402D03*
X1344059Y952969D03*
X1342209Y962536D03*
Y981670D03*
X1344059Y972103D03*
Y991237D03*
X1342209Y1000804D03*
X1340359Y991237D03*
X1345910Y988048D03*
X1340359Y1010371D03*
X1345241Y1028055D03*
X1341540D03*
X1348941D03*
X1343390Y1037622D03*
X1339689Y1044000D03*
X1335989Y1031244D03*
X1347091D03*
X1345241Y1047189D03*
X1343390Y1056756D03*
X1335989D03*
X1341540Y1053567D03*
X1347091Y1056756D03*
X1348941Y1047189D03*
X1345241Y1066323D03*
X1343390Y1075890D03*
X1345241Y1085457D03*
X1343390Y1095024D03*
X1345241Y1104591D03*
X1343390Y1114158D03*
Y1133292D03*
X1345241Y1123725D03*
Y1142858D03*
X1347091Y1158803D03*
X1348941Y1161992D03*
X1345241D03*
X1343390Y1152425D03*
X1335989Y1165181D03*
X1343390Y1158803D03*
X1341540Y1161992D03*
X1358863Y876434D03*
X1355162D03*
X1351461Y882812D03*
X1357012Y886001D03*
X1362563Y895568D03*
X1358863D03*
X1355162Y889190D03*
X1362563Y908324D03*
X1358863D03*
X1355162Y901946D03*
X1358863Y921079D03*
X1362563D03*
X1355162Y914701D03*
X1362563Y940213D03*
X1358863D03*
X1357012Y937024D03*
X1355162Y927457D03*
X1364414Y937024D03*
X1360713D03*
Y956158D03*
Y943402D03*
Y949780D03*
X1364414Y956158D03*
Y943402D03*
Y949780D03*
X1362563Y952969D03*
X1358863D03*
X1355162Y946591D03*
X1360713Y962536D03*
Y968914D03*
X1364414Y962536D03*
Y968914D03*
X1362563Y965725D03*
X1358863D03*
X1355162Y959347D03*
X1360713Y975292D03*
X1364414D03*
X1357012Y981670D03*
X1364414D03*
X1358863Y984859D03*
X1362563Y978481D03*
X1358863D03*
X1355162Y972103D03*
X1357012Y988048D03*
X1358863Y997615D03*
X1357012Y994426D03*
X1358863Y991237D03*
X1364414Y988048D03*
Y994426D03*
X1357012Y1000804D03*
X1364414D03*
X1351461Y991237D03*
X1357012Y1007182D03*
X1358863Y1003993D03*
X1364414Y1007182D03*
X1355162Y1010371D03*
X1362563D03*
X1351461D03*
X1360044Y1028055D03*
X1352642D03*
X1358193Y1031244D03*
X1360044Y1040811D03*
Y1034433D03*
X1358193Y1037622D03*
Y1044000D03*
X1354493D03*
X1363745Y1059945D03*
X1360044D03*
Y1047189D03*
X1358193Y1050378D03*
X1360044Y1053567D03*
X1361894Y1056756D03*
X1358193D03*
X1352642Y1053567D03*
X1363745Y1072701D03*
X1360044D03*
X1356343Y1066323D03*
X1363745Y1085457D03*
X1360044D03*
X1356343Y1079079D03*
X1363745Y1098213D03*
X1360044D03*
X1356343Y1091835D03*
X1358193Y1101402D03*
X1361894D03*
X1363745Y1117347D03*
X1360044D03*
X1356343Y1110969D03*
X1363745Y1130102D03*
X1360044D03*
X1356343Y1123725D03*
X1360044Y1142858D03*
X1363745D03*
X1356343Y1149236D03*
Y1136480D03*
X1358193Y1152425D03*
X1356343Y1161992D03*
X1360044D03*
X1369965Y876434D03*
X1366264D03*
X1377367D03*
X1368115Y879623D03*
X1371815D03*
X1368115Y886001D03*
X1369965Y895568D03*
X1373666D03*
X1366264Y889190D03*
X1377366D03*
X1379216Y886001D03*
X1371815D03*
X1375516D03*
X1369965Y908324D03*
X1373666D03*
X1369965Y921079D03*
X1373666D03*
X1369965Y940213D03*
X1373666D03*
X1371815Y937024D03*
X1379217D03*
X1368115D03*
X1375516D03*
X1371815Y956158D03*
Y943402D03*
Y949780D03*
X1375516Y956158D03*
Y943402D03*
Y949780D03*
X1369965Y952969D03*
X1373666D03*
X1371815Y962536D03*
Y968914D03*
X1375516Y962536D03*
Y968914D03*
X1369965Y965725D03*
X1373666D03*
X1371815Y975292D03*
X1375516D03*
X1366264Y984859D03*
X1369965Y978481D03*
X1373666D03*
X1371815Y981670D03*
X1379217D03*
X1373666Y984859D03*
Y991237D03*
X1371815Y988048D03*
Y994426D03*
Y1000804D03*
X1366264Y997615D03*
Y991237D03*
X1379217Y988048D03*
Y994426D03*
X1373666Y997615D03*
X1379217Y1000804D03*
X1366264Y1003993D03*
X1379217Y1007182D03*
X1377367Y1010371D03*
X1373666Y1003993D03*
X1369965Y1010371D03*
X1378548Y1028055D03*
X1367445D03*
X1374847Y1040811D03*
X1378548Y1034433D03*
X1372997Y1037622D03*
Y1044000D03*
X1367445Y1040811D03*
Y1034433D03*
X1365595Y1031244D03*
Y1037622D03*
Y1044000D03*
X1372997Y1031244D03*
X1374847Y1047189D03*
Y1053567D03*
X1371146Y1059945D03*
X1372997Y1056756D03*
Y1050378D03*
X1374847Y1059945D03*
X1365595Y1056756D03*
X1367445Y1047189D03*
Y1053567D03*
X1365595Y1050378D03*
X1371146Y1072701D03*
X1374847D03*
Y1085457D03*
X1371146D03*
X1374847Y1098213D03*
X1371146D03*
X1372997Y1101402D03*
X1376697D03*
X1369296D03*
X1365595D03*
X1374847Y1117347D03*
X1371146D03*
Y1130102D03*
X1374847D03*
Y1142858D03*
X1371146D03*
X1378548Y1149236D03*
X1367445D03*
X1369296Y1152425D03*
X1371146Y1161992D03*
X1378548D03*
X1367445D03*
X1388469Y876434D03*
X1392170D03*
X1381067D03*
X1390320Y879623D03*
X1394021D03*
X1381067Y895568D03*
X1384768D03*
X1390319Y886001D03*
X1392170Y895568D03*
X1388469Y889190D03*
X1394021Y886001D03*
X1384768Y908324D03*
X1392170D03*
X1381067Y908323D03*
X1384768Y921079D03*
X1381067D03*
X1392170D03*
X1394020Y937024D03*
X1382918Y930646D03*
X1386619D03*
X1384768Y940213D03*
X1381067D03*
X1394020Y930646D03*
X1392170Y940213D03*
X1381067Y933835D03*
X1386619Y937024D03*
X1384768Y933835D03*
X1382918Y937024D03*
X1394020Y956158D03*
Y943402D03*
Y949780D03*
X1382918Y956158D03*
Y943402D03*
Y949780D03*
X1386619Y956158D03*
Y943402D03*
Y949780D03*
X1384768Y952969D03*
X1381067D03*
X1392170D03*
X1394020Y962536D03*
Y968914D03*
X1382918Y962536D03*
Y968914D03*
X1386619Y962536D03*
Y968914D03*
X1384768Y965725D03*
X1381067D03*
X1392170D03*
X1394020Y975292D03*
X1382918D03*
X1386619D03*
X1381067Y978481D03*
X1384768D03*
X1386619Y981670D03*
X1381067Y984859D03*
X1392170Y978481D03*
X1394020Y981670D03*
X1388469Y984859D03*
X1386619Y988048D03*
X1394020D03*
X1381067Y991237D03*
X1388457Y997607D03*
X1388469Y991237D03*
X1382905Y1007174D03*
X1382236Y1028063D03*
X1380398Y1044000D03*
X1382246Y1040819D03*
X1389638D03*
X1382236Y1034441D03*
X1380398Y1037622D03*
Y1031244D03*
X1382249Y1047189D03*
X1389650D03*
X1380398Y1050378D03*
X1382249Y1059945D03*
Y1053567D03*
X1385949Y1059945D03*
X1380398Y1056756D03*
X1387800D03*
X1393351Y1059945D03*
X1387800Y1050378D03*
X1389650Y1053567D03*
X1382249Y1072701D03*
X1385949D03*
X1393351D03*
X1382249Y1085457D03*
X1385949D03*
X1393351D03*
X1382249Y1098213D03*
X1385949D03*
X1393351D03*
X1385949Y1104591D03*
X1384099Y1101402D03*
X1380398D03*
X1382249Y1104591D03*
X1387800Y1101402D03*
X1384099Y1107780D03*
X1382249Y1117347D03*
X1385949D03*
X1387800Y1107780D03*
X1393351Y1117347D03*
X1385949Y1130102D03*
X1382249D03*
X1393351D03*
X1382249Y1142858D03*
X1385949D03*
X1393351D03*
X1389650Y1149236D03*
X1380398Y1152425D03*
X1382249Y1161992D03*
X1391500Y1152425D03*
X1393351Y1161992D03*
X1389650D03*
X1399571Y876434D03*
X1403272D03*
X1405123Y879623D03*
X1401423D03*
X1401422Y886001D03*
X1395871Y895568D03*
X1399571Y889190D03*
X1408823Y892379D03*
X1405123D03*
X1397722Y886001D03*
X1408824D03*
X1405123D03*
X1395871Y908324D03*
X1408823Y911512D03*
X1405123D03*
X1408823Y898757D03*
X1405123D03*
X1395871Y921079D03*
X1408823Y924268D03*
X1405123D03*
X1403272Y940213D03*
X1406973D03*
X1397721Y937024D03*
Y930646D03*
X1395871Y940213D03*
X1406973Y933835D03*
X1403272D03*
Y952969D03*
Y946591D03*
X1406973Y952969D03*
Y946591D03*
X1397721Y956158D03*
Y943402D03*
Y949780D03*
X1395871Y952969D03*
X1405123Y943402D03*
X1408823D03*
X1405123Y956158D03*
X1408823D03*
X1403272Y959347D03*
Y965725D03*
X1406973Y959347D03*
Y965725D03*
X1397721Y962536D03*
Y968914D03*
X1405123D03*
X1395871Y965725D03*
X1408823Y968914D03*
X1403272Y978481D03*
Y972103D03*
X1406973Y978481D03*
Y972103D03*
X1397721Y975292D03*
X1395871Y978481D03*
X1401422Y981670D03*
X1395871Y984859D03*
X1408823Y981670D03*
X1403272Y984859D03*
X1401422Y988048D03*
X1395858Y997607D03*
X1395871Y991237D03*
X1403260Y997607D03*
X1408823Y988048D03*
X1403272Y991237D03*
X1397039Y1040819D03*
X1404441D03*
X1397052Y1047189D03*
X1404453D03*
X1395201Y1050378D03*
X1402603Y1056756D03*
Y1050378D03*
X1395201Y1056756D03*
X1397052Y1059945D03*
Y1053567D03*
X1404453D03*
X1406304Y1069512D03*
X1397052Y1072701D03*
Y1085457D03*
X1406304Y1082268D03*
X1397052Y1098213D03*
X1406304Y1095024D03*
X1408154Y1104591D03*
X1404453D03*
X1398902Y1107780D03*
X1395201D03*
X1397052Y1117347D03*
X1406304Y1114158D03*
X1397052Y1130102D03*
X1406304Y1126914D03*
X1397052Y1142858D03*
X1400752Y1149236D03*
X1406304Y1139669D03*
Y1146047D03*
X1402603Y1152425D03*
X1400752Y1161992D03*
X1406304Y1152425D03*
X1404453Y1161992D03*
X1408154Y1155614D03*
X1399256Y1540355D03*
X1401356D03*
X1402763Y1547073D03*
X1402707Y1549336D03*
X1403058Y1567540D03*
X1403059Y1564618D03*
X1402970Y1561698D03*
X1402473Y1571658D03*
X1423602Y892379D03*
Y911512D03*
Y898757D03*
Y924268D03*
Y943402D03*
Y956158D03*
Y968914D03*
X1410674Y984859D03*
X1410661Y997607D03*
X1410674Y991237D03*
X1411855Y1047189D03*
X1410004Y1050378D03*
X1411855Y1053567D03*
X1410004Y1056756D03*
Y1069512D03*
Y1082268D03*
Y1095024D03*
Y1114158D03*
Y1126914D03*
Y1139669D03*
Y1146047D03*
Y1152425D03*
Y1158803D03*
X1438405Y879623D03*
X1431003Y873245D03*
X1434704Y879623D03*
Y873245D03*
X1438405D03*
X1429153Y876434D03*
X1432854D03*
X1436554Y882812D03*
X1431003Y886001D03*
X1427302D03*
Y892379D03*
X1432854Y889190D03*
X1436554Y895568D03*
X1438405Y886001D03*
X1427302Y911512D03*
X1436554Y908324D03*
X1427302Y898757D03*
Y924268D03*
X1436554Y921079D03*
X1429153Y933835D03*
X1425452D03*
X1434704Y930646D03*
X1438405D03*
X1436554Y940213D03*
X1427302Y943402D03*
Y956158D03*
X1436554Y952969D03*
X1427302Y968914D03*
X1436554Y965725D03*
X1427302Y981670D03*
X1434704D03*
X1425452Y984859D03*
X1432854D03*
X1436554Y978481D03*
X1434704Y988048D03*
X1425465Y997607D03*
X1432866D03*
X1427302Y988048D03*
X1425452Y991237D03*
X1432854D03*
X1434047Y1040819D03*
X1434035Y1047189D03*
X1426633D03*
X1435885Y1050378D03*
X1428483D03*
X1437735Y1059945D03*
X1435885Y1056756D03*
X1428483D03*
X1426633Y1053567D03*
X1434035D03*
X1428483Y1069512D03*
X1424783D03*
X1437735Y1072701D03*
X1428483Y1082268D03*
X1424783D03*
X1437735Y1085457D03*
X1428483Y1095024D03*
X1424783D03*
X1430334Y1104591D03*
X1426633D03*
X1437735Y1098213D03*
X1428483Y1114158D03*
X1424783D03*
X1435885Y1107780D03*
X1437735Y1117347D03*
X1424783Y1126914D03*
X1428483D03*
X1437735Y1130102D03*
X1428483Y1139669D03*
X1424783D03*
X1434035Y1149236D03*
X1428483Y1146047D03*
X1424783D03*
X1437735Y1142858D03*
X1426633Y1161992D03*
X1424783Y1152425D03*
X1426633Y1155614D03*
X1428483Y1152425D03*
X1432184D03*
X1434035Y1161992D03*
X1430334D03*
X1424783Y1158803D03*
X1432184D03*
X1434035Y1155614D03*
X1428484Y1158803D03*
X1437735Y1155614D03*
X1443956Y876434D03*
X1440255D03*
X1451358D03*
X1449507Y873245D03*
X1453208D03*
X1440255Y882812D03*
X1442106Y886001D03*
X1443956Y889190D03*
X1447657Y895568D03*
X1440255D03*
X1453208Y886001D03*
X1451358Y895568D03*
X1447657Y908324D03*
X1440255D03*
X1451357D03*
X1447657Y921079D03*
X1440255D03*
X1451357D03*
X1445806Y930646D03*
X1449507D03*
X1447657Y940213D03*
X1440255D03*
X1451357D03*
X1442106Y930646D03*
X1453208Y937024D03*
X1445806D03*
X1451357Y933835D03*
X1447657D03*
X1449507Y937024D03*
X1447657Y952969D03*
X1440255D03*
X1451357D03*
X1440255Y965725D03*
X1447657D03*
X1451357D03*
X1440255Y978481D03*
X1447657D03*
X1442106Y981670D03*
X1449507D03*
X1447657Y984859D03*
X1440255D03*
X1451357Y978481D03*
X1449507Y988048D03*
X1440268Y997607D03*
X1447669D03*
X1442106Y988048D03*
X1440255Y991237D03*
X1447657D03*
X1441449Y1040819D03*
X1448850D03*
X1441436Y1047189D03*
X1448838D03*
X1450688Y1050378D03*
Y1056756D03*
X1441436Y1059945D03*
Y1053567D03*
X1443287Y1056756D03*
X1448838Y1053567D03*
X1443287Y1050378D03*
X1448838Y1059945D03*
X1452539D03*
X1441436Y1072701D03*
X1448838D03*
X1452539D03*
X1448838Y1085457D03*
X1441436D03*
X1452539D03*
X1448838Y1098213D03*
X1441436D03*
X1452539D03*
X1448838Y1104591D03*
X1452539D03*
X1446987Y1101402D03*
X1450688D03*
Y1107780D03*
X1446987D03*
X1439586D03*
X1448838Y1117347D03*
X1441436D03*
X1452539D03*
X1448838Y1130102D03*
X1441436D03*
X1452539Y1130103D03*
X1448838Y1142858D03*
X1441436D03*
X1445137Y1149236D03*
X1452539Y1142858D03*
X1446987Y1152425D03*
X1443287Y1165181D03*
X1439586Y1158803D03*
X1443287Y1152425D03*
X1452539Y1161992D03*
X1441436D03*
X1445137D03*
X1448838Y1155614D03*
X1439586Y1152425D03*
X1445137Y1155614D03*
X1443287Y1158803D03*
X1450627Y1540509D03*
X1452827D03*
X1450792Y1546218D03*
X1449133Y1551121D03*
X1449534Y1554612D03*
X1449580Y1568698D03*
Y1570898D03*
X1451027Y1573317D03*
X1462460Y876434D03*
X1455058D03*
X1466161D03*
X1464310Y873245D03*
X1460609D03*
Y879623D03*
X1464310D03*
Y886001D03*
X1458759Y895568D03*
X1462460D03*
X1466161Y889190D03*
X1455058D03*
X1460609Y886001D03*
X1456909D03*
X1468011D03*
X1458759Y908324D03*
X1462460D03*
X1458759Y921079D03*
X1462460D03*
Y940213D03*
X1458759D03*
X1456909Y937024D03*
X1464310D03*
X1460609D03*
X1468011D03*
X1458759Y952969D03*
X1462460D03*
Y965725D03*
X1458759D03*
X1462460Y978481D03*
X1458759D03*
X1464310Y981670D03*
X1456909D03*
X1462460Y984859D03*
X1455058D03*
X1464310Y988048D03*
Y994426D03*
X1456909Y988048D03*
Y994426D03*
X1462460Y997615D03*
Y991237D03*
X1455058Y997615D03*
Y991237D03*
X1456909Y1000804D03*
X1464310D03*
Y1007182D03*
X1456909D03*
X1462460Y1010371D03*
Y1003993D03*
X1455058Y1010371D03*
Y1003993D03*
X1459940Y1028055D03*
X1467342D03*
X1458090Y1037622D03*
Y1044000D03*
X1465491Y1037622D03*
Y1044000D03*
X1463641Y1040811D03*
X1456239D03*
X1459940Y1034433D03*
X1461791Y1031244D03*
X1454389D03*
X1467342Y1034433D03*
X1463641Y1047189D03*
X1456239D03*
X1465491Y1050378D03*
X1456239Y1053567D03*
X1463641D03*
X1458090Y1056756D03*
X1463641Y1059945D03*
X1465491Y1056756D03*
X1458090Y1050378D03*
X1459940Y1059945D03*
X1463641Y1072701D03*
X1459940D03*
X1463641Y1085457D03*
X1459940D03*
X1463641Y1098213D03*
X1459940D03*
X1454389Y1101402D03*
X1461791D03*
X1458090D03*
X1465491D03*
X1459940Y1117347D03*
X1463641D03*
X1459940Y1130102D03*
X1463641D03*
Y1142858D03*
X1459940D03*
X1456239Y1149236D03*
X1467342D03*
X1454389Y1158803D03*
X1467342Y1155614D03*
X1465491Y1158803D03*
X1459940Y1155614D03*
X1465491Y1152425D03*
X1454389D03*
X1467342Y1161992D03*
X1463641D03*
X1456239D03*
X1461791Y1165181D03*
X1458090Y1152425D03*
X1461791Y1158803D03*
X1456239Y1155614D03*
X1455098Y1577625D03*
X1475413Y879623D03*
X1482814D03*
X1473562Y876434D03*
X1477263D03*
X1471712Y873245D03*
X1475413D03*
X1480964Y876434D03*
X1475413Y886001D03*
X1477263Y889190D03*
X1473562Y895568D03*
X1469861D03*
X1471712Y886001D03*
X1469861Y908324D03*
X1473562D03*
X1477263Y901946D03*
X1473562Y921079D03*
X1469861D03*
X1477263Y914701D03*
X1469861Y940213D03*
X1473562D03*
X1477263Y927457D03*
X1475413Y937024D03*
X1471712D03*
X1473562Y952969D03*
X1469861D03*
X1477263Y946591D03*
X1473562Y965725D03*
X1469861D03*
X1477263Y959347D03*
X1471712Y981670D03*
X1473562Y978481D03*
X1469861D03*
Y984859D03*
X1477263Y972103D03*
Y984859D03*
Y991237D03*
X1469861Y997615D03*
Y991237D03*
X1471712Y988048D03*
Y994426D03*
X1477263Y997615D03*
X1471712Y1000804D03*
X1479113Y994426D03*
X1471712Y1007182D03*
X1477263Y1010371D03*
Y1003993D03*
X1469861Y1010371D03*
Y1003993D03*
X1480964Y1010371D03*
X1474743Y1028055D03*
X1482145D03*
X1478444Y1040811D03*
X1471043D03*
X1472893Y1037622D03*
Y1044000D03*
X1474743Y1034433D03*
X1476594Y1031244D03*
X1469192D03*
X1472893Y1050378D03*
X1478444Y1047189D03*
X1471043D03*
X1478444Y1053567D03*
X1472893Y1056756D03*
X1471043Y1053567D03*
X1474743Y1059945D03*
X1471043D03*
X1482145Y1053567D03*
X1478444Y1066323D03*
X1471043Y1072701D03*
X1474743D03*
X1478444Y1079079D03*
X1474743Y1085457D03*
X1471043D03*
X1478444Y1091835D03*
X1476594Y1101402D03*
X1474743Y1098213D03*
X1471043D03*
X1469192Y1101402D03*
X1478444Y1110969D03*
X1474743Y1117347D03*
X1471043D03*
X1478444Y1123725D03*
X1474743Y1130102D03*
X1471043D03*
X1478444Y1136480D03*
X1474743Y1142858D03*
X1471043D03*
X1478444Y1149236D03*
X1472893Y1158803D03*
X1471043Y1155614D03*
Y1161992D03*
X1469192Y1152425D03*
X1476594D03*
X1478444Y1161992D03*
X1474743D03*
X1476594Y1158803D03*
X1476778Y1165778D03*
X1486515Y879623D03*
X1490216D03*
X1484665Y876434D03*
X1488365D03*
Y895568D03*
X1492066Y882812D03*
X1490216Y905134D03*
X1488365Y914701D03*
X1490216Y924268D03*
X1488365Y933835D03*
X1490216Y943402D03*
X1488365Y952969D03*
X1490216Y962536D03*
Y981670D03*
X1488365Y972103D03*
Y991237D03*
X1490216Y1000804D03*
X1493917Y994426D03*
X1484665Y991237D03*
X1488365Y1010371D03*
X1492066D03*
X1493247Y1028055D03*
X1485846D03*
X1491397Y1037622D03*
X1498798Y1044000D03*
Y1031244D03*
X1487696Y1044000D03*
Y1031244D03*
X1489547Y1047189D03*
X1491397Y1056756D03*
X1498798D03*
X1493247Y1053567D03*
X1487696Y1056756D03*
X1485846Y1047189D03*
X1489547Y1066323D03*
X1491397Y1075890D03*
X1489547Y1085457D03*
X1491397Y1095024D03*
X1489547Y1104591D03*
X1491397Y1114158D03*
Y1133292D03*
X1489547Y1123725D03*
Y1142858D03*
X1491397Y1152425D03*
X1489547Y1161992D03*
X1485846D03*
X1487696Y1158803D03*
X1506869Y876434D03*
X1512421Y879623D03*
X1505019D03*
X1512421Y886001D03*
X1506869Y889190D03*
X1510570D03*
X1505019Y892379D03*
X1510570Y895568D03*
X1506869D03*
X1512421Y892379D03*
X1506869Y882812D03*
X1510570Y908324D03*
X1505019Y911512D03*
X1512421Y898757D03*
X1506869Y901946D03*
X1510570D03*
X1505019Y905134D03*
X1512421D03*
X1506869Y908324D03*
X1512421Y911512D03*
X1505019Y898757D03*
X1512421Y917890D03*
X1506869Y921079D03*
X1510570D03*
X1505019Y924268D03*
X1512421D03*
X1510570Y914701D03*
X1506869D03*
X1505019Y917890D03*
X1506869Y927457D03*
X1510570D03*
X1505019Y930646D03*
X1512421Y937024D03*
X1506869Y940213D03*
X1510570D03*
Y933835D03*
X1506869D03*
X1512421Y930646D03*
X1505019Y937024D03*
Y943402D03*
X1512421D03*
X1506869Y946591D03*
X1510570D03*
X1505019Y949780D03*
X1512421Y956158D03*
X1510570Y952969D03*
X1506869D03*
X1512421Y949780D03*
X1505019Y956158D03*
X1512421Y962536D03*
X1506869Y965725D03*
X1510570D03*
X1505019Y968914D03*
X1506869Y959347D03*
X1510570D03*
X1505019Y962536D03*
X1512421Y968914D03*
X1506869Y984859D03*
X1512421Y975292D03*
X1506869Y978481D03*
X1510570D03*
X1505019Y981670D03*
X1510570Y972103D03*
X1506869D03*
X1505019Y975292D03*
Y988048D03*
X1512421Y994426D03*
X1510570Y997615D03*
X1506869D03*
X1505019Y1000804D03*
X1512421D03*
Y988048D03*
X1506869Y991237D03*
X1499468D03*
X1505019Y994426D03*
X1510570Y991237D03*
Y1010371D03*
X1512421Y1007182D03*
X1510570Y1003993D03*
X1506869D03*
X1505019Y1007182D03*
X1506869Y1010371D03*
X1508050Y1028055D03*
X1500649D03*
X1511751D03*
X1506200Y1031244D03*
X1508050Y1034433D03*
X1511751D03*
X1513602Y1037622D03*
X1506200D03*
X1508050Y1040811D03*
X1511751D03*
X1506200Y1044000D03*
X1513602D03*
Y1031244D03*
X1506200Y1050378D03*
X1511751Y1059945D03*
X1508050Y1047189D03*
X1513602Y1050378D03*
X1511751Y1053567D03*
X1500649Y1047189D03*
X1513602Y1056756D03*
X1511751Y1047189D03*
X1508050Y1053567D03*
X1511751Y1072701D03*
X1506200Y1063134D03*
X1513602D03*
X1508050Y1066323D03*
X1506200Y1069512D03*
X1513602D03*
X1508050Y1072701D03*
X1511751Y1066323D03*
X1506200Y1075890D03*
X1513602D03*
X1508050Y1079079D03*
X1511751D03*
X1506200Y1082268D03*
X1513602D03*
X1508050Y1085457D03*
X1513602Y1088646D03*
X1506200D03*
X1511751Y1085457D03*
X1513602Y1101402D03*
X1508050Y1104591D03*
X1511751Y1091835D03*
X1506200Y1095024D03*
X1513602D03*
X1508050Y1098213D03*
X1511751D03*
X1506200Y1101402D03*
X1511751Y1104591D03*
X1508050Y1091835D03*
X1511751Y1110969D03*
X1506200Y1114158D03*
X1513602D03*
X1508050Y1117347D03*
X1511751D03*
X1513602Y1107780D03*
X1506200D03*
X1508050Y1110969D03*
X1506200Y1120536D03*
X1513602D03*
X1508050Y1123725D03*
X1511751Y1130102D03*
X1506200Y1133292D03*
X1513602D03*
Y1126914D03*
X1506200D03*
X1511751Y1123725D03*
X1508050Y1130102D03*
Y1136480D03*
X1511751D03*
X1506200Y1139669D03*
X1513602D03*
X1508050Y1142858D03*
X1511751Y1149236D03*
X1513602Y1146047D03*
X1506200D03*
X1511751Y1142858D03*
X1508050Y1149236D03*
X1506200Y1152425D03*
X1513602D03*
X1508050Y1155614D03*
X1513602Y1158803D03*
X1500649Y1161992D03*
X1504350D03*
X1527224Y873245D03*
X1516121D03*
X1519822D03*
X1514271Y876434D03*
X1523523Y879623D03*
X1525373Y876434D03*
X1516121Y886001D03*
X1514271Y895568D03*
X1516121Y905134D03*
Y924268D03*
X1514271Y914701D03*
Y933835D03*
X1516121Y943402D03*
X1514271Y952969D03*
X1516121Y962536D03*
Y981670D03*
X1514271Y972103D03*
X1516121Y1000804D03*
X1514271Y991237D03*
X1519822Y994426D03*
X1525373Y991237D03*
X1514271Y1010371D03*
X1517972D03*
X1519153Y1028055D03*
X1526554D03*
X1517302Y1037622D03*
X1524704Y1044000D03*
Y1031244D03*
X1517302Y1056756D03*
X1515452Y1047189D03*
X1524704Y1056756D03*
X1526554Y1047189D03*
X1519153Y1053567D03*
X1515452Y1066323D03*
Y1085457D03*
X1517302Y1075890D03*
X1515452Y1104591D03*
X1517302Y1095024D03*
Y1114158D03*
Y1133292D03*
X1515452Y1123725D03*
Y1142858D03*
X1517302Y1152425D03*
X1521003Y1158803D03*
X1515452Y1161992D03*
X1542027Y879623D03*
X1540176Y876434D03*
X1530924Y873245D03*
X1534625Y879623D03*
X1536476Y876434D03*
X1540176Y895568D03*
X1542027Y886001D03*
X1532775Y882812D03*
X1542027Y905134D03*
Y924268D03*
X1540176Y914701D03*
Y933835D03*
Y952969D03*
X1542027Y943402D03*
Y962536D03*
Y981670D03*
X1540176Y972103D03*
X1542027Y1000804D03*
X1540176Y991237D03*
X1530924Y994426D03*
X1536476Y991237D03*
X1540176Y1010371D03*
X1532775D03*
X1533956Y1028055D03*
X1537657D03*
X1543208Y1037622D03*
X1539507Y1044000D03*
Y1031244D03*
X1543208Y1056756D03*
X1541357Y1047189D03*
X1539507Y1056756D03*
X1537657Y1047189D03*
X1533956Y1053567D03*
X1541357Y1066323D03*
Y1085457D03*
X1543208Y1075890D03*
X1541357Y1104591D03*
X1543208Y1095024D03*
Y1114158D03*
Y1133292D03*
X1541357Y1123725D03*
Y1142858D03*
X1533956Y1161992D03*
X1543208Y1158803D03*
X1539507D03*
X1543208Y1152425D03*
X1537657Y1161992D03*
X1530255D03*
X1535368Y1540355D03*
X1537468D03*
X1538875Y1547073D03*
X1538819Y1549336D03*
X1539170Y1567540D03*
X1539171Y1564618D03*
X1539082Y1561698D03*
X1538585Y1571658D03*
X1539170Y1569640D03*
X1549428Y879623D03*
X1545728D03*
X1543877Y1010371D03*
X1545058Y1028055D03*
X1548759Y1161992D03*
X1546909Y1165181D03*
X1580940Y1540460D03*
X1578689Y1540509D03*
X1578854Y1546218D03*
X1577195Y1551121D03*
X1577596Y1554612D03*
X1577642Y1568698D03*
Y1570898D03*
X1583160Y1577625D03*
X1579089Y1573317D03*
X1663430Y1540355D03*
X1665530D03*
X1666937Y1547073D03*
X1666881Y1549336D03*
X1667231Y1567540D03*
X1667232Y1564618D03*
X1667143Y1561698D03*
X1670227Y1567413D03*
X1668750Y1563158D03*
X1666647Y1571658D03*
X1667231Y1569640D03*
G54D41*
X326731Y653394D03*
X363731D03*
X433624Y594259D03*
X754645Y1426892D03*
X766889Y1486756D03*
Y1530256D03*
X1166535Y1412479D03*
X1291146Y1375715D03*
X1320516D03*
X1415690Y601230D03*
X1487677Y640145D03*
X1524437Y640365D03*
X1701285Y198612D03*
X1700840Y1424519D03*
X1731660Y198612D03*
X1770442Y284934D03*
X1800002D03*
G54D25*
X79729Y289822D03*
Y310256D03*
X89729Y289822D03*
X99729D03*
X89729Y310256D03*
X99729D03*
X757184Y1712772D03*
Y1722772D03*
X1072863Y1419176D03*
Y1429176D03*
X1080970Y1650958D03*
Y1660958D03*
X1299439Y92812D03*
Y102812D03*
X1530377Y581353D03*
X1540377D03*
G54D68*
X1233404Y60384D03*
X1241278D03*
X1249152D03*
X1439049Y87432D03*
X1431175D03*
X1446923D03*
G54D23*
X64823Y756832D03*
Y760178D03*
X73933Y768706D03*
X73960Y766090D03*
X69323Y1068052D03*
Y1064706D03*
X94524Y760178D03*
Y756832D03*
X89965D03*
X90015Y766871D03*
X89965Y763525D03*
X94474D03*
X90015Y770218D03*
X85465Y960966D03*
X90965D03*
X103574Y763766D03*
X99024Y1068052D03*
Y1064706D03*
X124224Y760178D03*
Y756832D03*
X119666D03*
X119616Y767166D03*
X119666Y763525D03*
X124174D03*
X119716Y770218D03*
X115166Y960966D03*
X120666D03*
X133124Y763766D03*
X128724Y1068052D03*
Y1064706D03*
X153925Y760178D03*
Y756832D03*
X149366D03*
X149416Y766871D03*
X149366Y763525D03*
X153875D03*
X149416Y770218D03*
X144866Y960966D03*
X150366D03*
X162975Y763766D03*
X158425Y1068052D03*
Y1064706D03*
X183626Y760178D03*
Y756832D03*
X179067D03*
X179117Y766871D03*
X179067Y763525D03*
X183576D03*
X179117Y770218D03*
X174567Y960966D03*
X180067D03*
X186530Y1523953D03*
X192676Y763766D03*
X188126Y780257D03*
Y786950D03*
Y803682D03*
Y793643D03*
Y796989D03*
Y817068D03*
Y810375D03*
Y823761D03*
Y830454D03*
Y833800D03*
Y840493D03*
Y847186D03*
Y853879D03*
Y860572D03*
Y877304D03*
Y867265D03*
Y870611D03*
Y883997D03*
Y890690D03*
Y897383D03*
Y904076D03*
Y907423D03*
Y914115D03*
Y920808D03*
Y927501D03*
Y934194D03*
Y940887D03*
Y950926D03*
Y944234D03*
Y964312D03*
Y957619D03*
Y971005D03*
Y977698D03*
Y984391D03*
Y1001123D03*
Y997777D03*
Y991084D03*
Y1031241D03*
Y1037934D03*
Y1044627D03*
Y1058013D03*
Y1051320D03*
Y1074745D03*
Y1068052D03*
Y1064706D03*
Y1081438D03*
Y1088131D03*
Y1098171D03*
Y1104863D03*
Y1091478D03*
Y1111556D03*
Y1118249D03*
Y1134982D03*
Y1124942D03*
Y1128289D03*
Y1148367D03*
Y1141675D03*
Y1155060D03*
Y1161753D03*
Y1165100D03*
Y1171793D03*
Y1178486D03*
Y1185178D03*
Y1191871D03*
Y1208604D03*
Y1198564D03*
Y1201911D03*
Y1215297D03*
Y1221989D03*
Y1228682D03*
Y1235375D03*
Y1238722D03*
Y1245415D03*
Y1252108D03*
X195979Y1523953D03*
X196530Y1526353D03*
X191805D03*
X187081D03*
X200703Y1523953D03*
X201254Y1526353D03*
X191254Y1523953D03*
X188254Y1544997D03*
X192978D03*
X197703D03*
X188254Y1548397D03*
X192978D03*
X197703D03*
X194196Y1602380D03*
X197596D03*
X194196Y1614292D03*
X197596D03*
X213327Y760178D03*
Y756832D03*
X208768D03*
X204268Y776911D03*
X208768Y763525D03*
X212772Y766871D03*
X213277Y763525D03*
X208818Y770218D03*
X204268Y783604D03*
Y790297D03*
Y800336D03*
Y807029D03*
Y793643D03*
Y813722D03*
Y820415D03*
Y837147D03*
Y830454D03*
Y827108D03*
Y843840D03*
Y850533D03*
Y857226D03*
Y863919D03*
Y873958D03*
Y880651D03*
Y867265D03*
Y887344D03*
Y894037D03*
Y910769D03*
Y904076D03*
Y900730D03*
Y924155D03*
Y917462D03*
Y930848D03*
Y940887D03*
Y937541D03*
Y947580D03*
Y954273D03*
Y960966D03*
Y967659D03*
Y974352D03*
Y981045D03*
Y987737D03*
Y994430D03*
Y1001123D03*
Y1027895D03*
Y1034588D03*
Y1041281D03*
Y1047974D03*
Y1054667D03*
Y1061360D03*
Y1071399D03*
Y1064706D03*
Y1078092D03*
Y1088131D03*
Y1084785D03*
Y1094824D03*
Y1101517D03*
Y1108210D03*
Y1114903D03*
Y1131635D03*
Y1124942D03*
Y1121596D03*
Y1138328D03*
Y1145021D03*
Y1151714D03*
Y1161753D03*
Y1158407D03*
Y1168446D03*
Y1175139D03*
Y1181832D03*
Y1188525D03*
Y1205257D03*
Y1198564D03*
Y1195218D03*
Y1211950D03*
Y1218643D03*
Y1225336D03*
Y1235375D03*
Y1232029D03*
Y1242068D03*
Y1248761D03*
X205427Y1523953D03*
X205978Y1526353D03*
X210703D03*
X210152Y1523953D03*
X214876D03*
X215427Y1526353D03*
X202427Y1544997D03*
X207152D03*
X211876D03*
X216601D03*
X202427Y1548397D03*
X207152D03*
X211876D03*
X216601D03*
X206256Y1602380D03*
X209656D03*
X206256Y1614292D03*
X209656D03*
X222377Y763766D03*
X227540Y960966D03*
X220152Y1526353D03*
X224876D03*
X224325Y1523953D03*
X219601D03*
X229049D03*
X229600Y1526353D03*
X221325Y1544997D03*
X226050D03*
X230774D03*
X221325Y1548397D03*
X226050D03*
X230774D03*
X218316Y1602380D03*
X230376D03*
X221716D03*
X218316Y1614292D03*
X230376D03*
X221716D03*
X238469Y756832D03*
Y763525D03*
X238519Y770218D03*
X233969Y960966D03*
X243223Y1523953D03*
X243774Y1526353D03*
X238498Y1523953D03*
X239049Y1526353D03*
X233774Y1523953D03*
X234325Y1526353D03*
X235499Y1544997D03*
X240223D03*
X244947D03*
X235499Y1548397D03*
X240223D03*
X244947D03*
X242436Y1602380D03*
X233776D03*
X245836D03*
X242436Y1614292D03*
X233776D03*
X245836D03*
X257396Y1523953D03*
X253223Y1526353D03*
X252672Y1523953D03*
X257947Y1526353D03*
X248498D03*
X247947Y1523953D03*
X249671Y1544997D03*
X254396D03*
X259120D03*
X249671Y1548397D03*
X254396D03*
X259120D03*
X254496Y1602380D03*
X257896D03*
X254496Y1614292D03*
X257896D03*
X272525Y108556D03*
X268981D03*
Y111056D03*
X265438Y108556D03*
X261895D03*
Y111056D03*
X265438D03*
X272525D03*
X266556Y1602380D03*
X269956D03*
X266556Y1614292D03*
X269956D03*
X278616Y1602380D03*
X290676D03*
X282016D03*
X278616Y1614292D03*
X290676D03*
X282016D03*
X302736Y1602380D03*
X294076D03*
X306136D03*
X302736Y1614292D03*
X294076D03*
X306136D03*
X306694Y1507279D03*
X319867Y1526353D03*
X315143D03*
X319316Y1523953D03*
X314592D03*
X316316Y1544997D03*
X321040D03*
X316316Y1548397D03*
X321040D03*
X314796Y1602380D03*
X318196D03*
X314796Y1614292D03*
X318196D03*
X324041Y1523953D03*
X324592Y1526353D03*
X328765Y1523953D03*
X329316Y1526353D03*
X334040D03*
X333489Y1523953D03*
X325765Y1544997D03*
X330489D03*
X335214D03*
X325765Y1548397D03*
X330489D03*
X335214D03*
X326856Y1602380D03*
X330256D03*
X326856Y1614292D03*
X330256D03*
X338765Y1526353D03*
X338214Y1523953D03*
X347663D03*
X348214Y1526353D03*
X343489D03*
X342938Y1523953D03*
X339938Y1544997D03*
X344663D03*
X349387D03*
X339938Y1548397D03*
X344663D03*
X349387D03*
X338916Y1602380D03*
X350976D03*
X342316D03*
X338916Y1614292D03*
X350976D03*
X342316D03*
X362387Y1526353D03*
X361836Y1523953D03*
X352387D03*
X352938Y1526353D03*
X357662D03*
X357111Y1523953D03*
X363561Y1544997D03*
X354112D03*
X358836D03*
X363561Y1548397D03*
X354112D03*
X358836D03*
X363036Y1602380D03*
X354376D03*
X363036Y1614292D03*
X354376D03*
X380734Y1523953D03*
X376560Y1526353D03*
X376009Y1523953D03*
X371285D03*
X371836Y1526353D03*
X367111D03*
X366560Y1523953D03*
X368285Y1544997D03*
X373009D03*
X377733D03*
X368285Y1548397D03*
X373009D03*
X377733D03*
X375096Y1602380D03*
X366436D03*
X378496D03*
X375096Y1614292D03*
X366436D03*
X378496D03*
X385458Y1523953D03*
X381285Y1526353D03*
X386009D03*
X382458Y1544997D03*
X387182D03*
X382458Y1548397D03*
X387182D03*
X450703Y1523953D03*
X451254Y1526353D03*
X452427Y1544997D03*
Y1548397D03*
X464876Y1523953D03*
X460703Y1526353D03*
X455978D03*
X465427D03*
X455427Y1523953D03*
X460152D03*
X469600D03*
X470151Y1526353D03*
X457151Y1544997D03*
X461876D03*
X466600D03*
X457151Y1548397D03*
X461876D03*
X466600D03*
X458369Y1602380D03*
X461769D03*
X458369Y1614292D03*
X461769D03*
X474325Y1523953D03*
X474876Y1526353D03*
X483774Y1523953D03*
X484325Y1526353D03*
X479049Y1523953D03*
X479600Y1526353D03*
X471325Y1544997D03*
X476049D03*
X480774D03*
X471325Y1548397D03*
X476049D03*
X480774D03*
X470429Y1602380D03*
X482489D03*
X473829D03*
X470429Y1614292D03*
X482489D03*
X473829D03*
X497947Y1523953D03*
X498498Y1526353D03*
X488498Y1523953D03*
X489049Y1526353D03*
X493222Y1523953D03*
X493773Y1526353D03*
X499672Y1544997D03*
X485498D03*
X490223D03*
X494947D03*
X499672Y1548397D03*
X485498D03*
X490223D03*
X494947D03*
X494549Y1602380D03*
X485889D03*
X497949D03*
X494549Y1614292D03*
X485889D03*
X497949D03*
X507947Y1526353D03*
X507396Y1523953D03*
X512120D03*
X512671Y1526353D03*
X503222D03*
X502671Y1523953D03*
X504396Y1544997D03*
X509120D03*
X513844D03*
X504396Y1548397D03*
X509120D03*
X513844D03*
X506609Y1602380D03*
X510009D03*
X506609Y1614292D03*
X510009D03*
X521569Y1523953D03*
X522120Y1526353D03*
X517396D03*
X516845Y1523953D03*
X518569Y1544997D03*
X523293D03*
X518569Y1548397D03*
X523293D03*
X518669Y1602380D03*
X522069D03*
X518669Y1614292D03*
X522069D03*
X530729Y1602380D03*
X542789D03*
X534129D03*
X530729Y1614292D03*
X542789D03*
X534129D03*
X554849Y1602380D03*
X546189D03*
X558249D03*
X554849Y1614292D03*
X546189D03*
X558249D03*
X566909Y1602380D03*
X570309D03*
X566909Y1614292D03*
X570309D03*
X588765Y1526353D03*
X588214Y1523953D03*
X578765D03*
X583489D03*
X579316Y1526353D03*
X584040D03*
X580489Y1544997D03*
X585213D03*
X580489Y1548397D03*
X585213D03*
X578969Y1602380D03*
X582369D03*
X578969Y1614292D03*
X582369D03*
X602387Y1523953D03*
X602938Y1526353D03*
X592938Y1523953D03*
X593489Y1526353D03*
X598213D03*
X597662Y1523953D03*
X589938Y1544997D03*
X594662D03*
X599387D03*
X604111D03*
X589938Y1548397D03*
X594662D03*
X599387D03*
X604111D03*
X591029Y1602380D03*
X603089D03*
X594429D03*
X591029Y1614292D03*
X603089D03*
X594429D03*
X616560Y1523953D03*
X617111Y1526353D03*
X607111Y1523953D03*
X607662Y1526353D03*
X612387D03*
X611836Y1523953D03*
X608836Y1544997D03*
X613560D03*
X618285D03*
X608836Y1548397D03*
X613560D03*
X618285D03*
X615149Y1602380D03*
X606489D03*
X618549D03*
X615149Y1614292D03*
X606489D03*
X618549D03*
X626009Y1523953D03*
X626560Y1526353D03*
X631284D03*
X630733Y1523953D03*
X621835Y1526353D03*
X621284Y1523953D03*
X627734Y1544997D03*
X632458D03*
X623009D03*
X627734Y1548397D03*
X632458D03*
X623009D03*
X627209Y1602380D03*
X630609D03*
X627209Y1614292D03*
X630609D03*
X642854Y760178D03*
Y756832D03*
X642804Y763525D03*
X644907Y1523953D03*
X640733Y1526353D03*
X640182Y1523953D03*
X635458D03*
X636009Y1526353D03*
X645458D03*
X637182Y1544997D03*
X641906D03*
X646631D03*
X637182Y1548397D03*
X641906D03*
X646631D03*
X639269Y1602380D03*
X642669D03*
X639269Y1614292D03*
X642669D03*
X651905Y763766D03*
X663496Y960966D03*
X657996D03*
X650182Y1526353D03*
X649631Y1523953D03*
X651355Y1544997D03*
Y1548397D03*
X664634Y449952D03*
X667996Y756832D03*
X672555D03*
Y760178D03*
X668046Y766871D03*
X667996Y763525D03*
X672505D03*
X668046Y770218D03*
X677055Y780257D03*
Y786950D03*
Y803682D03*
Y793643D03*
Y796989D03*
Y817068D03*
Y810375D03*
Y823761D03*
Y830454D03*
Y833800D03*
Y840493D03*
Y847186D03*
Y853879D03*
Y860572D03*
Y877304D03*
Y867265D03*
Y870611D03*
Y883997D03*
Y890690D03*
Y897383D03*
Y904076D03*
Y907423D03*
Y914115D03*
Y920808D03*
Y927501D03*
Y934194D03*
Y940887D03*
Y950926D03*
Y944234D03*
Y964312D03*
Y957619D03*
Y971005D03*
Y977698D03*
Y984391D03*
Y1001123D03*
Y997777D03*
Y991084D03*
Y1031241D03*
Y1037934D03*
Y1044627D03*
Y1058013D03*
Y1051320D03*
Y1074745D03*
Y1068052D03*
Y1064706D03*
Y1081438D03*
Y1088131D03*
Y1098171D03*
Y1104863D03*
Y1091478D03*
Y1111556D03*
Y1118249D03*
Y1134982D03*
Y1124942D03*
Y1128289D03*
Y1148367D03*
Y1141675D03*
Y1155060D03*
Y1161753D03*
Y1165100D03*
Y1171793D03*
Y1178486D03*
Y1185178D03*
Y1191871D03*
Y1208604D03*
Y1198564D03*
Y1201911D03*
Y1215297D03*
Y1221989D03*
Y1228682D03*
Y1235375D03*
Y1238722D03*
Y1245415D03*
Y1252108D03*
X695796Y430957D03*
Y437256D03*
Y468672D03*
X693197Y776911D03*
X681606Y763766D03*
X693197Y783604D03*
Y790297D03*
Y800336D03*
Y807029D03*
Y793643D03*
Y813722D03*
Y820415D03*
Y837147D03*
Y830454D03*
Y827108D03*
Y843840D03*
Y850533D03*
Y857226D03*
Y863919D03*
Y873958D03*
Y880651D03*
Y867265D03*
Y887344D03*
Y894037D03*
Y910769D03*
Y904076D03*
Y900730D03*
Y924155D03*
Y917462D03*
Y930848D03*
Y940887D03*
Y937541D03*
Y947580D03*
Y954273D03*
Y960966D03*
Y967659D03*
Y974352D03*
Y981045D03*
Y987737D03*
Y994430D03*
Y1001123D03*
Y1027895D03*
Y1034588D03*
Y1041281D03*
Y1047974D03*
Y1054667D03*
Y1061360D03*
Y1071399D03*
Y1064706D03*
Y1078092D03*
Y1088131D03*
Y1084785D03*
Y1094824D03*
Y1101517D03*
Y1108210D03*
Y1114903D03*
Y1131635D03*
Y1124942D03*
Y1121596D03*
Y1138328D03*
Y1145021D03*
Y1151714D03*
Y1161753D03*
Y1158407D03*
Y1168446D03*
Y1175139D03*
Y1181832D03*
Y1188525D03*
Y1205257D03*
Y1198564D03*
Y1195218D03*
Y1211950D03*
Y1218643D03*
Y1225336D03*
Y1235375D03*
Y1232029D03*
Y1242068D03*
Y1248761D03*
X698599Y115178D03*
X705686D03*
X702142D03*
X698599Y112678D03*
X705686D03*
X702142D03*
X695056D03*
Y115178D03*
X708395Y427807D03*
Y424657D03*
X705245D03*
Y427807D03*
X702095D03*
X708395Y434106D03*
X705245Y430957D03*
X702095Y434106D03*
X698946Y427807D03*
X705245Y437256D03*
X698946Y430957D03*
X705245Y434106D03*
X702095Y430957D03*
X705245Y446705D03*
X708395Y440405D03*
Y443555D03*
X702095Y446705D03*
X705245Y443555D03*
X702095Y437256D03*
Y440405D03*
Y443555D03*
X705245Y440405D03*
X708395Y437256D03*
X698946Y446705D03*
X708395D03*
X698946Y449854D03*
X708395Y462373D03*
Y449854D03*
X705245Y459223D03*
X702095Y456074D03*
Y459223D03*
X708395Y456074D03*
X705245Y462373D03*
X702095D03*
X705245Y456074D03*
X695796Y449854D03*
X708395Y459223D03*
Y465523D03*
X705245Y468672D03*
X702095D03*
X698946Y471822D03*
X702095Y465523D03*
X695796Y471822D03*
X708395Y478121D03*
X705245Y471822D03*
X695796Y465523D03*
X702095Y478121D03*
X705245Y474971D03*
X708395Y471822D03*
Y468672D03*
X705245Y465523D03*
X702095Y471822D03*
X698946Y465523D03*
X705245Y478121D03*
X702095Y474971D03*
X698946Y487570D03*
Y481271D03*
Y484420D03*
X705245Y481271D03*
X702095D03*
X695796Y484420D03*
X708395D03*
Y481271D03*
X697697Y756832D03*
X702256D03*
Y760178D03*
X697747Y766871D03*
X697697Y763525D03*
X702206D03*
X697747Y770218D03*
X706756Y1068052D03*
Y1064706D03*
X720993Y418358D03*
X717843D03*
Y421508D03*
X720993Y430957D03*
X711544D03*
X714694D03*
X717843Y434106D03*
X720993D03*
X717843Y430957D03*
X720993Y421508D03*
X711544Y434106D03*
X714694D03*
X720993Y424657D03*
X717843D03*
Y427807D03*
X714694Y424657D03*
Y427807D03*
X711544Y424657D03*
Y427807D03*
X720993D03*
X717843Y437256D03*
X720993D03*
X714694D03*
X711544D03*
Y443555D03*
X717843D03*
X714694Y446705D03*
Y440405D03*
X720993D03*
X711544D03*
X714694Y443555D03*
X711544Y446705D03*
Y459223D03*
X714694D03*
X717843Y462373D03*
Y456074D03*
Y449854D03*
X714694Y462373D03*
X711544D03*
X714694Y449854D03*
X711544D03*
X714694Y456074D03*
X711544D03*
X720993Y471822D03*
Y468672D03*
X711544Y478121D03*
X717843Y474971D03*
X724143Y471822D03*
X720993Y478121D03*
X717843D03*
X720993Y474971D03*
X714694Y465523D03*
X717843Y471822D03*
Y468672D03*
X714694Y471822D03*
X711544D03*
X714694Y468672D03*
X711544D03*
X720993Y465523D03*
X711544Y474971D03*
X714694Y478121D03*
Y474971D03*
X724143Y481271D03*
X711544Y465523D03*
X717843Y481271D03*
X714694D03*
X720993D03*
X711544D03*
X720993Y484420D03*
X711307Y763766D03*
X722898Y960966D03*
X717398D03*
X731208Y398737D03*
X733512Y418358D03*
X727292D03*
X724143D03*
X736661Y424657D03*
Y430957D03*
Y434106D03*
X733512D03*
Y421508D03*
Y424657D03*
Y430957D03*
X727292D03*
Y434106D03*
X724143Y430957D03*
X727292Y427807D03*
X736661D03*
X727292Y424657D03*
X724143Y434106D03*
Y421508D03*
X739811Y430957D03*
X724143Y427807D03*
Y424657D03*
X733512Y437256D03*
X727292Y440405D03*
X724143Y446705D03*
X736661D03*
X733512Y440405D03*
X736661D03*
X727292Y437256D03*
X724143Y440405D03*
Y437256D03*
X736661D03*
Y459223D03*
Y456074D03*
X733512D03*
Y449854D03*
X736661D03*
X727292Y456074D03*
X724143Y459223D03*
Y456074D03*
X727292Y449854D03*
X724143D03*
X727292Y471822D03*
X724143Y468672D03*
X727292D03*
X736661D03*
X724143Y474971D03*
X733512Y478121D03*
X724143Y465523D03*
X727292D03*
X733512D03*
X736661D03*
X733512Y474971D03*
Y468672D03*
X736661Y478121D03*
Y471822D03*
X724143Y478121D03*
X727292D03*
X733512Y471822D03*
X736661Y474971D03*
Y487570D03*
Y481271D03*
X733512D03*
X727292D03*
X724143Y487570D03*
X727292Y484420D03*
Y487570D03*
X727398Y756832D03*
X731957D03*
Y760178D03*
X727398Y763525D03*
X731462Y766871D03*
X731907Y763525D03*
X727448Y770218D03*
X736457Y1068052D03*
Y1064706D03*
X755559Y421508D03*
X739811Y424657D03*
Y427807D03*
X742961Y424657D03*
Y427807D03*
X746110Y424657D03*
Y427807D03*
X752409Y430957D03*
Y434106D03*
X749260D03*
X752409Y424657D03*
X749260D03*
X746110Y430957D03*
X749260D03*
X742961D03*
X752409Y427807D03*
X749260D03*
X739811Y434106D03*
X742961D03*
X746110D03*
X752409Y443555D03*
X739811Y437256D03*
X746110D03*
X742961D03*
X746110Y440405D03*
X749260Y437256D03*
X739811Y440405D03*
X742961Y443555D03*
Y446705D03*
X752409Y440405D03*
X749260D03*
Y446705D03*
X752409Y437256D03*
Y446705D03*
X746110D03*
Y443555D03*
X749260D03*
X742961Y459223D03*
Y462373D03*
Y456074D03*
Y449854D03*
X752409Y456074D03*
X749260Y449854D03*
X746110Y459223D03*
X752409Y462373D03*
Y459223D03*
X749260D03*
X746110Y456074D03*
Y449854D03*
Y462373D03*
X749260D03*
X752409Y449854D03*
X749260Y456074D03*
X742961Y474971D03*
Y468672D03*
X739811Y478121D03*
Y474971D03*
Y471822D03*
X749260D03*
X739811Y468672D03*
X749260D03*
Y474971D03*
X742961Y471822D03*
X749260Y478121D03*
X746110Y474971D03*
X752409Y468672D03*
X742961Y478121D03*
X746110Y468672D03*
X739811Y465523D03*
X752409Y478121D03*
Y471822D03*
Y465523D03*
X746110D03*
X749260D03*
X752409Y474971D03*
X746110Y478121D03*
Y471822D03*
X749260Y481271D03*
X742961Y484420D03*
X739811Y481271D03*
X746110Y484420D03*
X749260D03*
X752409Y487570D03*
X742961D03*
Y490070D03*
X746110Y481271D03*
X752409D03*
X742961D03*
X741007Y763766D03*
X752599Y960966D03*
X747099D03*
X755559Y418358D03*
X758709D03*
X761858D03*
X755559Y427807D03*
Y430957D03*
X758709Y427807D03*
Y430957D03*
X765008Y424657D03*
X755559D03*
X758709D03*
Y421508D03*
X761858Y424657D03*
X765008Y430957D03*
X755559Y434106D03*
X761858Y430957D03*
Y427807D03*
X758709Y434106D03*
X765008Y427807D03*
Y446705D03*
X758709D03*
X755559Y443555D03*
Y446705D03*
Y437256D03*
X758709Y440405D03*
X755559D03*
X758709Y443555D03*
X761858Y446705D03*
X755559Y449854D03*
Y459223D03*
X765008Y456074D03*
X758709Y465523D03*
X755559Y462373D03*
X758709Y459223D03*
Y462373D03*
Y456074D03*
Y449854D03*
X755559Y478121D03*
Y468672D03*
Y471822D03*
X758709D03*
X761858Y478121D03*
Y474971D03*
Y471822D03*
X758709Y474971D03*
X765008Y471822D03*
Y474971D03*
Y465523D03*
X758709Y478121D03*
X761858Y468672D03*
Y465523D03*
X765008Y468672D03*
X755559Y465523D03*
Y474971D03*
Y481271D03*
Y484420D03*
X765008Y481271D03*
X761858D03*
X758709D03*
X757099Y756832D03*
X761658D03*
Y760178D03*
X757149Y766871D03*
X757099Y763525D03*
X761608D03*
X757149Y770218D03*
X766158Y1068052D03*
Y1064706D03*
X770708Y763766D03*
X782300Y960966D03*
X776800D03*
X786800Y756832D03*
X791358Y760178D03*
Y756832D03*
X786850Y766871D03*
X786800Y763525D03*
X791308D03*
X786850Y770218D03*
X795858Y1068052D03*
Y1064706D03*
X800409Y763765D03*
X812000Y960966D03*
X806500D03*
X816500Y756832D03*
X816550Y770218D03*
X816500Y763525D03*
X998206Y196191D03*
X1000706D03*
X998206Y199735D03*
X1000706D03*
X998206Y206821D03*
X1000706D03*
X998206Y203278D03*
X1000706D03*
X1040965Y756831D03*
Y760177D03*
X1050015Y763765D03*
X1040915Y763524D03*
X1045465Y1068051D03*
Y1064705D03*
X1066107Y756831D03*
X1066157Y766870D03*
X1066107Y763524D03*
X1066157Y770217D03*
X1061607Y960965D03*
X1070666Y756831D03*
Y760177D03*
X1079716Y763765D03*
X1070616Y763524D03*
X1067107Y960965D03*
X1075166Y1068051D03*
Y1064705D03*
X1095808Y756831D03*
X1095858Y766870D03*
X1095808Y763524D03*
X1095858Y770217D03*
X1091308Y960965D03*
X1100366Y756831D03*
Y760177D03*
X1109416Y763765D03*
X1100316Y763524D03*
X1096808Y960965D03*
X1104866Y1068051D03*
Y1064705D03*
X1125508Y756831D03*
X1125558Y766870D03*
X1125508Y763524D03*
X1125558Y770217D03*
X1121008Y960965D03*
X1130067Y756831D03*
Y760177D03*
X1139117Y763765D03*
X1130017Y763524D03*
X1126508Y960965D03*
X1134567Y1068051D03*
Y1064705D03*
X1155209Y756831D03*
Y763524D03*
X1155259Y770217D03*
X1150709Y960965D03*
X1159768Y756831D03*
Y760177D03*
X1168818Y763765D03*
X1159718Y763524D03*
X1164268Y780256D03*
Y786949D03*
Y803681D03*
Y793642D03*
Y796988D03*
Y817067D03*
Y810374D03*
Y823760D03*
Y830453D03*
Y833799D03*
Y840492D03*
Y847185D03*
Y853878D03*
Y860571D03*
Y877303D03*
Y867264D03*
Y870610D03*
Y883996D03*
Y890689D03*
Y897382D03*
Y904075D03*
Y907422D03*
Y914114D03*
Y920807D03*
Y927500D03*
Y934193D03*
Y940886D03*
Y950925D03*
Y944233D03*
Y964311D03*
Y957618D03*
Y971004D03*
X1156209Y960965D03*
X1164268Y977697D03*
Y984390D03*
Y1001122D03*
Y997776D03*
Y991083D03*
Y1031240D03*
Y1037933D03*
Y1044626D03*
Y1058012D03*
Y1051319D03*
Y1074744D03*
Y1068051D03*
Y1064705D03*
Y1081437D03*
Y1088130D03*
Y1098170D03*
Y1104862D03*
Y1091477D03*
Y1111555D03*
Y1118248D03*
Y1134981D03*
Y1124941D03*
Y1128288D03*
Y1148366D03*
Y1141674D03*
Y1155059D03*
Y1161752D03*
Y1165099D03*
Y1171792D03*
Y1178485D03*
Y1185177D03*
Y1191870D03*
Y1208603D03*
Y1198563D03*
Y1201910D03*
Y1215296D03*
Y1221988D03*
Y1228681D03*
Y1235374D03*
Y1238721D03*
Y1245414D03*
Y1252107D03*
X1184910Y756831D03*
X1180410Y776910D03*
X1184910Y763524D03*
X1184960Y770217D03*
X1180410Y783603D03*
Y790296D03*
Y800335D03*
Y807028D03*
Y793642D03*
Y813721D03*
Y820414D03*
Y837146D03*
Y830453D03*
Y827107D03*
Y843839D03*
Y850532D03*
Y857225D03*
Y863918D03*
Y873957D03*
Y880650D03*
Y867264D03*
Y887343D03*
Y894036D03*
Y910768D03*
Y904075D03*
Y900729D03*
Y924154D03*
Y917461D03*
Y930847D03*
Y940886D03*
Y937540D03*
Y947579D03*
Y954272D03*
Y960965D03*
Y967658D03*
Y974351D03*
Y981044D03*
Y987736D03*
Y994429D03*
Y1001122D03*
Y1027894D03*
Y1034587D03*
Y1041280D03*
Y1047973D03*
Y1054666D03*
Y1061359D03*
Y1071398D03*
Y1064705D03*
Y1078091D03*
Y1088130D03*
Y1084784D03*
Y1094823D03*
Y1101516D03*
Y1108209D03*
Y1114902D03*
Y1131634D03*
Y1124941D03*
Y1121595D03*
Y1138327D03*
Y1145020D03*
Y1151713D03*
Y1161752D03*
Y1158406D03*
Y1168445D03*
Y1175138D03*
Y1181831D03*
Y1188524D03*
Y1205256D03*
Y1198563D03*
Y1195217D03*
Y1211949D03*
Y1218642D03*
Y1225335D03*
Y1235374D03*
Y1232028D03*
Y1242067D03*
Y1248760D03*
X1189469Y760177D03*
Y756831D03*
X1198519Y763765D03*
X1188805Y766870D03*
X1189419Y763524D03*
X1194403Y1556953D03*
X1199678Y1559353D03*
X1194954D03*
X1199127Y1556953D03*
X1196127Y1577997D03*
Y1581397D03*
X1214600Y759562D03*
X1205448Y769914D03*
X1214661Y766870D03*
X1214611Y763524D03*
X1214841Y772277D03*
X1210111Y960965D03*
X1203682D03*
X1208576Y1556953D03*
X1204403Y1559353D03*
X1209127D03*
X1203852Y1556953D03*
X1213300D03*
X1213851Y1559353D03*
X1200851Y1577997D03*
X1205576D03*
X1210300D03*
X1215025D03*
X1200851Y1581397D03*
X1205576D03*
X1210300D03*
X1215025D03*
X1202069Y1635380D03*
X1214129D03*
X1205469D03*
X1202069Y1647292D03*
X1214129D03*
X1205469D03*
X1218025Y1556953D03*
X1218576Y1559353D03*
X1227474Y1556953D03*
X1228025Y1559353D03*
X1222749Y1556953D03*
X1223300Y1559353D03*
X1219749Y1577997D03*
X1224474D03*
X1229198D03*
X1219749Y1581397D03*
X1224474D03*
X1229198D03*
X1226189Y1635380D03*
X1217529D03*
X1229589D03*
X1226189Y1647292D03*
X1217529D03*
X1229589D03*
X1241647Y1556953D03*
X1242198Y1559353D03*
X1232198Y1556953D03*
X1232749Y1559353D03*
X1236922Y1556953D03*
X1237473Y1559353D03*
X1243372Y1577997D03*
X1233923D03*
X1238647D03*
X1243372Y1581397D03*
X1233923D03*
X1238647D03*
X1238249Y1635380D03*
X1241649D03*
X1238249Y1647292D03*
X1241649D03*
X1251647Y1559353D03*
X1251096Y1556953D03*
X1255820D03*
X1256371Y1559353D03*
X1246371Y1556953D03*
X1246922Y1559353D03*
X1248096Y1577997D03*
X1252820D03*
X1257544D03*
X1248096Y1581397D03*
X1252820D03*
X1257544D03*
X1250309Y1635380D03*
X1253709D03*
X1250309Y1647292D03*
X1253709D03*
X1265269Y1556953D03*
X1265820Y1559353D03*
X1261096D03*
X1260545Y1556953D03*
X1262269Y1577997D03*
X1266993D03*
X1262269Y1581397D03*
X1266993D03*
X1262369Y1635380D03*
X1274429D03*
X1265769D03*
X1262369Y1647292D03*
X1274429D03*
X1265769D03*
X1286489Y1635380D03*
X1277829D03*
X1289889D03*
X1286489Y1647292D03*
X1277829D03*
X1289889D03*
X1298549Y1635380D03*
X1301949D03*
X1298549Y1647292D03*
X1301949D03*
X1310609Y1635380D03*
X1314009D03*
X1310609Y1647292D03*
X1314009D03*
X1332465Y1559353D03*
X1331914Y1556953D03*
X1322465D03*
X1327189D03*
X1323016Y1559353D03*
X1327740D03*
X1324189Y1577997D03*
X1328913D03*
X1333638D03*
X1324189Y1581397D03*
X1328913D03*
X1333638D03*
X1322669Y1635380D03*
X1334729D03*
X1326069D03*
X1322669Y1647292D03*
X1334729D03*
X1326069D03*
X1346087Y1556953D03*
X1346638Y1559353D03*
X1336638Y1556953D03*
X1337189Y1559353D03*
X1341913D03*
X1341362Y1556953D03*
X1338362Y1577997D03*
X1343087D03*
X1347811D03*
X1338362Y1581397D03*
X1343087D03*
X1347811D03*
X1346789Y1635380D03*
X1338129D03*
X1346789Y1647292D03*
X1338129D03*
X1360260Y1556953D03*
X1360811Y1559353D03*
X1350811Y1556953D03*
X1351362Y1559353D03*
X1356087D03*
X1355536Y1556953D03*
X1352536Y1577997D03*
X1357260D03*
X1361985D03*
X1352536Y1581397D03*
X1357260D03*
X1361985D03*
X1358849Y1635380D03*
X1350189D03*
X1362249D03*
X1358849Y1647292D03*
X1350189D03*
X1362249D03*
X1369709Y1556953D03*
X1370260Y1559353D03*
X1379158Y1556953D03*
X1374984Y1559353D03*
X1374433Y1556953D03*
X1365535Y1559353D03*
X1364984Y1556953D03*
X1371434Y1577997D03*
X1376158D03*
X1366709D03*
X1371434Y1581397D03*
X1376158D03*
X1366709D03*
X1370909Y1635380D03*
X1374309D03*
X1370909Y1647292D03*
X1374309D03*
X1388607Y1556953D03*
X1384433Y1559353D03*
X1383882Y1556953D03*
X1379709Y1559353D03*
X1393882D03*
X1389158D03*
X1393331Y1556953D03*
X1380882Y1577997D03*
X1385606D03*
X1390331D03*
X1380882Y1581397D03*
X1385606D03*
X1390331D03*
X1382969Y1635380D03*
X1386369D03*
X1382969Y1647292D03*
X1386369D03*
X1395055Y1577997D03*
Y1581397D03*
X1458577Y1556953D03*
X1468577Y1559353D03*
X1463852D03*
X1459128D03*
X1463301Y1556953D03*
X1468026D03*
X1460301Y1577997D03*
X1465025D03*
X1460301Y1581397D03*
X1465025D03*
X1466243Y1635380D03*
Y1647292D03*
X1482199Y1556953D03*
X1482750Y1559353D03*
X1472750Y1556953D03*
X1473301Y1559353D03*
X1477474Y1556953D03*
X1478025Y1559353D03*
X1469750Y1577997D03*
X1474474D03*
X1479199D03*
X1483923D03*
X1469750Y1581397D03*
X1474474D03*
X1479199D03*
X1483923D03*
X1478303Y1635380D03*
X1469643D03*
X1481703D03*
X1478303Y1647292D03*
X1469643D03*
X1481703D03*
X1496372Y1556953D03*
X1491648D03*
X1496923Y1559353D03*
X1492199D03*
X1486923Y1556953D03*
X1487474Y1559353D03*
X1488648Y1577997D03*
X1493372D03*
X1498097D03*
X1488648Y1581397D03*
X1493372D03*
X1498097D03*
X1490363Y1635380D03*
X1493763D03*
X1490363Y1647292D03*
X1493763D03*
X1505821Y1556953D03*
X1506372Y1559353D03*
X1511096D03*
X1510545Y1556953D03*
X1501096D03*
X1501647Y1559353D03*
X1507546Y1577997D03*
X1512270D03*
X1502821D03*
X1507546Y1581397D03*
X1512270D03*
X1502821D03*
X1502423Y1635380D03*
X1505823D03*
X1502423Y1647292D03*
X1505823D03*
X1515821Y1559353D03*
X1515270Y1556953D03*
X1519994D03*
X1520545Y1559353D03*
X1525270D03*
X1524719Y1556953D03*
X1516994Y1577997D03*
X1521718D03*
X1526443D03*
X1516994Y1581397D03*
X1521718D03*
X1526443D03*
X1514483Y1635380D03*
X1526543D03*
X1517883D03*
X1514483Y1647292D03*
X1526543D03*
X1517883D03*
X1529443Y1556953D03*
X1529994Y1559353D03*
X1531167Y1577997D03*
Y1581397D03*
X1538603Y1635380D03*
X1529943D03*
X1542003D03*
X1538603Y1647292D03*
X1529943D03*
X1542003D03*
X1550663Y1635380D03*
X1554063D03*
X1550663Y1647292D03*
X1554063D03*
X1562723Y1635380D03*
X1566123D03*
X1562723Y1647292D03*
X1566123D03*
X1586639Y1556953D03*
X1587190Y1559353D03*
X1588363Y1577997D03*
Y1581397D03*
X1586843Y1635380D03*
X1574783D03*
X1578183D03*
X1586843Y1647292D03*
X1574783D03*
X1578183D03*
X1600812Y1556953D03*
X1596639Y1559353D03*
X1596088Y1556953D03*
X1601363Y1559353D03*
X1591363Y1556953D03*
X1591914Y1559353D03*
X1593087Y1577997D03*
X1597812D03*
X1602536D03*
X1593087Y1581397D03*
X1597812D03*
X1602536D03*
X1598903Y1635380D03*
X1590243D03*
X1602303D03*
X1598903Y1647292D03*
X1590243D03*
X1602303D03*
X1610261Y1556953D03*
X1610812Y1559353D03*
X1606087D03*
X1605536Y1556953D03*
X1614985D03*
X1615536Y1559353D03*
X1607261Y1577997D03*
X1611985D03*
X1616710D03*
X1607261Y1581397D03*
X1611985D03*
X1616710D03*
X1610963Y1635380D03*
X1614363D03*
X1610963Y1647292D03*
X1614363D03*
X1618996Y760177D03*
Y756831D03*
X1618946Y763524D03*
X1624434Y1556953D03*
X1624985Y1559353D03*
X1620261D03*
X1619710Y1556953D03*
X1629709Y1559353D03*
X1629158Y1556953D03*
X1621434Y1577997D03*
X1626159D03*
X1630883D03*
X1621434Y1581397D03*
X1626159D03*
X1630883D03*
X1623023Y1635380D03*
X1626423D03*
X1623023Y1647292D03*
X1626423D03*
X1644138Y756831D03*
Y763524D03*
X1644188Y770217D03*
X1639638Y960965D03*
X1634138D03*
X1633883Y1556953D03*
X1634434Y1559353D03*
X1643332Y1556953D03*
X1643883Y1559353D03*
X1639158D03*
X1638607Y1556953D03*
X1635608Y1577997D03*
X1640332D03*
X1645056D03*
X1635608Y1581397D03*
X1640332D03*
X1645056D03*
X1635083Y1635380D03*
X1647143D03*
X1638483D03*
X1635083Y1647292D03*
X1647143D03*
X1638483D03*
X1648697Y760177D03*
Y756831D03*
X1657747Y763765D03*
X1648647Y766870D03*
Y763524D03*
X1653197Y780256D03*
Y786949D03*
Y803681D03*
Y793642D03*
Y796988D03*
Y817067D03*
Y810374D03*
Y823760D03*
Y830453D03*
Y833799D03*
Y840492D03*
Y847185D03*
Y853878D03*
Y860571D03*
Y877303D03*
Y867264D03*
Y870610D03*
Y883996D03*
Y890689D03*
Y897382D03*
Y904075D03*
Y907422D03*
Y914114D03*
Y920807D03*
Y927500D03*
Y934193D03*
Y940886D03*
Y950925D03*
Y944233D03*
Y964311D03*
Y957618D03*
Y971004D03*
Y977697D03*
Y984390D03*
Y1001122D03*
Y997776D03*
Y991083D03*
Y1031240D03*
Y1037933D03*
Y1044626D03*
Y1058012D03*
Y1051319D03*
Y1074744D03*
Y1068051D03*
Y1064705D03*
Y1081437D03*
Y1088130D03*
Y1098170D03*
Y1104862D03*
Y1091477D03*
Y1111555D03*
Y1118248D03*
Y1134981D03*
Y1124941D03*
Y1128288D03*
Y1148366D03*
Y1141674D03*
Y1155059D03*
Y1161752D03*
Y1165099D03*
Y1171792D03*
Y1178485D03*
Y1185177D03*
Y1191870D03*
Y1208603D03*
Y1198563D03*
Y1201910D03*
Y1215296D03*
Y1221988D03*
Y1228681D03*
Y1235374D03*
Y1238721D03*
Y1245414D03*
Y1252107D03*
X1652781Y1556953D03*
X1648607Y1559353D03*
X1648056Y1556953D03*
X1658056Y1559353D03*
X1653332D03*
X1657505Y1556953D03*
X1649780Y1577997D03*
X1654505D03*
X1659229D03*
X1649780Y1581397D03*
X1654505D03*
X1659229D03*
X1650543Y1635380D03*
Y1647292D03*
X1673839Y756831D03*
X1669339Y776910D03*
X1673839Y763524D03*
X1673889Y770217D03*
X1669339Y783603D03*
Y790296D03*
Y800335D03*
Y807028D03*
Y793642D03*
Y813721D03*
Y820414D03*
Y837146D03*
Y830453D03*
Y827107D03*
Y843839D03*
Y850532D03*
Y857225D03*
Y863918D03*
Y873957D03*
Y880650D03*
Y867264D03*
Y887343D03*
Y894036D03*
Y910768D03*
Y904075D03*
Y900729D03*
Y924154D03*
Y917461D03*
Y930847D03*
Y940886D03*
Y937540D03*
Y947579D03*
Y954272D03*
Y960965D03*
Y967658D03*
Y974351D03*
Y981044D03*
Y987736D03*
Y994429D03*
Y1001122D03*
Y1027894D03*
Y1034587D03*
Y1041280D03*
Y1047973D03*
Y1054666D03*
Y1061359D03*
Y1071398D03*
Y1064705D03*
Y1078091D03*
Y1088130D03*
Y1084784D03*
Y1094823D03*
Y1101516D03*
Y1108209D03*
Y1114902D03*
Y1131634D03*
Y1124941D03*
Y1121595D03*
Y1138327D03*
Y1145020D03*
Y1151713D03*
Y1161752D03*
Y1158406D03*
Y1168445D03*
Y1175138D03*
Y1181831D03*
Y1188524D03*
Y1205256D03*
Y1198563D03*
Y1195217D03*
Y1211949D03*
Y1218642D03*
Y1225335D03*
Y1235374D03*
Y1232028D03*
Y1242067D03*
Y1248760D03*
X1678398Y760177D03*
Y756831D03*
X1687448Y763765D03*
X1678348Y766870D03*
Y763524D03*
X1682898Y1068051D03*
Y1064705D03*
X1703540Y756831D03*
X1703590Y766870D03*
X1703540Y763524D03*
X1703590Y770217D03*
X1699040Y960965D03*
X1693540D03*
X1708099Y760177D03*
Y756831D03*
X1717149Y763765D03*
X1708049Y763524D03*
X1712599Y1068051D03*
Y1064705D03*
X1736986Y109723D03*
Y112223D03*
X1733241Y756831D03*
X1733727Y766870D03*
X1733241Y763524D03*
X1733291Y770217D03*
X1728741Y960965D03*
X1723241D03*
X1740529Y112223D03*
Y109723D03*
X1744072Y112223D03*
Y109723D03*
X1747616Y112223D03*
Y109723D03*
X1737800Y756831D03*
Y760177D03*
X1746850Y763765D03*
X1737750Y763524D03*
X1742300Y1068051D03*
Y1064705D03*
X1762942Y756831D03*
X1762992Y766870D03*
X1762942Y763524D03*
X1762992Y770217D03*
X1758442Y960965D03*
X1752942D03*
X1767500Y760177D03*
Y756831D03*
X1767450Y763524D03*
X1772000Y1068051D03*
Y1064705D03*
X1792642Y756831D03*
Y763524D03*
X1792692Y770217D03*
X1788142Y960965D03*
X1782642D03*
G54D43*
X373673Y-28871D03*
Y-18871D03*
D03*
Y-8871D03*
X398673Y-28871D03*
Y-18871D03*
D03*
Y-8871D03*
X718093Y-28871D03*
Y-18871D03*
D03*
Y-8871D03*
X743093Y-28871D03*
Y-18871D03*
D03*
Y-8871D03*
X825152Y-35011D03*
Y-25011D03*
Y-15011D03*
Y-25011D03*
Y-15011D03*
Y-5011D03*
D03*
Y4989D03*
Y14989D03*
D03*
Y4989D03*
Y24989D03*
X850152Y-35011D03*
Y-25011D03*
Y-15011D03*
Y-25011D03*
Y-15011D03*
Y-5011D03*
D03*
Y4989D03*
Y14989D03*
D03*
Y4989D03*
Y24989D03*
X1169572Y-35011D03*
Y-15011D03*
Y-25011D03*
D03*
Y-15011D03*
Y-5011D03*
D03*
Y4989D03*
Y14989D03*
Y4989D03*
Y14989D03*
Y24989D03*
X1194572Y-35011D03*
Y-15011D03*
Y-25011D03*
D03*
Y-15011D03*
Y-5011D03*
D03*
Y4989D03*
Y14989D03*
Y4989D03*
Y14989D03*
Y24989D03*
X1228672Y-35011D03*
Y-25011D03*
Y-15011D03*
Y-25011D03*
Y-15011D03*
Y-5011D03*
D03*
Y4989D03*
Y14989D03*
D03*
Y4989D03*
Y24989D03*
X1253672Y-35011D03*
Y-25011D03*
Y-15011D03*
Y-25011D03*
Y-15011D03*
Y-5011D03*
D03*
Y4989D03*
Y14989D03*
D03*
Y4989D03*
Y24989D03*
X1428431Y-35011D03*
Y-15011D03*
Y-25011D03*
D03*
Y-15011D03*
Y-5011D03*
D03*
Y4989D03*
Y14989D03*
Y4989D03*
Y14989D03*
Y24989D03*
X1453431Y-35011D03*
Y-15011D03*
Y-25011D03*
D03*
Y-15011D03*
Y-5011D03*
D03*
Y4989D03*
Y14989D03*
Y4989D03*
Y14989D03*
Y24989D03*
X1521966Y-29212D03*
D03*
Y-39212D03*
Y-19212D03*
X1546966Y-29212D03*
D03*
Y-39212D03*
Y-19212D03*
X1721725Y-29212D03*
Y-39212D03*
Y-29212D03*
Y-19212D03*
X1746725Y-29212D03*
Y-39212D03*
Y-29212D03*
Y-19212D03*
G54D54*
X793879Y194881D03*
X789942Y204724D03*
X793879Y214567D03*
X805690Y188976D03*
Y220472D03*
X817501Y194881D03*
X821438Y204724D03*
X817501Y214567D03*
X828390Y1420331D03*
X841240Y1407481D03*
X832154Y1411245D03*
Y1429417D03*
X841240Y1433181D03*
X850326Y1411245D03*
Y1429417D03*
X854090Y1420331D03*
X1007154Y1411245D03*
X1003390Y1420331D03*
X1007154Y1429417D03*
X1016240Y1407481D03*
Y1433181D03*
X1025326Y1411245D03*
Y1429417D03*
X1029090Y1420331D03*
X1045848Y194881D03*
X1041911Y204724D03*
X1045848Y214567D03*
X1057659Y188976D03*
Y220472D03*
X1069470Y194881D03*
X1073407Y204724D03*
X1069470Y214567D03*
G54D10*
X3001Y61178D03*
Y127178D03*
Y149178D03*
Y171178D03*
Y193178D03*
Y215178D03*
Y237178D03*
Y259178D03*
Y281178D03*
Y303178D03*
X10875Y323721D03*
Y345721D03*
Y367721D03*
Y389721D03*
Y411721D03*
Y433721D03*
Y455721D03*
Y477721D03*
Y499721D03*
Y521721D03*
X20587Y523970D03*
X16342Y516951D03*
X16512Y533155D03*
X10875Y543721D03*
Y565721D03*
Y587721D03*
Y609721D03*
Y653721D03*
Y675721D03*
Y697721D03*
Y719721D03*
Y741721D03*
Y763721D03*
Y785721D03*
Y807721D03*
Y829721D03*
Y851721D03*
Y873721D03*
Y895721D03*
Y917721D03*
Y939721D03*
Y961721D03*
Y983721D03*
Y1005721D03*
Y1027721D03*
Y1049721D03*
Y1071721D03*
Y1093721D03*
Y1115721D03*
Y1137721D03*
Y1159721D03*
Y1181721D03*
Y1203721D03*
Y1225721D03*
Y1247721D03*
Y1269721D03*
Y1291721D03*
Y1445721D03*
Y1467721D03*
Y1489721D03*
Y1511721D03*
Y1533721D03*
Y1555721D03*
Y1577721D03*
X33184Y523285D03*
X36402Y528675D03*
X33257Y540370D03*
X26887Y541805D03*
X35133Y1603396D03*
X35167Y1610521D03*
X28592Y1617961D03*
X35233Y1623196D03*
X28592Y1639961D03*
Y1661961D03*
Y1683961D03*
X44600Y280357D03*
X50500Y311100D03*
X47602Y1622414D03*
X51333Y1640996D03*
X54584Y8335D03*
Y30335D03*
X58633Y1641388D03*
X85133Y1616396D03*
Y1620896D03*
Y1625396D03*
X85167Y1629905D03*
X101939Y1657742D03*
Y1662728D03*
X120891Y521216D03*
X144610Y429560D03*
X163113Y1486190D03*
X160513Y1479500D03*
Y1484280D03*
X165713Y1479500D03*
Y1484280D03*
X160513Y1501300D03*
Y1506080D03*
X165713D03*
X163113Y1507982D03*
X165713Y1501300D03*
X173488Y1510800D03*
Y1514420D03*
Y1518040D03*
X224055Y127146D03*
X262886Y147391D03*
X274201Y579478D03*
X280621Y1486682D03*
X291175Y1486190D03*
X288575Y1484280D03*
Y1479500D03*
X280621Y1500082D03*
X288575Y1506080D03*
Y1501300D03*
X291175Y1507990D03*
X301747Y121469D03*
Y127469D03*
Y124469D03*
X293775Y1484280D03*
Y1479500D03*
Y1506080D03*
Y1501300D03*
X304606Y1546333D03*
X297323Y1659772D03*
X311754Y121472D03*
Y124472D03*
Y127472D03*
X311476Y1552567D03*
X307255Y1649750D03*
X326475Y182855D03*
X349676Y276708D03*
X349695Y286712D03*
X380181Y236674D03*
X390461Y270694D03*
Y267694D03*
Y275194D03*
X387184Y494382D03*
X390082Y1549178D03*
X404743Y494451D03*
X408683Y1486682D03*
Y1500082D03*
X425555Y92014D03*
Y82014D03*
X412715Y254165D03*
X423730Y249570D03*
X412715Y262165D03*
Y270165D03*
X418543Y494374D03*
X418918Y1006025D03*
Y1013505D03*
Y1009765D03*
Y1024726D03*
Y1020986D03*
Y1028466D03*
Y1017245D03*
X415318Y1032206D03*
X424686Y1484280D03*
Y1479500D03*
Y1506080D03*
Y1501300D03*
X431299Y204145D03*
X432343Y494297D03*
X427286Y1486190D03*
X429886Y1484280D03*
Y1479500D03*
Y1506080D03*
Y1501300D03*
X427286Y1507990D03*
X438732Y1546977D03*
X444090Y116007D03*
X443400Y247880D03*
X448852Y283318D03*
X441159Y1055141D03*
X447587Y1552567D03*
X468228Y70016D03*
X457931Y212703D03*
X465699Y282833D03*
X469323Y306273D03*
X462093Y310123D03*
X467943Y311563D03*
X465153Y310123D03*
X467893Y308643D03*
X458873Y310173D03*
X455813D03*
X462365Y1006025D03*
Y1009765D03*
Y1013505D03*
Y1020986D03*
Y1028466D03*
Y1024726D03*
Y1017245D03*
Y1032206D03*
X462500Y1733500D03*
X480323Y291023D03*
X474691Y306073D03*
X471743Y304923D03*
X473643Y308683D03*
X471003Y311563D03*
X470953Y308643D03*
X484063Y313956D03*
X498776Y209285D03*
Y213285D03*
X500269Y225071D03*
X488908Y242754D03*
X503161Y149895D03*
X514418Y141171D03*
X515151Y220166D03*
X501718Y240558D03*
X508723Y280721D03*
X510223Y289035D03*
X507698D03*
Y297090D03*
X510223D03*
X507698Y305145D03*
X510223D03*
X510606Y314124D03*
X508081D03*
X523831Y95445D03*
Y102931D03*
X519579Y207435D03*
X530418Y141171D03*
X538567Y294777D03*
X542813Y319173D03*
X544794Y1486682D03*
Y1500082D03*
X549800Y147000D03*
X553300Y164500D03*
X556811Y152742D03*
X552699Y291833D03*
X556323Y315273D03*
X558743Y313923D03*
X545873Y319173D03*
X549093Y319123D03*
X558003Y320563D03*
X554943D03*
X552153Y319123D03*
X554893Y317643D03*
X557953D03*
X555348Y1486190D03*
X552748Y1484280D03*
Y1479500D03*
X557948Y1484280D03*
Y1479500D03*
X552748Y1506080D03*
Y1501300D03*
X557948Y1506080D03*
Y1501300D03*
X555348Y1507990D03*
X568472Y149226D03*
X563951Y160644D03*
X567323Y300023D03*
X561691Y315073D03*
X560643Y317683D03*
X568573Y321993D03*
X568779Y1546333D03*
X585685Y178125D03*
X578172Y231393D03*
X587140Y257630D03*
X575524Y261171D03*
X575649Y1552567D03*
X599678Y175534D03*
X595723Y289721D03*
X594698Y298035D03*
X597223D03*
X594698Y314145D03*
X597223D03*
X594698Y306090D03*
X597223D03*
Y322200D03*
X594698D03*
X600520Y401728D03*
X616654Y1382864D03*
X633805Y302289D03*
X642816Y574185D03*
X634529Y674890D03*
X640129D03*
X643649Y674781D03*
X649936Y574185D03*
X660062Y672761D03*
X654676Y674806D03*
X654005Y1548999D03*
X670000Y465844D03*
X672856Y1486682D03*
Y1500082D03*
X719195Y172873D03*
Y177865D03*
X714203Y172873D03*
Y177865D03*
X719195Y196373D03*
X714203D03*
X719195Y184873D03*
Y189865D03*
X714203Y184873D03*
Y189865D03*
Y208207D03*
X719195D03*
Y201365D03*
X714203D03*
Y213199D03*
X719195D03*
X744911Y166887D03*
X749261Y1628208D03*
X754286Y266319D03*
X754291Y269322D03*
X756692Y278942D03*
X765285Y276374D03*
X761510Y1638434D03*
X762030Y1668583D03*
X755408Y1672381D03*
X757557Y1684444D03*
X773457Y249792D03*
X774485Y286879D03*
X791341Y264848D03*
X784261Y1482049D03*
Y1534963D03*
X784277Y1528191D03*
X808469Y1356745D03*
Y1359245D03*
X811272Y1382752D03*
X811767Y1388154D03*
X836163Y279355D03*
X856397Y344669D03*
X865132Y333317D03*
X860152D03*
X861377Y344669D03*
X869406Y753541D03*
X874617Y1084657D03*
X877817D03*
Y1088057D03*
X874617D03*
X881217Y1084657D03*
Y1088057D03*
X874617Y1100957D03*
X877817D03*
Y1097557D03*
X874617D03*
X881217Y1100957D03*
Y1097557D03*
X889057Y1053133D03*
X897754Y1156119D03*
X916268Y277859D03*
X928224Y264072D03*
X942763Y272340D03*
X944820Y1156119D03*
X957421Y157699D03*
X960421D03*
X962243Y179917D03*
X947748Y1146553D03*
X964743Y179917D03*
X963985Y177154D03*
X965520Y1567570D03*
X962520D03*
X968520D03*
X965520Y1582570D03*
X962520D03*
Y1579570D03*
X965520D03*
Y1576570D03*
X962520D03*
X965520Y1573570D03*
X962520D03*
Y1570570D03*
X965520D03*
X968520Y1582570D03*
Y1579570D03*
Y1576570D03*
Y1573570D03*
Y1570570D03*
X965520Y1588570D03*
X962520D03*
Y1585570D03*
X965520D03*
X968520Y1588570D03*
Y1585570D03*
X991553Y216809D03*
X988460Y354725D03*
X992233Y373679D03*
X986356Y1087508D03*
X983156D03*
Y1084108D03*
X986356D03*
X989556Y1087508D03*
Y1084108D03*
X986356Y1097008D03*
X983156D03*
Y1100408D03*
X986356D03*
X989556Y1097008D03*
Y1100408D03*
X1002736Y157943D03*
X999736D03*
X993306Y174953D03*
X993206Y178053D03*
X1006436Y176843D03*
X999916Y184548D03*
X996416D03*
X992506Y184553D03*
X993460Y354725D03*
X998460D03*
X997488Y370287D03*
X994160Y1567710D03*
X997160D03*
X1000160D03*
X994160Y1582710D03*
X997160D03*
Y1579710D03*
X994160D03*
X997160Y1570710D03*
X994160D03*
Y1573710D03*
X997160D03*
X994160Y1576710D03*
X997160D03*
X1000160Y1582710D03*
Y1579710D03*
Y1570710D03*
Y1573710D03*
Y1576710D03*
X994160Y1588710D03*
X997160D03*
Y1585710D03*
X994160D03*
X1000160Y1588710D03*
Y1585710D03*
X1021899Y61590D03*
Y127590D03*
X1011358Y195324D03*
X1008068Y198387D03*
X1019936Y207333D03*
Y210463D03*
X1013306Y528942D03*
X1032354Y538201D03*
X1022686D03*
X1027520Y552724D03*
X1025750Y1567710D03*
X1031750D03*
X1028750D03*
X1025750Y1576710D03*
Y1573710D03*
Y1570710D03*
Y1579710D03*
Y1582710D03*
X1028750Y1576710D03*
Y1573710D03*
Y1570710D03*
Y1579710D03*
Y1582710D03*
X1031750Y1576710D03*
Y1573710D03*
Y1570710D03*
Y1579710D03*
Y1582710D03*
X1025750Y1585710D03*
Y1588710D03*
X1028750Y1585710D03*
Y1588710D03*
X1031750Y1585710D03*
Y1588710D03*
X1059055Y492537D03*
X1057219Y1567883D03*
X1060219D03*
X1063219D03*
X1066219D03*
X1057219Y1576883D03*
Y1573883D03*
Y1570883D03*
Y1579883D03*
Y1582883D03*
X1060219Y1576883D03*
Y1573883D03*
Y1570883D03*
Y1579883D03*
Y1582883D03*
X1063219Y1576883D03*
Y1573883D03*
Y1570883D03*
X1066219Y1576883D03*
Y1573883D03*
Y1570883D03*
Y1579883D03*
X1063219D03*
Y1582883D03*
X1066219D03*
X1057219Y1585883D03*
Y1588883D03*
X1060219Y1585883D03*
Y1588883D03*
X1066219Y1585883D03*
X1063219D03*
Y1588883D03*
X1066219D03*
X1094399Y1568043D03*
X1091399D03*
X1085399D03*
X1088399D03*
X1091399Y1580043D03*
X1094399D03*
Y1571043D03*
Y1574043D03*
Y1577043D03*
X1091399Y1571043D03*
Y1574043D03*
Y1577043D03*
X1088399Y1580043D03*
X1085399D03*
X1088399Y1571043D03*
X1085399D03*
Y1574043D03*
X1088399D03*
X1085399Y1577043D03*
X1088399D03*
X1094399Y1583043D03*
X1091399D03*
X1085399D03*
X1088399D03*
X1094399Y1589043D03*
X1091399D03*
Y1586043D03*
X1094399D03*
X1085399Y1589043D03*
X1088399D03*
Y1586043D03*
X1085399D03*
X1092030Y1715841D03*
Y1725991D03*
X1097399Y1568043D03*
Y1580043D03*
Y1571043D03*
Y1574043D03*
Y1577043D03*
Y1583043D03*
Y1589043D03*
Y1586043D03*
X1170986Y1519190D03*
X1168386Y1517280D03*
Y1512500D03*
Y1534300D03*
Y1539080D03*
X1170986Y1540990D03*
X1173586Y1517280D03*
Y1512500D03*
Y1534300D03*
Y1539080D03*
X1181361Y1543800D03*
Y1547420D03*
Y1551040D03*
X1172603Y1554561D03*
X1188472Y80165D03*
X1197980Y1688270D03*
X1213072Y1682899D03*
X1207770Y1717011D03*
Y1731011D03*
X1226094Y297066D03*
X1288494Y1519682D03*
Y1533082D03*
X1304705Y79807D03*
X1303266Y533713D03*
Y530413D03*
X1300200Y590600D03*
X1299048Y1519190D03*
X1296448Y1517280D03*
Y1512500D03*
X1301648Y1517280D03*
Y1512500D03*
X1296448Y1534300D03*
X1301648D03*
X1296448Y1539080D03*
X1301648D03*
X1299048Y1540990D03*
X1309185Y74748D03*
X1316266Y564514D03*
X1317266Y589522D03*
X1318300Y640000D03*
Y643000D03*
Y649000D03*
Y646000D03*
X1318363Y1411404D03*
X1312700Y1579596D03*
X1319349Y1585567D03*
X1330820Y525165D03*
X1330758Y521749D03*
X1330820Y518265D03*
X1330658Y538749D03*
X1330758Y528649D03*
X1330773Y531776D03*
X1330758Y535449D03*
X1329673Y552509D03*
X1332673D03*
X1326673Y544909D03*
X1329673Y545909D03*
Y549309D03*
X1330658Y542949D03*
X1332673Y545909D03*
Y549309D03*
X1329673Y558709D03*
Y555709D03*
X1332673D03*
X1325366Y589522D03*
X1321300Y643000D03*
Y640000D03*
Y649000D03*
Y646000D03*
X1326433Y1214334D03*
X1335260Y236594D03*
Y246594D03*
Y241594D03*
Y251594D03*
X1348611Y1212963D03*
Y1218463D03*
X1364239Y1207949D03*
X1391460Y1032205D03*
X1388918Y1687878D03*
X1382045Y1712038D03*
Y1708038D03*
X1384604Y1728318D03*
X1393179Y1733118D03*
X1404917Y109037D03*
X1395060Y1009764D03*
Y1006024D03*
Y1013504D03*
Y1020985D03*
Y1024725D03*
Y1028465D03*
Y1017244D03*
X1397955Y1582178D03*
X1405058Y1639607D03*
X1417301Y1055140D03*
X1416556Y1519682D03*
Y1533082D03*
X1418740Y1622902D03*
X1427973Y60409D03*
X1438507Y1006024D03*
Y1009764D03*
Y1013504D03*
Y1024725D03*
Y1020985D03*
Y1017244D03*
Y1028465D03*
Y1032205D03*
X1435160Y1519190D03*
X1432560Y1517280D03*
Y1512500D03*
X1437760Y1517280D03*
Y1512500D03*
X1432560Y1534300D03*
X1437760D03*
X1432560Y1539080D03*
X1437760D03*
X1435160Y1540990D03*
X1433979Y1655655D03*
X1441141Y53699D03*
X1448505Y1579725D03*
X1455461Y1585567D03*
X1528993Y4115D03*
Y26115D03*
X1534067Y1582178D03*
X1552668Y1519682D03*
Y1533082D03*
X1568176Y568423D03*
X1570676D03*
X1565676D03*
X1561376Y572258D03*
X1566010Y673210D03*
X1562730Y675180D03*
X1563222Y1519190D03*
X1560622Y1517280D03*
Y1512500D03*
X1565822Y1517280D03*
Y1512500D03*
X1560622Y1534300D03*
X1565822D03*
X1560622Y1539080D03*
X1565822D03*
X1563222Y1540990D03*
X1586291Y306746D03*
X1584160Y558973D03*
X1576653Y1579333D03*
X1583523Y1585567D03*
X1606535Y553297D03*
X1607369Y561330D03*
X1631889Y521480D03*
X1618884Y533388D03*
X1632798Y544564D03*
X1622391Y564169D03*
X1627242Y1436148D03*
X1627181Y1448016D03*
X1636929Y524690D03*
Y528190D03*
Y531690D03*
Y535190D03*
Y538690D03*
X1639868Y542444D03*
X1636783Y542604D03*
X1635798Y545564D03*
X1638798D03*
Y548964D03*
Y552164D03*
X1635798D03*
Y548964D03*
Y555364D03*
X1638798D03*
X1635798Y558364D03*
X1648029Y1718759D03*
Y1733909D03*
X1652525Y141762D03*
X1662129Y1582178D03*
X1673100Y126762D03*
X1676971Y1668582D03*
X1686154Y434160D03*
X1685298Y1451231D03*
X1680730Y1519682D03*
Y1533082D03*
X1688243Y1663802D03*
X1682724Y1717701D03*
X1704444Y407045D03*
X1707444D03*
X1697914Y427155D03*
X1698014Y424055D03*
X1701124Y433650D03*
X1697214Y433655D03*
X1704624Y433650D03*
X1704822Y1694243D03*
X1702985Y1700328D03*
X1711144Y425945D03*
X1722149Y1715265D03*
X1719149Y1703190D03*
X1722149Y1730415D03*
X1724263Y1681465D03*
X1752250Y303850D03*
X1749329Y1662956D03*
X1743329Y1668956D03*
X1743153Y1662956D03*
X1749329Y1674956D03*
X1743329D03*
X1754850Y303930D03*
X1755329Y1668956D03*
Y1662956D03*
Y1674956D03*
X1763463Y1691465D03*
X1758963Y1691565D03*
X1787390Y161834D03*
X1800040Y164393D03*
X1797719Y186610D03*
X1811668Y218900D03*
X1811606Y222513D03*
X1808429Y218837D03*
X1811606Y226438D03*
X1808367Y222450D03*
X1810479Y211850D03*
X1810509Y214660D03*
X1808260Y213232D03*
X1808367Y226375D03*
X1825111Y164393D03*
X1813079Y211850D03*
X1813109Y214660D03*
G54D17*
X18960Y1598181D03*
X440029Y240381D03*
X434420Y239930D03*
X934302Y578318D03*
X1769420Y19506D03*
X1777420D03*
Y24506D03*
G54D19*
X35852Y673010D03*
Y675510D03*
Y697322D03*
Y694822D03*
Y705728D03*
X50138Y425810D03*
X45182D03*
X45022Y449106D03*
X50002D03*
X48626Y552365D03*
X50880Y1412563D03*
X51358Y1647717D03*
Y1650217D03*
X52052Y1684027D03*
X67257Y69340D03*
X62930Y282866D03*
Y312866D03*
X62833Y409597D03*
X62808Y418675D03*
X65380Y427810D03*
X60393D03*
X58349Y1403331D03*
X54449Y1641722D03*
X61415Y1661695D03*
X61374Y1669931D03*
X70127Y1687362D03*
X73015Y28406D03*
X80101D03*
X73015Y40020D03*
X80101D03*
X78253Y75343D03*
X74773Y790297D03*
Y800336D03*
Y827108D03*
Y837147D03*
Y863919D03*
Y873958D03*
Y900730D03*
Y910769D03*
Y937541D03*
Y947580D03*
Y1084785D03*
Y1094824D03*
Y1121596D03*
Y1131635D03*
Y1158407D03*
Y1168446D03*
Y1195218D03*
Y1205257D03*
Y1232029D03*
Y1242068D03*
X71511Y1444379D03*
X69486Y1661828D03*
X69589Y1669878D03*
X78127Y1687362D03*
X74127D03*
X94274Y28406D03*
X87188D03*
Y40020D03*
X94274D03*
X89257Y69340D03*
X90150Y1314560D03*
X86127Y1687362D03*
X92192Y1713741D03*
X92596Y1737117D03*
X108448Y28406D03*
X101361D03*
Y40020D03*
X108448D03*
X100257Y75340D03*
X111257Y69340D03*
X104474Y790297D03*
Y800336D03*
Y827108D03*
Y837147D03*
Y863919D03*
Y873958D03*
Y900730D03*
Y910769D03*
Y937541D03*
Y947580D03*
Y1084785D03*
Y1094824D03*
Y1121596D03*
Y1131635D03*
Y1158407D03*
Y1168446D03*
Y1195218D03*
Y1205257D03*
Y1232029D03*
Y1242068D03*
X112355Y1426064D03*
Y1433564D03*
Y1441064D03*
X110144Y1597831D03*
X110996Y1592018D03*
X122621Y28406D03*
X115534D03*
Y40020D03*
X122621D03*
X122257Y75340D03*
X119855Y1426064D03*
X127355Y1433564D03*
Y1426064D03*
X119855Y1441064D03*
X127355D03*
X127374Y1572749D03*
X127392Y1575524D03*
X125768Y1568744D03*
X127246Y1585801D03*
X127264Y1588576D03*
X113496Y1592018D03*
X116353Y1646612D03*
X120353D03*
X124353D03*
X123278Y1658587D03*
X119353Y1695941D03*
X115353D03*
X125107Y1702666D03*
X124461Y1726116D03*
X114596Y1737117D03*
X129708Y28406D03*
Y40020D03*
X133257Y69343D03*
X141642Y491434D03*
X134174Y790297D03*
Y800336D03*
Y837147D03*
Y827108D03*
Y863919D03*
Y873958D03*
Y900730D03*
Y910769D03*
Y937541D03*
Y947580D03*
Y1084785D03*
Y1094824D03*
Y1121596D03*
Y1131635D03*
Y1158407D03*
Y1168446D03*
Y1195218D03*
Y1205257D03*
Y1232029D03*
Y1242068D03*
X128617Y1561022D03*
X129892Y1575524D03*
X129874Y1572749D03*
X128268Y1568744D03*
X129764Y1588576D03*
X129746Y1585801D03*
X128353Y1646612D03*
X140353D03*
X136048Y1666851D03*
X133548Y1677351D03*
X131353Y1696062D03*
X135353D03*
X139353D03*
X136596Y1737117D03*
X151400Y28406D03*
Y40020D03*
X144257Y75340D03*
X155253Y69343D03*
X148353Y1646612D03*
X144353D03*
X155328Y1670087D03*
X146928Y1685087D03*
X143353Y1696062D03*
X158487Y28406D03*
X165574D03*
X158487Y40020D03*
X165574D03*
X167461Y75340D03*
X163875Y790297D03*
Y800336D03*
Y837147D03*
Y827108D03*
Y863919D03*
Y873958D03*
Y900730D03*
Y910769D03*
Y937541D03*
Y947580D03*
Y1084785D03*
Y1094824D03*
Y1121596D03*
Y1131635D03*
Y1158407D03*
Y1168446D03*
Y1195218D03*
Y1205257D03*
Y1232029D03*
Y1242068D03*
X163421Y1425171D03*
Y1427671D03*
Y1430171D03*
Y1432671D03*
X158596Y1737117D03*
X172660Y28406D03*
X179747D03*
X172660Y40020D03*
X179747D03*
X178461Y69340D03*
X173960Y400560D03*
X172721Y1425171D03*
Y1430171D03*
Y1427671D03*
Y1432671D03*
X175351Y1462595D03*
X182051Y1452895D03*
X181760Y1731351D03*
X180596Y1737117D03*
X195534Y28406D03*
Y40020D03*
X189457Y75343D03*
X200461Y69340D03*
X193576Y790297D03*
Y800336D03*
Y827108D03*
Y837147D03*
Y863919D03*
Y873958D03*
Y900730D03*
Y910769D03*
Y937541D03*
Y947580D03*
Y1084785D03*
Y1094824D03*
Y1121596D03*
Y1131635D03*
Y1158407D03*
Y1168446D03*
Y1205257D03*
Y1195218D03*
Y1232029D03*
Y1242068D03*
X202151Y1462595D03*
X195451Y1472295D03*
X202621Y28406D03*
X216794D03*
X209708D03*
X202621Y40020D03*
X209708D03*
X216794D03*
X211595Y75340D03*
X208851Y1452895D03*
X202596Y1737117D03*
X223881Y28406D03*
X230967D03*
X223881Y40020D03*
X230967D03*
X222591Y69343D03*
X223277Y790297D03*
Y800336D03*
Y837147D03*
Y827108D03*
Y863919D03*
Y873958D03*
Y900730D03*
Y910769D03*
Y937541D03*
Y947580D03*
Y1084785D03*
Y1094824D03*
Y1121596D03*
Y1131635D03*
Y1158407D03*
Y1168446D03*
Y1205257D03*
Y1195218D03*
Y1232029D03*
Y1242068D03*
X228951Y1462595D03*
X222251Y1472295D03*
X224596Y1737117D03*
X233595Y75340D03*
X242215Y151788D03*
X234727Y584030D03*
Y571211D03*
X245815Y672746D03*
X244565Y677846D03*
Y680446D03*
Y675246D03*
X242543Y691115D03*
X239443Y691015D03*
X239843Y709715D03*
X235651Y1452895D03*
X252996Y28365D03*
X256496D03*
X249496D03*
X259996D03*
X252195Y144320D03*
X259475Y657245D03*
X259426Y644830D03*
X259475Y662845D03*
X250312Y670080D03*
Y667180D03*
X250835Y672692D03*
X253279Y672708D03*
X258379Y666644D03*
Y669601D03*
Y672708D03*
X255779D03*
X260979Y666644D03*
Y669601D03*
Y672708D03*
X247165Y677846D03*
Y680446D03*
Y675246D03*
X254448Y692050D03*
X255751Y1462595D03*
X249051Y1472295D03*
X266601Y586578D03*
X271571Y644796D03*
X264335Y657245D03*
X261905D03*
Y662845D03*
X264335D03*
X263579Y669601D03*
X266179D03*
Y672708D03*
X263579D03*
X270857Y668515D03*
X263839Y692049D03*
X275851Y1452895D03*
X262451D03*
X266596Y1737117D03*
X278979Y28406D03*
X286066D03*
X279273Y99186D03*
X289553Y121806D03*
X291109Y700885D03*
X283062Y700979D03*
X279895Y709487D03*
X283565Y706933D03*
X286009Y706949D03*
X278545Y706987D03*
X279895Y712087D03*
Y714687D03*
X291109Y703842D03*
Y706949D03*
X288509D03*
X277295Y709487D03*
Y712087D03*
Y714687D03*
X283062Y703936D03*
X277055Y722649D03*
X279171Y724988D03*
X281992Y1342705D03*
X292705Y580275D03*
X292156Y679071D03*
X304301Y679037D03*
X292205Y691486D03*
X297065D03*
X294635D03*
X293709Y700885D03*
X297065Y697086D03*
X303657Y702815D03*
X292205Y697086D03*
X294635D03*
X293709Y703842D03*
Y706949D03*
X298909Y703842D03*
Y706949D03*
X296309Y703842D03*
Y706949D03*
X303413Y1462595D03*
X315912Y721039D03*
Y723996D03*
X321279Y727099D03*
X312665Y729637D03*
Y732237D03*
X310065Y729637D03*
Y732237D03*
X316335Y727083D03*
X311315Y727137D03*
X318779Y727099D03*
X313255Y746279D03*
X312665Y734837D03*
X310065D03*
X310113Y1452895D03*
X312596Y1737117D03*
X328966Y548030D03*
X324926Y699221D03*
X329835Y711636D03*
X324975D03*
X329835Y717236D03*
X327405Y711636D03*
X324975Y717236D03*
X327405D03*
X326479Y721035D03*
X323879D03*
Y727099D03*
X326479D03*
X329079D03*
X331679D03*
X323879Y723992D03*
X326479D03*
X329079D03*
X331679D03*
X330213Y1462595D03*
X323513Y1472295D03*
X334596Y1737117D03*
X350817Y558248D03*
X343182Y586415D03*
Y591335D03*
X348449Y720827D03*
Y723784D03*
X345725Y729369D03*
X343125D03*
X345725Y731969D03*
X343125D03*
X344375Y726869D03*
X349395Y726815D03*
X336457Y722815D03*
X339825Y746269D03*
X342425D03*
X349625D03*
X345725Y734569D03*
X343125D03*
X336913Y1452895D03*
X350313Y1472295D03*
X352418Y225329D03*
Y222329D03*
X355733Y275059D03*
X357986Y698953D03*
X362895Y716968D03*
X360465Y711368D03*
X362895D03*
X358035D03*
Y716968D03*
X360465D03*
X359539Y720767D03*
X356939D03*
X351839Y726831D03*
X354339D03*
X356939D03*
X362139D03*
X359539D03*
X364739D03*
X356939Y723724D03*
X362139D03*
X359539D03*
X364739D03*
X352225Y746269D03*
X360025D03*
X362625D03*
X352943Y1214510D03*
X363713Y1452895D03*
X357013Y1462595D03*
X356596Y1737117D03*
X379023Y225149D03*
X371318Y218629D03*
X379023Y228649D03*
X379028Y232559D03*
X369428Y231759D03*
X372528Y231859D03*
X369171Y562380D03*
X376671D03*
X369100Y577400D03*
X369171Y569880D03*
X376600Y577400D03*
X376165Y729437D03*
X378765D03*
X376165Y732037D03*
X378765D03*
X377415Y726937D03*
X369557Y722615D03*
X373425Y746169D03*
X370825D03*
X376165Y734637D03*
X378765D03*
X367836Y1209506D03*
X377190Y1387697D03*
X377113Y1472295D03*
X393287Y-9234D03*
X391635Y161091D03*
X384259Y562426D03*
X384301Y577446D03*
X385443Y597279D03*
X391026Y699021D03*
X395935Y717036D03*
Y711436D03*
X393505D03*
X391075D03*
Y717036D03*
X393505D03*
X392579Y720835D03*
X389979D03*
X381802Y720789D03*
Y723746D03*
X387379Y726899D03*
X384879D03*
X389979D03*
Y723792D03*
X382435Y726883D03*
X392579Y726899D03*
X395179D03*
X392579Y723792D03*
X395179D03*
X389981Y1015474D03*
Y1022560D03*
Y1019017D03*
X383813Y1462595D03*
X390513Y1452895D03*
X406243Y100076D03*
X402184Y507101D03*
X403133Y565415D03*
X403157Y569415D03*
X410415Y709137D03*
X409165Y711637D03*
Y714237D03*
Y716837D03*
X397779Y726899D03*
Y723792D03*
X402457Y722615D03*
X397461Y1015474D03*
X404941D03*
X397461Y1022560D03*
X404941Y1019017D03*
Y1022560D03*
X397461Y1019017D03*
X403913Y1452895D03*
X417617Y79073D03*
X423376Y96664D03*
X411952Y132751D03*
Y123051D03*
X422936Y228147D03*
Y232793D03*
X420288Y244184D03*
X415984Y507024D03*
X424026Y681221D03*
X424075Y693636D03*
X425579Y703035D03*
X422979D03*
X424075Y699236D03*
X414682Y703139D03*
X411765Y711637D03*
Y714237D03*
Y716837D03*
X415435Y709083D03*
X417879Y709099D03*
X425579D03*
X422979D03*
X420379D03*
X425579Y705992D03*
X422979D03*
X414682Y706096D03*
X423811Y1009400D03*
Y1028831D03*
X417098Y1533764D03*
Y1531264D03*
X422596Y1737117D03*
X429685Y88657D03*
X436090Y116007D03*
Y124007D03*
Y132007D03*
X440591Y684518D03*
X436130Y683281D03*
X426505Y693636D03*
X428935D03*
Y699236D03*
X426505D03*
X430779Y709099D03*
Y705992D03*
X428179Y709099D03*
Y705992D03*
X435457Y704915D03*
X439411Y733527D03*
X436811D03*
X439411Y736147D03*
X436811D03*
X436411Y738717D03*
X439011D03*
X436411Y743917D03*
X439011D03*
X436411Y741317D03*
X439011D03*
X431291Y1009400D03*
X438316Y1014745D03*
X427551Y1009400D03*
X435031D03*
X438771D03*
X428473Y1014745D03*
X438771Y1028831D03*
X438316Y1023013D03*
X427551Y1028831D03*
X435031D03*
X438316Y1018879D03*
X428473D03*
Y1023013D03*
X431291Y1028831D03*
X427251Y1291747D03*
X439524Y1462595D03*
X448090Y116007D03*
X444090Y132007D03*
X452480Y273420D03*
X441320Y298170D03*
X452565Y652837D03*
X455379Y678435D03*
X450279Y684499D03*
X455379D03*
X452779D03*
X455379Y681392D03*
X444165Y687037D03*
X441565D03*
X443235Y684637D03*
X447835Y684483D03*
X447162Y678409D03*
Y681366D03*
X444325Y702449D03*
X441725D03*
X444165Y689637D03*
Y692237D03*
X441565D03*
Y689637D03*
X446591Y716837D03*
X443991D03*
X446591Y719437D03*
X443991D03*
X441959Y993766D03*
Y997766D03*
X442034Y989766D03*
X442511Y1009400D03*
X449992D03*
X446252D03*
X453732D03*
X441959Y1001766D03*
X447174Y1014745D03*
X446252Y1028831D03*
X453732D03*
X449992D03*
X447174Y1023013D03*
X442511Y1028831D03*
X447174Y1018879D03*
X446224Y1452895D03*
X444596Y1737117D03*
X463402Y229970D03*
X457731Y237588D03*
X463653Y237390D03*
X462703Y242342D03*
X467644Y353417D03*
X469046Y657062D03*
X456426Y656621D03*
X458905Y669036D03*
X456475D03*
X461335D03*
X457979Y678435D03*
X460579Y684499D03*
X457979D03*
X460579Y681392D03*
X457979D03*
X467957Y680315D03*
X463179Y684499D03*
Y681392D03*
X461335Y674636D03*
X456475D03*
X458905D03*
X457472Y1009400D03*
X457410Y1014745D03*
Y1018879D03*
Y1023013D03*
X457472Y1028831D03*
X466324Y1462595D03*
X459624Y1472295D03*
X466596Y1737117D03*
X486682Y197516D03*
X483800Y270440D03*
X475415Y658037D03*
X482879Y657999D03*
X480435Y657983D03*
X485379Y657999D03*
X479822Y651989D03*
Y654946D03*
X476765Y660537D03*
X474165D03*
X476765Y663137D03*
X474165D03*
X476765Y665737D03*
X474165D03*
X473024Y1452895D03*
X495232Y189516D03*
X486600Y200800D03*
X495232Y197516D03*
X491635Y212577D03*
X487541Y226527D03*
X488076Y350420D03*
X501171Y630087D03*
X493935Y642536D03*
X489075D03*
X491505D03*
X489026Y630121D03*
X493935Y648136D03*
X487979Y651935D03*
X490579D03*
X493179Y654892D03*
Y657999D03*
X487979Y654892D03*
X490579D03*
Y657999D03*
X487979D03*
X495779Y654892D03*
Y657999D03*
X489075Y648136D03*
X491505D03*
X499824Y1452895D03*
X493124Y1462595D03*
X486424Y1472295D03*
X488596Y1737117D03*
X510810Y49193D03*
X510065Y626437D03*
X508715Y623937D03*
X507465Y626437D03*
X513735Y623883D03*
X513012Y620706D03*
Y617749D03*
X510065Y629037D03*
X507465D03*
X510065Y631637D03*
X507465D03*
X514771Y643138D03*
X500457Y653715D03*
X513224Y1472295D03*
X517915Y42257D03*
X525001D03*
X517896Y49193D03*
X524763Y49189D03*
X522418Y137171D03*
X526418D03*
X517973Y211998D03*
X522326Y596021D03*
X524805Y608436D03*
X522375D03*
X527235D03*
X526479Y620792D03*
Y623899D03*
X523879Y620792D03*
X521279D03*
X523879Y623899D03*
X521279D03*
X518679D03*
X516179D03*
X529079Y620792D03*
Y623899D03*
X523879Y617835D03*
X521279D03*
X527235Y614036D03*
X522375D03*
X524805D03*
X521771Y643138D03*
X528771D03*
X519924Y1462595D03*
X526624Y1452895D03*
X532070Y49193D03*
X539156D03*
X530418Y137171D03*
X541013Y222441D03*
X534471Y595987D03*
X533857Y619615D03*
X534271Y643138D03*
X540024Y1452895D03*
X532596Y1737117D03*
X557091Y114382D03*
X550505D03*
X553100Y227700D03*
X551200Y377650D03*
X551171Y1167678D03*
X554596Y1737117D03*
X564431Y45132D03*
X562475Y242721D03*
X571271Y1259488D03*
X567586Y1462595D03*
X574286Y1452895D03*
X578621Y45112D03*
X585296Y222954D03*
X586000Y808862D03*
X578830Y1218588D03*
X585501Y1229536D03*
X587686Y1472295D03*
X576596Y1737117D03*
X595682Y44842D03*
X603064Y44523D03*
X599284Y32866D03*
X593920Y49193D03*
X600793Y193185D03*
X596661Y188775D03*
X590300Y190660D03*
X595563Y239128D03*
X603283Y419744D03*
X597071Y799268D03*
X592761Y1220688D03*
X594386Y1462595D03*
X601086Y1452895D03*
X598596Y1737117D03*
X618427Y43432D03*
X615180Y49193D03*
X618600Y160750D03*
X613207Y182229D03*
X615464Y347522D03*
X607871Y359262D03*
X613761Y790418D03*
X605771Y1267098D03*
X614486Y1472295D03*
X624937Y44019D03*
X620390Y36794D03*
X630900Y118920D03*
X632695Y1366157D03*
Y1372257D03*
Y1378257D03*
X627886Y1452895D03*
X621186Y1462595D03*
X620596Y1737117D03*
X648487Y44106D03*
X638695Y1366157D03*
X644795D03*
X643395Y1372857D03*
X638695Y1378257D03*
X644795D03*
X647986Y1462595D03*
X641286Y1472295D03*
X642596Y1737117D03*
X654590Y49193D03*
X661676D03*
X652804Y790297D03*
Y800336D03*
Y837147D03*
Y827108D03*
Y863919D03*
Y873958D03*
Y900730D03*
Y910769D03*
Y937541D03*
Y947580D03*
Y1084785D03*
Y1094824D03*
Y1121596D03*
Y1131635D03*
Y1158407D03*
Y1168446D03*
Y1205257D03*
Y1195218D03*
Y1232029D03*
Y1242068D03*
X661685Y1367283D03*
X654686Y1452895D03*
X662153Y1727718D03*
X675849Y49193D03*
X668763D03*
X668086Y1452895D03*
X664596Y1737117D03*
X682505Y790297D03*
Y800336D03*
Y837147D03*
Y827108D03*
Y863919D03*
Y873958D03*
Y900730D03*
Y910769D03*
Y937541D03*
Y947580D03*
Y1084785D03*
Y1094824D03*
Y1121596D03*
Y1131635D03*
Y1158407D03*
Y1168446D03*
Y1205257D03*
Y1195218D03*
Y1232029D03*
Y1242068D03*
X688540Y1455140D03*
X697400Y345761D03*
X697300Y1454140D03*
X722581Y49182D03*
X713420Y102060D03*
X712206Y790297D03*
Y800336D03*
Y827108D03*
Y837147D03*
Y863919D03*
Y873958D03*
Y900730D03*
Y910769D03*
Y937541D03*
Y947580D03*
Y1084785D03*
Y1094824D03*
Y1121596D03*
Y1131635D03*
Y1158407D03*
Y1168446D03*
Y1195218D03*
Y1205257D03*
Y1232029D03*
Y1242068D03*
X731743Y-30584D03*
X734996Y-30570D03*
X731758Y-28069D03*
X735011Y-28055D03*
X728718Y-29264D03*
X735041Y-23025D03*
X735026Y-25540D03*
X731555Y83685D03*
X737009Y83169D03*
X724134Y141288D03*
X728500Y533862D03*
X736500D03*
X732500D03*
X738260Y553625D03*
X747637Y534874D03*
X740638Y549900D03*
X741907Y790297D03*
Y800336D03*
Y827108D03*
Y837147D03*
Y863919D03*
Y873958D03*
Y900730D03*
Y910769D03*
Y937541D03*
Y947580D03*
Y1084785D03*
Y1094824D03*
Y1121596D03*
Y1131635D03*
Y1158407D03*
Y1168446D03*
Y1195218D03*
Y1205257D03*
Y1232029D03*
Y1242068D03*
X751521Y1659158D03*
X752596Y1737117D03*
X762199Y126684D03*
Y129684D03*
X758111Y172636D03*
X762300Y188910D03*
X764500Y534424D03*
X760500Y534352D03*
X781242Y489574D03*
X771608Y790297D03*
Y800336D03*
Y837147D03*
Y827108D03*
Y863919D03*
Y873958D03*
Y900730D03*
Y910769D03*
Y937541D03*
Y947580D03*
Y1084785D03*
Y1094824D03*
Y1121596D03*
Y1131635D03*
Y1158407D03*
Y1168446D03*
Y1195218D03*
Y1205257D03*
Y1232029D03*
Y1242068D03*
X778030Y1310259D03*
X780530D03*
X773974Y1731920D03*
X796333Y439344D03*
X786030Y1310259D03*
X794030D03*
X796530D03*
X788530D03*
X791823Y1527404D03*
X795926Y1731918D03*
X807451Y763765D03*
X801308Y790297D03*
Y800336D03*
Y837147D03*
Y827108D03*
Y863919D03*
Y873958D03*
Y900730D03*
Y910769D03*
Y937541D03*
Y947580D03*
Y1084785D03*
Y1094824D03*
Y1121596D03*
Y1131635D03*
Y1158407D03*
Y1168446D03*
Y1195218D03*
Y1205257D03*
Y1232029D03*
Y1242068D03*
X802030Y1310259D03*
X804530D03*
X807601Y1307191D03*
X810246Y1351988D03*
X817974Y1731920D03*
X839974D03*
X844766Y-15374D03*
Y-5374D03*
Y24626D03*
X849711Y212062D03*
X845221Y216532D03*
X854707Y229878D03*
X852207D03*
X874295Y163862D03*
X863488Y176332D03*
X861974Y1731920D03*
X883974D03*
X898000Y1112336D03*
Y1109736D03*
Y1116544D03*
Y1119144D03*
Y1130160D03*
Y1132760D03*
Y1123352D03*
Y1125952D03*
X916880Y1138969D03*
X906473Y1158574D03*
X903980Y1268420D03*
X904024Y1272692D03*
X903947Y1276968D03*
X903899Y1281203D03*
X903945Y1285420D03*
X903923Y1289630D03*
X903651Y1293853D03*
X903690Y1298027D03*
X905974Y1731920D03*
X921477Y1134647D03*
X925525Y1135172D03*
X919880Y1146569D03*
Y1139969D03*
Y1143369D03*
Y1149769D03*
X922880Y1146569D03*
Y1139969D03*
Y1143369D03*
Y1149769D03*
X919077Y1136521D03*
X923125Y1137046D03*
X919880Y1152769D03*
X928751Y1266347D03*
X928901Y1270408D03*
X928852Y1274591D03*
X928979Y1278713D03*
X928827Y1283048D03*
X928928Y1287193D03*
X928906Y1291676D03*
X928983Y1295957D03*
X927974Y1731920D03*
X935497Y195925D03*
Y210098D03*
Y203012D03*
Y224272D03*
Y217185D03*
Y231358D03*
X935783Y634051D03*
X941000Y1110557D03*
Y1107957D03*
Y1117557D03*
Y1114957D03*
Y1124557D03*
Y1121957D03*
Y1131557D03*
Y1128957D03*
X953498Y1158574D03*
X949974Y1731920D03*
X967315Y1135550D03*
X972109Y1135149D03*
X966905Y1146569D03*
X969905D03*
X966905Y1139969D03*
Y1143369D03*
X969905Y1139969D03*
Y1143369D03*
X966905Y1149769D03*
X969905D03*
X963012Y1139511D03*
X964915Y1137424D03*
X969709Y1137023D03*
X966905Y1152769D03*
X968594Y1288193D03*
X971974Y1731920D03*
X991031Y528574D03*
X998056Y518214D03*
Y523874D03*
X999031Y528574D03*
X999894Y1267126D03*
X993974Y1731920D03*
X1021220Y243638D03*
X1012220D03*
X1007669Y268884D03*
Y258222D03*
X1007587Y767480D03*
Y769980D03*
Y780880D03*
Y778380D03*
Y789484D03*
Y791984D03*
X1010894Y1271743D03*
X1010865Y1275768D03*
X1010944Y1279751D03*
X1010650Y1310500D03*
X1015974Y1731920D03*
X1025493Y758819D03*
X1044012Y268659D03*
X1051495Y265133D03*
X1040097Y529508D03*
X1050915Y790296D03*
Y800335D03*
Y827107D03*
Y837146D03*
Y863918D03*
Y873957D03*
Y910768D03*
Y900729D03*
Y937540D03*
Y947579D03*
Y1084784D03*
Y1094823D03*
Y1131634D03*
Y1121595D03*
Y1158406D03*
Y1168445D03*
Y1205256D03*
Y1195217D03*
Y1232028D03*
Y1242067D03*
X1037974Y1731920D03*
X1054355Y258698D03*
X1065552Y271441D03*
X1056517Y512787D03*
X1061837Y519703D03*
X1060721Y1313954D03*
X1061974Y1731920D03*
X1080616Y790296D03*
Y800335D03*
Y827107D03*
Y837146D03*
Y863918D03*
Y873957D03*
Y910768D03*
Y900729D03*
Y937540D03*
Y947579D03*
Y1084784D03*
Y1094823D03*
Y1131634D03*
Y1121595D03*
Y1158406D03*
Y1168445D03*
Y1205256D03*
Y1195217D03*
Y1232028D03*
Y1242067D03*
X1081857Y269856D03*
X1089030Y1691229D03*
X1092980Y1696029D03*
X1095489Y1708519D03*
X1081974Y1731920D03*
X1110316Y790296D03*
Y800335D03*
Y827107D03*
Y837146D03*
Y863918D03*
Y873957D03*
Y910768D03*
Y900729D03*
Y937540D03*
Y947579D03*
Y1084784D03*
Y1094823D03*
Y1131634D03*
Y1121595D03*
Y1158406D03*
Y1168445D03*
Y1205256D03*
Y1195217D03*
Y1232028D03*
Y1242067D03*
X1103351Y1737117D03*
X1112001Y1718991D03*
X1125351Y1737117D03*
X1140017Y790296D03*
Y800335D03*
Y827107D03*
Y837146D03*
Y863918D03*
Y873957D03*
Y910768D03*
Y900729D03*
Y937540D03*
Y947579D03*
Y1084784D03*
Y1094823D03*
Y1131634D03*
Y1121595D03*
Y1158406D03*
Y1168445D03*
Y1205256D03*
Y1195217D03*
Y1232028D03*
Y1242067D03*
X1169718Y790296D03*
Y800335D03*
Y837146D03*
Y827107D03*
Y863918D03*
Y873957D03*
Y900729D03*
Y910768D03*
Y937540D03*
Y947579D03*
Y1084784D03*
Y1094823D03*
Y1121595D03*
Y1131634D03*
Y1158406D03*
Y1168445D03*
Y1205256D03*
Y1195217D03*
Y1232028D03*
Y1242067D03*
X1183050Y-20074D03*
Y-10074D03*
Y-74D03*
Y9926D03*
X1183224Y1495595D03*
X1186312Y-20074D03*
Y-10074D03*
Y-74D03*
Y9926D03*
X1200037Y164987D03*
Y160987D03*
X1189727Y177187D03*
X1200012Y185187D03*
X1199419Y790296D03*
Y800335D03*
Y837146D03*
Y827107D03*
Y863918D03*
Y873957D03*
Y900729D03*
Y910768D03*
Y937540D03*
Y947579D03*
Y1084784D03*
Y1094823D03*
Y1121595D03*
Y1131634D03*
Y1158406D03*
Y1168445D03*
Y1195217D03*
Y1205256D03*
Y1232028D03*
Y1242067D03*
X1189924Y1485895D03*
X1199612Y1700334D03*
X1199294Y1721143D03*
X1191351Y1737117D03*
X1215581Y91346D03*
X1202711Y87651D03*
X1215581Y94846D03*
X1213355Y1412564D03*
Y1427564D03*
Y1420064D03*
X1203324Y1505295D03*
X1210024Y1495595D03*
X1214954Y1700343D03*
X1204447Y1707143D03*
X1213351Y1737117D03*
X1223455Y91346D03*
X1230312Y88635D03*
X1215931Y141530D03*
X1218431D03*
X1231118Y142125D03*
X1228355Y1412564D03*
X1220855D03*
X1228355Y1427564D03*
Y1420064D03*
X1220855Y1427564D03*
X1216724Y1485895D03*
X1230124Y1505295D03*
X1235546Y75293D03*
X1232812Y88635D03*
X1239218Y128239D03*
Y137239D03*
Y132739D03*
Y123739D03*
X1238094Y280573D03*
X1233345Y300157D03*
X1242429Y443255D03*
Y447255D03*
X1243524Y1485895D03*
X1236824Y1495595D03*
X1235351Y1737117D03*
X1248286Y-15374D03*
Y-25374D03*
Y14626D03*
X1252561Y72675D03*
X1255185Y140053D03*
Y142553D03*
X1255175Y137553D03*
X1246094Y280573D03*
X1246748Y785752D03*
X1258121Y1342686D03*
X1256924Y1505295D03*
X1257351Y1737117D03*
X1270324Y1485895D03*
X1263624Y1495595D03*
X1278677Y808988D03*
X1283724Y1485895D03*
X1279351Y1737117D03*
X1295532Y539513D03*
X1301666Y555413D03*
X1301351Y1737117D03*
X1319667Y87587D03*
Y105227D03*
X1307857Y111353D03*
X1317986Y1485895D03*
X1311286Y1495595D03*
X1333878Y637721D03*
X1331386Y1505295D03*
X1323351Y1737117D03*
X1344958Y85358D03*
X1336558Y637721D03*
X1339238D03*
X1344438D03*
X1341838D03*
X1344786Y1485895D03*
X1338086Y1495595D03*
X1345351Y1737117D03*
X1356868Y85324D03*
X1360629Y120380D03*
X1363831Y642042D03*
X1361387Y642026D03*
X1356367Y642080D03*
X1352527Y638278D03*
X1360944Y638999D03*
Y636042D03*
X1357717Y647180D03*
Y649780D03*
X1355117D03*
Y647180D03*
X1357717Y644580D03*
X1355117D03*
X1364317Y661368D03*
X1357057Y661328D03*
X1364886Y1495595D03*
X1358186Y1505295D03*
X1369808Y87587D03*
X1382123Y614130D03*
X1374887Y626579D03*
X1372457D03*
X1370027D03*
X1369978Y614164D03*
X1366331Y642042D03*
X1376731Y638935D03*
Y642042D03*
X1371531Y638935D03*
Y642042D03*
Y635978D03*
X1374887Y632179D03*
X1374131Y638935D03*
Y642042D03*
X1368931Y638935D03*
Y642042D03*
Y635978D03*
X1370027Y632179D03*
X1372457D03*
X1371847Y661328D03*
X1366123Y1015473D03*
X1373603D03*
Y1019016D03*
Y1022559D03*
X1366123D03*
Y1019016D03*
X1371586Y1485895D03*
X1367351Y1737117D03*
X1381457Y637865D03*
X1380306Y664816D03*
X1380256Y667466D03*
X1393664Y671949D03*
Y668992D03*
X1390417Y677480D03*
X1389067Y674980D03*
X1387817Y677480D03*
X1394087Y674926D03*
X1390417Y680080D03*
X1387817D03*
X1390417Y682680D03*
X1387817D03*
X1388757Y693397D03*
Y690897D03*
X1381083Y1015473D03*
Y1022559D03*
Y1019016D03*
X1384986Y1505295D03*
X1391686Y1495595D03*
X1389351Y1737117D03*
X1403207Y118938D03*
X1402678Y647064D03*
X1404231Y671835D03*
X1406831D03*
X1409431D03*
X1404231Y668878D03*
X1407587Y665079D03*
X1405157Y659479D03*
X1407587D03*
X1401631Y671835D03*
Y668878D03*
X1402727Y659479D03*
Y665079D03*
X1405157D03*
X1404231Y674942D03*
X1409431D03*
X1406831D03*
X1396531D03*
X1399031D03*
X1401631D03*
X1403693Y1009399D03*
X1407433D03*
X1399953D03*
X1404615Y1014744D03*
X1399953Y1028830D03*
X1407433D03*
X1404615Y1023012D03*
Y1018878D03*
X1403693Y1028830D03*
X1406608Y1282606D03*
X1398386Y1485895D03*
X1414823Y647030D03*
X1414157Y670665D03*
X1416241Y700281D03*
X1416291Y697631D03*
X1420417Y712660D03*
Y715260D03*
Y710060D03*
X1423017Y712660D03*
Y715260D03*
Y710060D03*
X1421667Y707560D03*
X1422757Y726097D03*
Y723597D03*
X1418101Y997765D03*
Y993765D03*
X1418176Y989765D03*
X1418653Y1009399D03*
X1418101Y1001765D03*
X1422394Y1009399D03*
X1414913D03*
X1411173D03*
X1423316Y1014744D03*
X1414458D03*
Y1023012D03*
X1418653Y1028830D03*
X1411173D03*
X1414913D03*
X1423316Y1023012D03*
Y1018878D03*
X1422394Y1028830D03*
X1414458Y1018878D03*
X1411786Y1485895D03*
X1413199Y1643920D03*
X1411351Y1737117D03*
X1438883Y-15050D03*
Y-25050D03*
Y-5050D03*
Y14950D03*
Y4950D03*
X1438312Y152166D03*
X1435278Y679644D03*
X1436257Y676265D03*
X1436831Y701458D03*
X1435327Y692059D03*
X1437757D03*
X1434231Y701458D03*
X1435327Y697659D03*
X1437757D03*
X1426264Y701572D03*
X1436831Y704415D03*
Y707522D03*
X1439431Y704415D03*
Y707522D03*
X1431631D03*
X1429131D03*
X1426687Y707506D03*
X1434231Y704415D03*
Y707522D03*
X1426264Y704529D03*
X1433614Y1009399D03*
X1426134D03*
X1429874D03*
X1433552Y1014744D03*
X1429874Y1028830D03*
X1433552Y1018878D03*
Y1023012D03*
X1426134Y1028830D03*
X1433614D03*
X1433351Y1737117D03*
X1441908Y-26370D03*
X1445161Y-26356D03*
X1441908Y-16370D03*
X1441923Y-13855D03*
X1445161Y-16356D03*
X1445176Y-13841D03*
X1441923Y-23855D03*
X1445176Y-23841D03*
X1441908Y-6370D03*
X1441923Y-3855D03*
X1445161Y-6356D03*
X1445176Y-3841D03*
X1441908Y3630D03*
X1445161Y3644D03*
X1441908Y13630D03*
X1441923Y16145D03*
X1445161Y13644D03*
X1445176Y16159D03*
X1441923Y6145D03*
X1445176Y6159D03*
X1440871Y130118D03*
X1453667Y152166D03*
X1447423Y679610D03*
X1440187Y697659D03*
X1446757Y703265D03*
X1440187Y692059D03*
X1442031Y704415D03*
Y707522D03*
X1453335Y729637D03*
Y732237D03*
Y734837D03*
X1453757Y743597D03*
Y746097D03*
X1454098Y1485895D03*
X1447398Y1495595D03*
X1459177Y163796D03*
X1456282Y568977D03*
Y572977D03*
Y576977D03*
Y580977D03*
X1468196Y699221D03*
X1468245Y711636D03*
Y717236D03*
X1467149Y721035D03*
X1458599Y721045D03*
Y724002D03*
X1455935Y729637D03*
Y732237D03*
X1454585Y727137D03*
X1459605Y727083D03*
X1462049Y727099D03*
X1464549D03*
X1467149Y723992D03*
Y727099D03*
X1455935Y734837D03*
X1467498Y1505295D03*
X1455579Y1636114D03*
X1473105Y717236D03*
X1470675Y711636D03*
X1473105D03*
X1470675Y717236D03*
X1469749Y721035D03*
X1479757Y722865D03*
X1469749Y723992D03*
X1474949D03*
X1472349D03*
Y727099D03*
X1469749D03*
X1474949D03*
X1481665Y745809D03*
X1477177Y803488D03*
X1478177Y817013D03*
X1480898Y1485895D03*
X1474198Y1495595D03*
X1498543Y587841D03*
X1492264Y721149D03*
X1486417Y729637D03*
Y732237D03*
X1489017Y729687D03*
Y732237D03*
X1492264Y724106D03*
X1487667Y727137D03*
X1492687Y727083D03*
X1495131Y727099D03*
X1497631D03*
X1486417Y734837D03*
X1489017D03*
X1484265Y745809D03*
X1489177Y803488D03*
X1498177Y817013D03*
X1494298Y1505295D03*
X1501278Y699221D03*
X1506187Y717236D03*
Y711636D03*
X1501327D03*
X1503757D03*
X1501327Y717404D03*
X1503757D03*
X1502831Y721035D03*
X1500231D03*
X1512757Y722897D03*
X1500231Y723992D03*
X1502831D03*
X1505431D03*
X1508031D03*
X1500231Y727099D03*
X1502831D03*
X1505431D03*
X1508031D03*
X1505905Y746119D03*
X1508505D03*
X1507698Y1485895D03*
X1500998Y1495595D03*
X1499351Y1737117D03*
X1519930Y543470D03*
X1516357Y555318D03*
X1516257Y559977D03*
X1525064Y721149D03*
Y724106D03*
X1521817Y729637D03*
Y732237D03*
X1525487Y727083D03*
X1527931Y727099D03*
X1519217Y729637D03*
Y732237D03*
X1520467Y727137D03*
X1521817Y734837D03*
X1519217D03*
X1515895Y746119D03*
X1518495D03*
X1521098Y1505295D03*
X1527798Y1495595D03*
X1521351Y1737117D03*
X1541580Y-19575D03*
X1541666Y69340D03*
X1532853Y560264D03*
X1534078Y699221D03*
X1536557Y711636D03*
X1534127D03*
X1538987Y717236D03*
Y711636D03*
X1534127Y717236D03*
X1536557D03*
X1535631Y721035D03*
X1533031D03*
X1538231Y723992D03*
X1540831D03*
X1538231Y727099D03*
X1540831D03*
X1530431D03*
X1533031Y723992D03*
X1535631D03*
X1533031Y727099D03*
X1535631D03*
X1543563Y757803D03*
X1543585Y762919D03*
X1543574Y760361D03*
X1534317Y1216828D03*
X1531227Y1227648D03*
X1540227D03*
X1534498Y1485895D03*
X1543351Y1737117D03*
X1554510Y28406D03*
X1547424D03*
X1554510Y40020D03*
X1547424D03*
X1552662Y75343D03*
X1546257Y701097D03*
X1558194Y702166D03*
Y699209D03*
X1552347Y712897D03*
X1554947D03*
X1552347Y710297D03*
Y707697D03*
X1554947Y710297D03*
Y707697D03*
X1553597Y705197D03*
X1558617Y705143D03*
X1551250Y723840D03*
X1553750D03*
X1545557Y722897D03*
X1556555Y740617D03*
X1556544Y738059D03*
X1554055Y740617D03*
X1554044Y738059D03*
X1546965Y746119D03*
X1546954Y743561D03*
X1548119Y751952D03*
X1545619D03*
X1548119Y754832D03*
X1545619D03*
X1546063Y757803D03*
X1546085Y762919D03*
X1546074Y760361D03*
X1549877Y1217288D03*
Y1221288D03*
X1547898Y1485895D03*
X1561597Y28406D03*
X1568683D03*
Y40020D03*
X1561597D03*
X1563666Y69340D03*
X1567208Y677281D03*
X1572117Y695296D03*
X1568761Y702052D03*
X1571361D03*
X1568761Y699095D03*
X1566161Y702052D03*
Y699095D03*
X1569687Y689696D03*
X1572117D03*
X1567257D03*
Y695296D03*
X1569687D03*
X1563561Y705159D03*
X1561061D03*
X1568761D03*
X1571361D03*
X1566161D03*
X1568660Y1283460D03*
X1572036Y1306083D03*
X1565351Y1737117D03*
X1575770Y28406D03*
X1582857D03*
Y40020D03*
X1575770D03*
X1574666Y75340D03*
X1585666Y69340D03*
X1579748Y536344D03*
X1576843Y674425D03*
X1579807Y671268D03*
X1586367Y671428D03*
X1587717Y676528D03*
Y673928D03*
X1585117Y676528D03*
Y673928D03*
Y679128D03*
X1587717D03*
X1578757Y700965D03*
X1573961Y702052D03*
X1586070Y696830D03*
Y694330D03*
X1573961Y705159D03*
X1578904Y721340D03*
Y723840D03*
X1584849Y793506D03*
X1587028Y1307137D03*
X1582160Y1485895D03*
X1575460Y1495595D03*
X1587351Y1737117D03*
X1589943Y28406D03*
X1597030D03*
Y40020D03*
X1589943D03*
X1596666Y75340D03*
X1599837Y295328D03*
X1593214Y531226D03*
X1599978Y643512D03*
X1600027Y655927D03*
X1602457D03*
X1591387Y671374D03*
X1593831Y671390D03*
X1596331D03*
X1601531D03*
Y668283D03*
Y665326D03*
X1598931Y671390D03*
Y668283D03*
Y665326D03*
X1600027Y661527D03*
X1602457D03*
X1590964Y668397D03*
Y665440D03*
X1594539Y1295288D03*
X1595560Y1505295D03*
X1602260Y1495595D03*
X1604117Y28406D03*
Y40020D03*
X1607666Y69343D03*
X1609355Y592794D03*
X1615677Y648488D03*
X1604887Y655927D03*
X1618117Y657528D03*
Y654928D03*
X1611557Y667165D03*
X1606731Y671390D03*
Y668283D03*
X1604131Y671390D03*
Y668283D03*
X1604887Y661527D03*
X1618117Y660128D03*
X1613154Y688238D03*
Y690738D03*
X1605447Y1288748D03*
X1608960Y1485895D03*
X1609351Y1737117D03*
X1632896Y28406D03*
X1625809D03*
X1632896Y40020D03*
X1625809D03*
X1618666Y75340D03*
X1631558Y588513D03*
X1628756Y588591D03*
X1624067Y588474D03*
X1621187Y588591D03*
X1632978Y624512D03*
X1633027Y636927D03*
Y642527D03*
X1620717Y657528D03*
X1631931Y652390D03*
Y649283D03*
X1626831Y652390D03*
X1629331D03*
X1631931Y646326D03*
X1624387Y652374D03*
X1619367Y652428D03*
X1620717Y654928D03*
X1623964Y649397D03*
Y646440D03*
X1621050Y671768D03*
X1623550D03*
X1620717Y660128D03*
X1628946Y790296D03*
Y800335D03*
Y827107D03*
Y837146D03*
Y863918D03*
Y873957D03*
Y900729D03*
Y910768D03*
Y937540D03*
Y947579D03*
Y1084784D03*
Y1094823D03*
Y1121595D03*
Y1131634D03*
Y1158406D03*
Y1168445D03*
Y1195217D03*
Y1205256D03*
Y1232028D03*
Y1242067D03*
X1629060Y1495595D03*
X1622360Y1505295D03*
X1631351Y1737117D03*
X1647069Y28406D03*
X1639983D03*
X1647069Y40020D03*
X1639983D03*
X1641870Y75340D03*
X1645123Y624478D03*
X1637887Y642527D03*
Y636927D03*
X1635457D03*
Y642527D03*
X1644457Y648265D03*
X1639731Y652390D03*
X1634531D03*
X1637131D03*
X1639731Y649283D03*
X1634531D03*
X1637131D03*
X1634531Y646326D03*
X1643183Y1419441D03*
X1643283Y1431541D03*
X1635760Y1485895D03*
X1654156Y28406D03*
Y40020D03*
X1652870Y69340D03*
X1650917Y657528D03*
Y654928D03*
X1653517Y657528D03*
X1652167Y652428D03*
X1653517Y654928D03*
X1648604Y671768D03*
X1650917Y660128D03*
X1659618Y659021D03*
X1662298D03*
X1651104Y671768D03*
X1653517Y660128D03*
X1656938Y659021D03*
X1651959Y689800D03*
X1658647Y790296D03*
Y800335D03*
Y827107D03*
Y837146D03*
Y863918D03*
Y873957D03*
Y900729D03*
Y910768D03*
Y937540D03*
Y947579D03*
Y1084784D03*
Y1094823D03*
Y1121595D03*
Y1131634D03*
Y1158406D03*
Y1168445D03*
Y1205256D03*
Y1195217D03*
Y1232028D03*
Y1242067D03*
X1649283Y1419441D03*
Y1431541D03*
X1655383D03*
Y1419441D03*
X1655957Y1445116D03*
X1662560Y1485895D03*
X1649160Y1505295D03*
X1655860Y1495595D03*
X1653351Y1737117D03*
X1677030Y28406D03*
X1669943D03*
X1677030Y40020D03*
X1669943D03*
X1663866Y75343D03*
X1674870Y69340D03*
X1668516Y599956D03*
X1674516D03*
X1668516Y609450D03*
X1671516Y599956D03*
X1674516Y609450D03*
X1677516Y599956D03*
X1671516Y609450D03*
X1677516D03*
X1667498Y659021D03*
X1664898D03*
X1675960Y1485895D03*
X1668000Y1711759D03*
Y1726909D03*
X1675351Y1737117D03*
X1684117Y28406D03*
X1691203D03*
Y40020D03*
X1684117D03*
X1686004Y75340D03*
X1688348Y790296D03*
Y800335D03*
Y827107D03*
Y837146D03*
Y863918D03*
Y873957D03*
Y910768D03*
Y900729D03*
Y937540D03*
Y947579D03*
Y1084784D03*
Y1094823D03*
Y1131634D03*
Y1121595D03*
Y1158406D03*
Y1168445D03*
Y1205256D03*
Y1195217D03*
Y1232028D03*
Y1242067D03*
X1684677Y1440258D03*
X1687357Y1440268D03*
X1698290Y28406D03*
X1705376D03*
X1698290Y40020D03*
X1697000Y69343D03*
X1701121Y641658D03*
X1706101D03*
X1695529Y1545193D03*
X1703000Y1711759D03*
X1697351Y1737117D03*
X1708004Y75340D03*
X1708305Y679720D03*
X1718049Y790296D03*
Y800335D03*
Y827107D03*
Y837146D03*
Y863918D03*
Y873957D03*
Y910768D03*
Y900729D03*
Y937540D03*
Y947579D03*
Y1084784D03*
Y1094823D03*
Y1131634D03*
Y1121595D03*
Y1158406D03*
Y1168445D03*
Y1195217D03*
Y1205256D03*
Y1232028D03*
Y1242067D03*
X1719351Y1737117D03*
X1735375Y-40925D03*
X1732350Y-39605D03*
X1735390Y-38410D03*
X1738628Y-40911D03*
X1738658Y-35881D03*
X1738673Y-33366D03*
X1738643Y-38396D03*
X1749571Y255317D03*
Y252317D03*
X1745502Y660088D03*
X1747750Y790296D03*
Y800335D03*
Y827107D03*
Y837146D03*
Y863918D03*
Y873957D03*
Y910768D03*
Y900729D03*
Y937540D03*
Y947579D03*
Y1084784D03*
Y1094823D03*
Y1131634D03*
Y1121595D03*
Y1158406D03*
Y1168445D03*
Y1205256D03*
Y1195217D03*
Y1232028D03*
Y1242067D03*
X1742120Y1708265D03*
Y1723415D03*
X1741351Y1737117D03*
X1753388Y28406D03*
X1760475D03*
X1754364Y100353D03*
X1764644Y122973D03*
X1755969Y251524D03*
Y248524D03*
X1763509Y251341D03*
Y248341D03*
X1763351Y1737117D03*
X1771881Y128439D03*
Y125939D03*
Y123439D03*
X1781966Y128501D03*
Y126001D03*
Y123501D03*
X1775984Y253779D03*
Y256779D03*
X1777450Y790296D03*
Y800335D03*
Y827107D03*
Y837146D03*
Y863918D03*
Y873957D03*
Y910768D03*
Y900729D03*
Y937540D03*
Y947579D03*
Y1084784D03*
Y1094823D03*
Y1131634D03*
Y1121595D03*
Y1158406D03*
Y1168445D03*
Y1205256D03*
Y1195217D03*
Y1232028D03*
Y1242067D03*
X1785072Y53161D03*
X1789811Y178083D03*
X1794629Y193323D03*
X1791645Y193397D03*
X1795219Y185910D03*
X1795949Y205580D03*
X1795909Y209128D03*
X1795365Y197567D03*
X1796019Y202030D03*
X1791445Y197497D03*
X1783592Y763765D03*
X1804111Y178083D03*
X1807711D03*
Y175083D03*
X1803165Y196127D03*
X1797621Y193373D03*
X1800389Y193424D03*
X1803045Y193397D03*
X1798943Y204744D03*
Y209044D03*
X1802276Y209013D03*
X1805235Y208950D03*
X1802276Y204713D03*
X1800125Y201857D03*
X1805235Y204650D03*
X1799629Y198870D03*
X1803145Y198697D03*
X1817674Y188699D03*
X1829732Y367359D03*
G54D24*
X67725Y1538946D03*
X74912D03*
X72585D03*
X70155D03*
X103468D03*
X105898D03*
X108328D03*
X110655D03*
X1757438Y1571982D03*
X1755008D03*
X1762195D03*
X1759868D03*
X1793181D03*
X1790751D03*
X1795611D03*
X1797938D03*
G54D28*
X130000Y1719450D03*
X543277Y88632D03*
X538620Y93289D03*
G54D64*
X1156378Y133866D03*
X1183858Y207205D03*
X1173858D03*
X1193858D03*
X1351260Y164213D03*
Y174213D03*
X1361260Y164213D03*
Y174213D03*
X1371260Y164213D03*
X1381260D03*
X1371260Y174213D03*
X1381260D03*
X1391260Y164213D03*
Y174213D03*
G54D20*
X50880Y1415563D03*
Y1418963D03*
X61157Y69340D03*
X64557D03*
X58349Y1406331D03*
Y1409731D03*
X78265Y26477D03*
X74865D03*
X81970Y19541D03*
X72153Y75343D03*
X75553D03*
X69323Y780257D03*
Y786950D03*
Y803682D03*
Y793643D03*
Y796989D03*
Y817068D03*
Y810375D03*
Y823761D03*
Y830454D03*
Y833800D03*
Y840493D03*
Y847186D03*
Y853879D03*
Y860572D03*
Y877304D03*
Y867265D03*
Y870611D03*
Y883997D03*
Y890690D03*
Y897383D03*
Y904076D03*
Y907423D03*
Y914115D03*
Y920808D03*
Y927501D03*
Y934194D03*
Y940887D03*
Y950926D03*
Y944234D03*
Y964312D03*
Y957619D03*
Y971005D03*
Y977698D03*
Y984391D03*
Y1001123D03*
Y997777D03*
Y991084D03*
Y1031241D03*
Y1037934D03*
Y1044627D03*
Y1058013D03*
Y1051320D03*
Y1074745D03*
Y1081438D03*
Y1088131D03*
Y1098171D03*
Y1104863D03*
Y1091478D03*
Y1111556D03*
Y1118249D03*
Y1134982D03*
Y1124942D03*
Y1128289D03*
Y1148367D03*
Y1141675D03*
Y1155060D03*
Y1161753D03*
Y1165100D03*
Y1171793D03*
Y1178486D03*
Y1185178D03*
Y1191871D03*
Y1208604D03*
Y1198564D03*
Y1201911D03*
Y1215297D03*
Y1221989D03*
Y1228682D03*
Y1235375D03*
Y1238722D03*
Y1245415D03*
Y1252108D03*
X85370Y19541D03*
X92438Y26477D03*
X89038D03*
X96143Y19541D03*
X94157Y75340D03*
X83157Y69340D03*
X97557Y75340D03*
X86557Y69340D03*
X85465Y776911D03*
Y783604D03*
Y790297D03*
Y800336D03*
Y807029D03*
Y793643D03*
Y813722D03*
Y820415D03*
Y837147D03*
Y830454D03*
Y827108D03*
Y843840D03*
Y850533D03*
Y857226D03*
Y863919D03*
Y873958D03*
Y880651D03*
Y867265D03*
Y887344D03*
Y894037D03*
Y910769D03*
Y904076D03*
Y900730D03*
Y924155D03*
Y917462D03*
Y930848D03*
Y940887D03*
Y937541D03*
Y947580D03*
Y954273D03*
Y967659D03*
Y974352D03*
Y981045D03*
Y987737D03*
Y994430D03*
Y1001123D03*
Y1027895D03*
Y1034588D03*
Y1041281D03*
Y1047974D03*
Y1054667D03*
Y1061360D03*
Y1071399D03*
Y1064706D03*
Y1078092D03*
Y1088131D03*
Y1084785D03*
Y1094824D03*
Y1101517D03*
Y1108210D03*
Y1114903D03*
Y1131635D03*
Y1124942D03*
Y1121596D03*
Y1138328D03*
Y1145021D03*
Y1151714D03*
Y1161753D03*
Y1158407D03*
Y1168446D03*
Y1175139D03*
Y1181832D03*
Y1188525D03*
Y1205257D03*
Y1198564D03*
Y1195218D03*
Y1211950D03*
Y1218643D03*
Y1225336D03*
Y1235375D03*
Y1232029D03*
Y1242068D03*
Y1248761D03*
X99543Y19541D03*
X106611Y26477D03*
X103211D03*
X110316Y19541D03*
X105157Y69340D03*
X108557D03*
X99024Y780257D03*
Y786950D03*
Y803682D03*
Y793643D03*
Y796989D03*
Y817068D03*
Y810375D03*
Y823761D03*
Y830454D03*
Y833800D03*
Y840493D03*
Y847186D03*
Y853879D03*
Y860572D03*
Y877304D03*
Y867265D03*
Y870611D03*
Y883997D03*
Y890690D03*
Y897383D03*
Y904076D03*
Y907423D03*
Y914115D03*
Y920808D03*
Y927501D03*
Y934194D03*
Y940887D03*
Y950926D03*
Y944234D03*
Y964312D03*
Y957619D03*
Y971005D03*
Y977698D03*
Y984391D03*
Y1001123D03*
Y997777D03*
Y991084D03*
Y1031241D03*
Y1037934D03*
Y1044627D03*
Y1058013D03*
Y1051320D03*
Y1074745D03*
Y1081438D03*
Y1088131D03*
Y1098171D03*
Y1104863D03*
Y1091478D03*
Y1111556D03*
Y1118249D03*
Y1134982D03*
Y1124942D03*
Y1128289D03*
Y1148367D03*
Y1141675D03*
Y1155060D03*
Y1161753D03*
Y1165100D03*
Y1171793D03*
Y1178486D03*
Y1185178D03*
Y1191871D03*
Y1208604D03*
Y1198564D03*
Y1201911D03*
Y1215297D03*
Y1221989D03*
Y1228682D03*
Y1235375D03*
Y1238722D03*
Y1245415D03*
Y1252108D03*
X112473Y1660235D03*
X109073D03*
X107569Y1685763D03*
X110969D03*
X113716Y19541D03*
X120785Y26477D03*
X117385D03*
X124490Y19541D03*
X116157Y75340D03*
X127153Y69343D03*
X119557Y75340D03*
X115166Y776911D03*
Y783604D03*
Y790297D03*
Y800336D03*
Y807029D03*
Y793643D03*
Y813722D03*
Y820415D03*
Y837147D03*
Y830454D03*
Y827108D03*
Y843840D03*
Y850533D03*
Y857226D03*
Y863919D03*
Y873958D03*
Y880651D03*
Y867265D03*
Y887344D03*
Y894037D03*
Y910769D03*
Y904076D03*
Y900730D03*
Y924155D03*
Y917462D03*
Y930848D03*
Y940887D03*
Y937541D03*
Y947580D03*
Y954273D03*
Y967659D03*
Y974352D03*
Y981045D03*
Y987737D03*
Y994430D03*
Y1001123D03*
Y1027895D03*
Y1034588D03*
Y1041281D03*
Y1047974D03*
Y1054667D03*
Y1061360D03*
Y1071399D03*
Y1064706D03*
Y1078092D03*
Y1088131D03*
Y1084785D03*
Y1094824D03*
Y1101517D03*
Y1108210D03*
Y1114903D03*
Y1131635D03*
Y1124942D03*
Y1121596D03*
Y1138328D03*
Y1145021D03*
Y1151714D03*
Y1161753D03*
Y1158407D03*
Y1168446D03*
Y1175139D03*
Y1181832D03*
Y1188525D03*
Y1205257D03*
Y1198564D03*
Y1195218D03*
Y1211950D03*
Y1218643D03*
Y1225336D03*
Y1235375D03*
Y1232029D03*
Y1242068D03*
Y1248761D03*
X127890Y19541D03*
X138157Y75340D03*
X141557D03*
X130553Y69343D03*
X128724Y780257D03*
Y786950D03*
Y803682D03*
Y793643D03*
Y796989D03*
Y817068D03*
Y810375D03*
Y823761D03*
Y830454D03*
Y833800D03*
Y840493D03*
Y847186D03*
Y853879D03*
Y860572D03*
Y877304D03*
Y867265D03*
Y870611D03*
Y883997D03*
Y890690D03*
Y897383D03*
Y904076D03*
Y907423D03*
Y914115D03*
Y920808D03*
Y927501D03*
Y934194D03*
Y940887D03*
Y950926D03*
Y944234D03*
Y964312D03*
Y957619D03*
Y971005D03*
Y977698D03*
Y984391D03*
Y1001123D03*
Y997777D03*
Y991084D03*
Y1031241D03*
Y1037934D03*
Y1044627D03*
Y1058013D03*
Y1051320D03*
Y1074745D03*
Y1081438D03*
Y1088131D03*
Y1098171D03*
Y1104863D03*
Y1091478D03*
Y1111556D03*
Y1118249D03*
Y1134982D03*
Y1124942D03*
Y1128289D03*
Y1148367D03*
Y1141675D03*
Y1155060D03*
Y1161753D03*
Y1165100D03*
Y1171793D03*
Y1178486D03*
Y1185178D03*
Y1191871D03*
Y1208604D03*
Y1198564D03*
Y1201911D03*
Y1215297D03*
Y1221989D03*
Y1228682D03*
Y1235375D03*
Y1238722D03*
Y1245415D03*
Y1252108D03*
X156651Y26477D03*
X153251D03*
X149153Y69343D03*
X152553D03*
X144866Y776911D03*
Y783604D03*
Y790297D03*
Y800336D03*
Y807029D03*
Y793643D03*
Y813722D03*
Y820415D03*
Y837147D03*
Y830454D03*
Y827108D03*
Y843840D03*
Y850533D03*
Y857226D03*
Y863919D03*
Y873958D03*
Y880651D03*
Y867265D03*
Y887344D03*
Y894037D03*
Y910769D03*
Y904076D03*
Y900730D03*
Y924155D03*
Y917462D03*
Y930848D03*
Y940887D03*
Y937541D03*
Y947580D03*
Y954273D03*
Y967659D03*
Y974352D03*
Y981045D03*
Y987737D03*
Y994430D03*
Y1001123D03*
Y1027895D03*
Y1034588D03*
Y1041281D03*
Y1047974D03*
Y1054667D03*
Y1061360D03*
Y1071399D03*
Y1064706D03*
Y1078092D03*
Y1088131D03*
Y1084785D03*
Y1094824D03*
Y1101517D03*
Y1108210D03*
Y1114903D03*
Y1131635D03*
Y1124942D03*
Y1121596D03*
Y1138328D03*
Y1145021D03*
Y1151714D03*
Y1161753D03*
Y1158407D03*
Y1168446D03*
Y1175139D03*
Y1181832D03*
Y1188525D03*
Y1205257D03*
Y1198564D03*
Y1195218D03*
Y1211950D03*
Y1218643D03*
Y1225336D03*
Y1235375D03*
Y1232029D03*
Y1242068D03*
Y1248761D03*
X170824Y26477D03*
X163756Y19541D03*
X167424Y26477D03*
X160356Y19541D03*
X161361Y75340D03*
X164761D03*
X158425Y780257D03*
Y786950D03*
Y803682D03*
Y793643D03*
Y796989D03*
Y817068D03*
Y810375D03*
Y823761D03*
Y830454D03*
Y833800D03*
Y840493D03*
Y847186D03*
Y853879D03*
Y860572D03*
Y877304D03*
Y867265D03*
Y870611D03*
Y883997D03*
Y890690D03*
Y897383D03*
Y904076D03*
Y907423D03*
Y914115D03*
Y920808D03*
Y927501D03*
Y934194D03*
Y940887D03*
Y950926D03*
Y944234D03*
Y964312D03*
Y957619D03*
Y971005D03*
Y977698D03*
Y984391D03*
Y1001123D03*
Y997777D03*
Y991084D03*
Y1031241D03*
Y1037934D03*
Y1044627D03*
Y1058013D03*
Y1051320D03*
Y1074745D03*
Y1081438D03*
Y1088131D03*
Y1098171D03*
Y1104863D03*
Y1091478D03*
Y1111556D03*
Y1118249D03*
Y1134982D03*
Y1124942D03*
Y1128289D03*
Y1148367D03*
Y1141675D03*
Y1155060D03*
Y1161753D03*
Y1165100D03*
Y1171793D03*
Y1178486D03*
Y1185178D03*
Y1191871D03*
Y1208604D03*
Y1198564D03*
Y1201911D03*
Y1215297D03*
Y1221989D03*
Y1228682D03*
Y1235375D03*
Y1238722D03*
Y1245415D03*
Y1252108D03*
X169351Y1462595D03*
X163113Y1483590D03*
Y1480190D03*
Y1501990D03*
Y1505390D03*
X177929Y19541D03*
X174529D03*
X183357Y75343D03*
X172361Y69340D03*
X186757Y75343D03*
X175761Y69340D03*
X174567Y776911D03*
Y783604D03*
Y790297D03*
Y800336D03*
Y807029D03*
Y793643D03*
Y813722D03*
Y820415D03*
Y837147D03*
Y830454D03*
Y827108D03*
Y843840D03*
Y850533D03*
Y857226D03*
Y863919D03*
Y873958D03*
Y880651D03*
Y867265D03*
Y887344D03*
Y894037D03*
Y910769D03*
Y904076D03*
Y900730D03*
Y924155D03*
Y917462D03*
Y930848D03*
Y940887D03*
Y937541D03*
Y947580D03*
Y954273D03*
Y967659D03*
Y974352D03*
Y981045D03*
Y987737D03*
Y994430D03*
Y1001123D03*
Y1027895D03*
Y1034588D03*
Y1041281D03*
Y1047974D03*
Y1054667D03*
Y1061360D03*
Y1071399D03*
Y1064706D03*
Y1078092D03*
Y1088131D03*
Y1084785D03*
Y1094824D03*
Y1101517D03*
Y1108210D03*
Y1114903D03*
Y1131635D03*
Y1124942D03*
Y1121596D03*
Y1138328D03*
Y1145021D03*
Y1151714D03*
Y1161753D03*
Y1158407D03*
Y1168446D03*
Y1175139D03*
Y1181832D03*
Y1188525D03*
Y1205257D03*
Y1198564D03*
Y1195218D03*
Y1211950D03*
Y1218643D03*
Y1225336D03*
Y1235375D03*
Y1232029D03*
Y1242068D03*
Y1248761D03*
X172751Y1462595D03*
X179451Y1452895D03*
X176051D03*
X200785Y26477D03*
X197385D03*
X194361Y69340D03*
X197761D03*
X199551Y1462595D03*
X196151D03*
X192851Y1472295D03*
X189451D03*
X188166Y1592380D03*
X200226D03*
X191566D03*
X188166Y1624292D03*
X200226D03*
X191566D03*
X207890Y19541D03*
X214958Y26477D03*
X204490Y19541D03*
X211558Y26477D03*
X216491Y69343D03*
X205495Y75340D03*
X208895D03*
X209768Y960966D03*
X206251Y1452895D03*
X202851D03*
X216251Y1472295D03*
X212286Y1592380D03*
X203626D03*
X215686D03*
X212286Y1624292D03*
X203626D03*
X215686D03*
X222063Y19541D03*
X218663D03*
X227495Y75340D03*
X230895D03*
X219891Y69343D03*
X226351Y1462595D03*
X222951D03*
X229651Y1452895D03*
X219651Y1472295D03*
X224346Y1592380D03*
X227746D03*
X224346Y1624292D03*
X227746D03*
X233051Y1452895D03*
X246451Y1472295D03*
X243051D03*
X236406Y1592380D03*
X239806D03*
X236406Y1624292D03*
X239806D03*
X253151Y1462595D03*
X259851Y1452895D03*
X249751Y1462595D03*
X256451Y1452895D03*
X248466Y1592380D03*
X260526D03*
X251866D03*
X248466Y1624292D03*
X260526D03*
X251866D03*
X269851Y1452895D03*
X273251D03*
X272586Y1592380D03*
X263926D03*
X275986D03*
X272586Y1624292D03*
X263926D03*
X275986D03*
X280621Y1484082D03*
Y1480682D03*
X291175Y1483590D03*
Y1480190D03*
X280621Y1497482D03*
Y1494082D03*
X291175Y1501990D03*
Y1505390D03*
X284646Y1592380D03*
X288046D03*
X284646Y1624292D03*
X288046D03*
X300813Y1462595D03*
X297413D03*
X304113Y1452895D03*
X296706Y1592380D03*
X300106D03*
X296706Y1624292D03*
X300106D03*
X307513Y1452895D03*
X320913Y1472295D03*
X317513D03*
X308766Y1592380D03*
X320826D03*
X312166D03*
X308766Y1624292D03*
X320826D03*
X312166D03*
X327613Y1462595D03*
X334313Y1452895D03*
X324213Y1462595D03*
X330913Y1452895D03*
X332886Y1592380D03*
X324226D03*
X332886Y1624292D03*
X324226D03*
X351013Y1462595D03*
X347713Y1472295D03*
X344313D03*
X344946Y1592380D03*
X336286D03*
X348346D03*
X344946Y1624292D03*
X336286D03*
X348346D03*
X354413Y1462595D03*
X361113Y1452895D03*
X357713D03*
X357006Y1592380D03*
X360406D03*
X357006Y1624292D03*
X360406D03*
X371999Y819527D03*
X372000Y831797D03*
Y835197D03*
X371999Y822927D03*
X372000Y846427D03*
Y843027D03*
X377813Y1462595D03*
X374513Y1472295D03*
X371113D03*
X369066Y1592380D03*
X372466D03*
X369066Y1624292D03*
X372466D03*
X390841Y-25571D03*
Y-22171D03*
Y-15571D03*
Y-12171D03*
X385001Y816927D03*
Y813527D03*
X381213Y1462595D03*
X387913Y1452895D03*
X384513D03*
X400426Y112815D03*
Y116215D03*
X405606Y125815D03*
Y129715D03*
X401313Y1452895D03*
X397913D03*
X408683Y1480682D03*
Y1484082D03*
Y1497482D03*
Y1494082D03*
X417486Y124179D03*
Y127579D03*
X436924Y1462595D03*
X433524D03*
X440224Y1452895D03*
X427286Y1483590D03*
Y1480190D03*
Y1501990D03*
Y1505390D03*
X455502Y88711D03*
X452102D03*
X448414Y94684D03*
X445014D03*
X443624Y1452895D03*
X453624Y1472295D03*
X452339Y1592380D03*
Y1624292D03*
X462456Y95101D03*
X459056D03*
X463724Y1462595D03*
X470424Y1452895D03*
X460324Y1462595D03*
X467024Y1452895D03*
X457024Y1472295D03*
X464399Y1592380D03*
X455739D03*
X467799D03*
X464399Y1624292D03*
X455739D03*
X467799D03*
X476295Y130020D03*
X472895D03*
X482255Y133222D03*
Y129822D03*
X483824Y1472295D03*
X480424D03*
X476459Y1592380D03*
X479859D03*
X476459Y1624292D03*
X479859D03*
X490380Y131442D03*
X493780D03*
X490524Y1462595D03*
X497224Y1452895D03*
X487124Y1462595D03*
X493824Y1452895D03*
X488519Y1592380D03*
X491919D03*
X488519Y1624292D03*
X491919D03*
X514240Y97146D03*
X513924Y1462595D03*
X510624Y1472295D03*
X507224D03*
X500579Y1592380D03*
X512639D03*
X503979D03*
X500579Y1624292D03*
X512639D03*
X503979D03*
X526460Y100895D03*
Y97495D03*
X517640Y97146D03*
X517324Y1462595D03*
X524024Y1452895D03*
X520624D03*
X524699Y1592380D03*
X516039D03*
X528099D03*
X524699Y1624292D03*
X516039D03*
X528099D03*
X533918Y47067D03*
X537318D03*
X537424Y1452895D03*
X534024D03*
X544794Y1480682D03*
Y1484082D03*
Y1497482D03*
Y1494082D03*
X536759Y1592380D03*
X540159D03*
X536759Y1624292D03*
X540159D03*
X559069Y105385D03*
Y101985D03*
X552105Y112203D03*
X555505D03*
X548819Y1592380D03*
X552219D03*
X548819Y1624292D03*
X552219D03*
X572939Y1592380D03*
X560879D03*
X564279D03*
X572939Y1624292D03*
X560879D03*
X564279D03*
X584999Y1592380D03*
X576339D03*
X588399D03*
X584999Y1624292D03*
X576339D03*
X588399D03*
X597059Y1592380D03*
X600459D03*
X597059Y1624292D03*
X600459D03*
X609119Y1592380D03*
X612519D03*
X609119Y1624292D03*
X612519D03*
X621179Y1592380D03*
X633239D03*
X624579D03*
X621179Y1624292D03*
X633239D03*
X624579D03*
X636639Y1592380D03*
Y1624292D03*
X653999Y1426757D03*
Y1423357D03*
X687697Y960966D03*
X691276Y1455112D03*
X704771Y179599D03*
Y182999D03*
Y194810D03*
Y191410D03*
Y206621D03*
Y203221D03*
Y218432D03*
Y215032D03*
X706756Y780257D03*
Y786950D03*
Y803682D03*
Y793643D03*
Y796989D03*
Y817068D03*
Y810375D03*
Y823761D03*
Y830454D03*
Y833800D03*
Y840493D03*
Y847186D03*
Y853879D03*
Y860572D03*
Y877304D03*
Y867265D03*
Y870611D03*
Y883997D03*
Y890690D03*
Y897383D03*
Y904076D03*
Y907423D03*
Y914115D03*
Y920808D03*
Y927501D03*
Y934194D03*
Y940887D03*
Y950926D03*
Y944234D03*
Y964312D03*
Y957619D03*
Y971005D03*
Y977698D03*
Y984391D03*
Y1001123D03*
Y997777D03*
Y991084D03*
Y1031241D03*
Y1037934D03*
Y1044627D03*
Y1058013D03*
Y1051320D03*
Y1074745D03*
Y1081438D03*
Y1088131D03*
Y1098171D03*
Y1104863D03*
Y1091478D03*
Y1111556D03*
Y1118249D03*
Y1134982D03*
Y1124942D03*
Y1128289D03*
Y1148367D03*
Y1141675D03*
Y1155060D03*
Y1161753D03*
Y1165100D03*
Y1171793D03*
Y1178486D03*
Y1185178D03*
Y1191871D03*
Y1208604D03*
Y1198564D03*
Y1201911D03*
Y1215297D03*
Y1221989D03*
Y1228682D03*
Y1235375D03*
Y1238722D03*
Y1245415D03*
Y1252108D03*
X694676Y1455112D03*
X716699Y177087D03*
Y173687D03*
Y189087D03*
Y185687D03*
Y200587D03*
Y197187D03*
Y209021D03*
Y212421D03*
X722898Y776911D03*
Y783604D03*
Y790297D03*
Y800336D03*
Y807029D03*
Y793643D03*
Y813722D03*
Y820415D03*
Y837147D03*
Y830454D03*
Y827108D03*
Y843840D03*
Y850533D03*
Y857226D03*
Y863919D03*
Y873958D03*
Y880651D03*
Y867265D03*
Y887344D03*
Y894037D03*
Y910769D03*
Y904076D03*
Y900730D03*
Y924155D03*
Y917462D03*
Y930848D03*
Y940887D03*
Y937541D03*
Y947580D03*
Y954273D03*
Y967659D03*
Y974352D03*
Y981045D03*
Y987737D03*
Y994430D03*
Y1001123D03*
Y1027895D03*
Y1034588D03*
Y1041281D03*
Y1047974D03*
Y1054667D03*
Y1061360D03*
Y1071399D03*
Y1064706D03*
Y1078092D03*
Y1088131D03*
Y1084785D03*
Y1094824D03*
Y1101517D03*
Y1108210D03*
Y1114903D03*
Y1131635D03*
Y1124942D03*
Y1121596D03*
Y1138328D03*
Y1145021D03*
Y1151714D03*
Y1161753D03*
Y1158407D03*
Y1168446D03*
Y1175139D03*
Y1181832D03*
Y1188525D03*
Y1205257D03*
Y1198564D03*
Y1195218D03*
Y1211950D03*
Y1218643D03*
Y1225336D03*
Y1235375D03*
Y1232029D03*
Y1242068D03*
Y1248761D03*
X725925Y-25571D03*
Y-22171D03*
Y-15571D03*
Y-12171D03*
X736457Y780257D03*
Y786950D03*
Y803682D03*
Y793643D03*
Y796989D03*
Y817068D03*
Y810375D03*
Y823761D03*
Y830454D03*
Y833800D03*
Y840493D03*
Y847186D03*
Y853879D03*
Y860572D03*
Y877304D03*
Y867265D03*
Y870611D03*
Y883997D03*
Y890690D03*
Y897383D03*
Y904076D03*
Y907423D03*
Y914115D03*
Y920808D03*
Y927501D03*
Y934194D03*
Y940887D03*
Y950926D03*
Y944234D03*
Y964312D03*
Y957619D03*
Y971005D03*
Y977698D03*
Y984391D03*
Y1001123D03*
Y997777D03*
Y991084D03*
Y1031241D03*
Y1037934D03*
Y1044627D03*
Y1058013D03*
Y1051320D03*
Y1074745D03*
Y1081438D03*
Y1088131D03*
Y1098171D03*
Y1104863D03*
Y1091478D03*
Y1111556D03*
Y1118249D03*
Y1134982D03*
Y1124942D03*
Y1128289D03*
Y1148367D03*
Y1141675D03*
Y1155060D03*
Y1161753D03*
Y1165100D03*
Y1171793D03*
Y1178486D03*
Y1185178D03*
Y1191871D03*
Y1208604D03*
Y1198564D03*
Y1201911D03*
Y1215297D03*
Y1221989D03*
Y1228682D03*
Y1235375D03*
Y1238722D03*
Y1245415D03*
Y1252108D03*
X752599Y776911D03*
Y783604D03*
Y790297D03*
Y800336D03*
Y807029D03*
Y793643D03*
Y813722D03*
Y820415D03*
Y837147D03*
Y830454D03*
Y827108D03*
Y843840D03*
Y850533D03*
Y857226D03*
Y863919D03*
Y873958D03*
Y880651D03*
Y867265D03*
Y887344D03*
Y894037D03*
Y910769D03*
Y904076D03*
Y900730D03*
Y924155D03*
Y917462D03*
Y930848D03*
Y940887D03*
Y937541D03*
Y947580D03*
Y954273D03*
Y967659D03*
Y974352D03*
Y981045D03*
Y987737D03*
Y994430D03*
Y1001123D03*
Y1027895D03*
Y1034588D03*
Y1041281D03*
Y1047974D03*
Y1054667D03*
Y1061360D03*
Y1071399D03*
Y1064706D03*
Y1078092D03*
Y1088131D03*
Y1084785D03*
Y1094824D03*
Y1101517D03*
Y1108210D03*
Y1114903D03*
Y1131635D03*
Y1124942D03*
Y1121596D03*
Y1138328D03*
Y1145021D03*
Y1151714D03*
Y1161753D03*
Y1158407D03*
Y1168446D03*
Y1175139D03*
Y1181832D03*
Y1188525D03*
Y1205257D03*
Y1198564D03*
Y1195218D03*
Y1211950D03*
Y1218643D03*
Y1225336D03*
Y1235375D03*
Y1232029D03*
Y1242068D03*
Y1248761D03*
X766158Y780257D03*
Y786950D03*
Y803682D03*
Y793643D03*
Y796989D03*
Y817068D03*
Y810375D03*
Y823761D03*
Y830454D03*
Y833800D03*
Y840493D03*
Y847186D03*
Y853879D03*
Y860572D03*
Y877304D03*
Y867265D03*
Y870611D03*
Y883997D03*
Y890690D03*
Y897383D03*
Y904076D03*
Y907423D03*
Y914115D03*
Y920808D03*
Y927501D03*
Y934194D03*
Y940887D03*
Y950926D03*
Y944234D03*
Y964312D03*
Y957619D03*
Y971005D03*
Y977698D03*
Y984391D03*
Y1001123D03*
Y997777D03*
Y991084D03*
Y1031241D03*
Y1037934D03*
Y1044627D03*
Y1058013D03*
Y1051320D03*
Y1074745D03*
Y1081438D03*
Y1088131D03*
Y1098171D03*
Y1104863D03*
Y1091478D03*
Y1111556D03*
Y1118249D03*
Y1134982D03*
Y1124942D03*
Y1128289D03*
Y1148367D03*
Y1141675D03*
Y1155060D03*
Y1161753D03*
Y1165100D03*
Y1171793D03*
Y1178486D03*
Y1185178D03*
Y1191871D03*
Y1208604D03*
Y1198564D03*
Y1201911D03*
Y1215297D03*
Y1221989D03*
Y1228682D03*
Y1235375D03*
Y1238722D03*
Y1245415D03*
Y1252108D03*
X782300Y776911D03*
Y783604D03*
Y790297D03*
Y800336D03*
Y807029D03*
Y793643D03*
Y813722D03*
Y820415D03*
Y837147D03*
Y830454D03*
Y827108D03*
Y843840D03*
Y850533D03*
Y857226D03*
Y863919D03*
Y873958D03*
Y880651D03*
Y867265D03*
Y887344D03*
Y894037D03*
Y910769D03*
Y904076D03*
Y900730D03*
Y924155D03*
Y917462D03*
Y930848D03*
Y940887D03*
Y937541D03*
Y947580D03*
Y954273D03*
Y967659D03*
Y974352D03*
Y981045D03*
Y987737D03*
Y994430D03*
Y1001123D03*
Y1027895D03*
Y1034588D03*
Y1041281D03*
Y1047974D03*
Y1054667D03*
Y1061360D03*
Y1071399D03*
Y1064706D03*
Y1078092D03*
Y1088131D03*
Y1084785D03*
Y1094824D03*
Y1101517D03*
Y1108210D03*
Y1114903D03*
Y1131635D03*
Y1124942D03*
Y1121596D03*
Y1138328D03*
Y1145021D03*
Y1151714D03*
Y1161753D03*
Y1158407D03*
Y1168446D03*
Y1175139D03*
Y1181832D03*
Y1188525D03*
Y1205257D03*
Y1198564D03*
Y1195218D03*
Y1211950D03*
Y1218643D03*
Y1225336D03*
Y1235375D03*
Y1232029D03*
Y1242068D03*
Y1248761D03*
X795858Y780257D03*
Y786950D03*
Y803682D03*
Y793643D03*
Y796989D03*
Y817068D03*
Y810375D03*
Y823761D03*
Y830454D03*
Y833800D03*
Y840493D03*
Y847186D03*
Y853879D03*
Y860572D03*
Y877304D03*
Y867265D03*
Y870611D03*
Y883997D03*
Y890690D03*
Y897383D03*
Y904076D03*
Y907423D03*
Y914115D03*
Y920808D03*
Y927501D03*
Y934194D03*
Y940887D03*
Y950926D03*
Y944234D03*
Y964312D03*
Y957619D03*
Y971005D03*
Y977698D03*
Y984391D03*
Y1001123D03*
Y997777D03*
Y991084D03*
Y1031241D03*
Y1037934D03*
Y1044627D03*
Y1058013D03*
Y1051320D03*
Y1074745D03*
Y1081438D03*
Y1088131D03*
Y1098171D03*
Y1104863D03*
Y1091478D03*
Y1111556D03*
Y1118249D03*
Y1134982D03*
Y1124942D03*
Y1128289D03*
Y1148367D03*
Y1141675D03*
Y1155060D03*
Y1161753D03*
Y1165100D03*
Y1171793D03*
Y1178486D03*
Y1185178D03*
Y1191871D03*
Y1208604D03*
Y1198564D03*
Y1201911D03*
Y1215297D03*
Y1221989D03*
Y1228682D03*
Y1235375D03*
Y1238722D03*
Y1245415D03*
Y1252108D03*
X812000Y776911D03*
Y783604D03*
Y790297D03*
Y800336D03*
Y807029D03*
Y793643D03*
Y813722D03*
Y820415D03*
Y837147D03*
Y830454D03*
Y827108D03*
Y843840D03*
Y850533D03*
Y857226D03*
Y863919D03*
Y873958D03*
Y880651D03*
Y867265D03*
Y887344D03*
Y894037D03*
Y910769D03*
Y904076D03*
Y900730D03*
Y924155D03*
Y917462D03*
Y930848D03*
Y940887D03*
Y937541D03*
Y947580D03*
Y954273D03*
Y967659D03*
Y974352D03*
Y981045D03*
Y987737D03*
Y994430D03*
Y1001123D03*
Y1027895D03*
Y1034588D03*
Y1041281D03*
Y1047974D03*
Y1054667D03*
Y1061360D03*
Y1071399D03*
Y1064706D03*
Y1078092D03*
Y1088131D03*
Y1084785D03*
Y1094824D03*
Y1101517D03*
Y1108210D03*
Y1114903D03*
Y1131635D03*
Y1124942D03*
Y1121596D03*
Y1138328D03*
Y1145021D03*
Y1151714D03*
Y1161753D03*
Y1158407D03*
Y1168446D03*
Y1175139D03*
Y1181832D03*
Y1188525D03*
Y1205257D03*
Y1198564D03*
Y1195218D03*
Y1211950D03*
Y1218643D03*
Y1225336D03*
Y1235375D03*
Y1232029D03*
Y1242068D03*
Y1248761D03*
X814296Y1384045D03*
Y1387445D03*
X842320Y-21711D03*
Y-18311D03*
Y-11711D03*
Y-8311D03*
Y18289D03*
Y21689D03*
X1007587Y805418D03*
Y816352D03*
Y819752D03*
Y808818D03*
Y827354D03*
Y830754D03*
Y838356D03*
Y841756D03*
X1045465Y780256D03*
Y786949D03*
Y803681D03*
Y793642D03*
Y796988D03*
Y817067D03*
Y810374D03*
Y823760D03*
Y830453D03*
Y833799D03*
Y840492D03*
Y847185D03*
Y853878D03*
Y860571D03*
Y877303D03*
Y867264D03*
Y870610D03*
Y883996D03*
Y890689D03*
Y897382D03*
Y904075D03*
Y907422D03*
Y914114D03*
Y920807D03*
Y927500D03*
Y934193D03*
Y940886D03*
Y950925D03*
Y944233D03*
Y964311D03*
Y957618D03*
Y971004D03*
Y977697D03*
Y984390D03*
Y1001122D03*
Y997776D03*
Y991083D03*
Y1031240D03*
Y1037933D03*
Y1044626D03*
Y1058012D03*
Y1051319D03*
Y1074744D03*
Y1081437D03*
Y1088130D03*
Y1098170D03*
Y1104862D03*
Y1091477D03*
Y1111555D03*
Y1118248D03*
Y1134981D03*
Y1124941D03*
Y1128288D03*
Y1148366D03*
Y1141674D03*
Y1155059D03*
Y1161752D03*
Y1165099D03*
Y1171792D03*
Y1178485D03*
Y1185177D03*
Y1191870D03*
Y1208603D03*
Y1198563D03*
Y1201910D03*
Y1215296D03*
Y1221988D03*
Y1228681D03*
Y1235374D03*
Y1238721D03*
Y1245414D03*
Y1252107D03*
X1061607Y776910D03*
Y783603D03*
Y790296D03*
Y800335D03*
Y807028D03*
Y793642D03*
Y813721D03*
Y820414D03*
Y837146D03*
Y830453D03*
Y827107D03*
Y843839D03*
Y850532D03*
Y857225D03*
Y863918D03*
Y873957D03*
Y880650D03*
Y867264D03*
Y887343D03*
Y894036D03*
Y910768D03*
Y904075D03*
Y900729D03*
Y924154D03*
Y917461D03*
Y930847D03*
Y940886D03*
Y937540D03*
Y947579D03*
Y954272D03*
Y967658D03*
Y974351D03*
Y981044D03*
Y987736D03*
Y994429D03*
Y1001122D03*
Y1027894D03*
Y1034587D03*
Y1041280D03*
Y1047973D03*
Y1054666D03*
Y1061359D03*
Y1071398D03*
Y1064705D03*
Y1078091D03*
Y1088130D03*
Y1084784D03*
Y1094823D03*
Y1101516D03*
Y1108209D03*
Y1114902D03*
Y1131634D03*
Y1124941D03*
Y1121595D03*
Y1138327D03*
Y1145020D03*
Y1151713D03*
Y1161752D03*
Y1158406D03*
Y1168445D03*
Y1175138D03*
Y1181831D03*
Y1188524D03*
Y1205256D03*
Y1198563D03*
Y1195217D03*
Y1211949D03*
Y1218642D03*
Y1225335D03*
Y1235374D03*
Y1232028D03*
Y1242067D03*
Y1248760D03*
X1075166Y780256D03*
Y786949D03*
Y803681D03*
Y793642D03*
Y796988D03*
Y817067D03*
Y810374D03*
Y823760D03*
Y830453D03*
Y833799D03*
Y840492D03*
Y847185D03*
Y853878D03*
Y860571D03*
Y877303D03*
Y867264D03*
Y870610D03*
Y883996D03*
Y890689D03*
Y897382D03*
Y904075D03*
Y907422D03*
Y914114D03*
Y920807D03*
Y927500D03*
Y934193D03*
Y940886D03*
Y950925D03*
Y944233D03*
Y964311D03*
Y957618D03*
Y971004D03*
Y977697D03*
Y984390D03*
Y1001122D03*
Y997776D03*
Y991083D03*
Y1031240D03*
Y1037933D03*
Y1044626D03*
Y1058012D03*
Y1051319D03*
Y1074744D03*
Y1081437D03*
Y1088130D03*
Y1098170D03*
Y1104862D03*
Y1091477D03*
Y1111555D03*
Y1118248D03*
Y1134981D03*
Y1124941D03*
Y1128288D03*
Y1148366D03*
Y1141674D03*
Y1155059D03*
Y1161752D03*
Y1165099D03*
Y1171792D03*
Y1178485D03*
Y1185177D03*
Y1191870D03*
Y1208603D03*
Y1198563D03*
Y1201910D03*
Y1215296D03*
Y1221988D03*
Y1228681D03*
Y1235374D03*
Y1238721D03*
Y1245414D03*
Y1252107D03*
X1091308Y776910D03*
Y783603D03*
Y790296D03*
Y800335D03*
Y807028D03*
Y793642D03*
Y813721D03*
Y820414D03*
Y837146D03*
Y830453D03*
Y827107D03*
Y843839D03*
Y850532D03*
Y857225D03*
Y863918D03*
Y873957D03*
Y880650D03*
Y867264D03*
Y887343D03*
Y894036D03*
Y910768D03*
Y904075D03*
Y900729D03*
Y924154D03*
Y917461D03*
Y930847D03*
Y940886D03*
Y937540D03*
Y947579D03*
Y954272D03*
Y967658D03*
Y974351D03*
Y981044D03*
Y987736D03*
Y994429D03*
Y1001122D03*
Y1027894D03*
Y1034587D03*
Y1041280D03*
Y1047973D03*
Y1054666D03*
Y1061359D03*
Y1071398D03*
Y1064705D03*
Y1078091D03*
Y1088130D03*
Y1084784D03*
Y1094823D03*
Y1101516D03*
Y1108209D03*
Y1114902D03*
Y1131634D03*
Y1124941D03*
Y1121595D03*
Y1138327D03*
Y1145020D03*
Y1151713D03*
Y1161752D03*
Y1158406D03*
Y1168445D03*
Y1175138D03*
Y1181831D03*
Y1188524D03*
Y1205256D03*
Y1198563D03*
Y1195217D03*
Y1211949D03*
Y1218642D03*
Y1225335D03*
Y1235374D03*
Y1232028D03*
Y1242067D03*
Y1248760D03*
X1104866Y780256D03*
Y786949D03*
Y803681D03*
Y793642D03*
Y796988D03*
Y817067D03*
Y810374D03*
Y823760D03*
Y830453D03*
Y833799D03*
Y840492D03*
Y847185D03*
Y853878D03*
Y860571D03*
Y877303D03*
Y867264D03*
Y870610D03*
Y883996D03*
Y890689D03*
Y897382D03*
Y904075D03*
Y907422D03*
Y914114D03*
Y920807D03*
Y927500D03*
Y934193D03*
Y940886D03*
Y950925D03*
Y944233D03*
Y964311D03*
Y957618D03*
Y971004D03*
Y977697D03*
Y984390D03*
Y1001122D03*
Y997776D03*
Y991083D03*
Y1031240D03*
Y1037933D03*
Y1044626D03*
Y1058012D03*
Y1051319D03*
Y1074744D03*
Y1081437D03*
Y1088130D03*
Y1098170D03*
Y1104862D03*
Y1091477D03*
Y1111555D03*
Y1118248D03*
Y1134981D03*
Y1124941D03*
Y1128288D03*
Y1148366D03*
Y1141674D03*
Y1155059D03*
Y1161752D03*
Y1165099D03*
Y1171792D03*
Y1178485D03*
Y1185177D03*
Y1191870D03*
Y1208603D03*
Y1198563D03*
Y1201910D03*
Y1215296D03*
Y1221988D03*
Y1228681D03*
Y1235374D03*
Y1238721D03*
Y1245414D03*
Y1252107D03*
X1121008Y776910D03*
Y783603D03*
Y790296D03*
Y800335D03*
Y807028D03*
Y793642D03*
Y813721D03*
Y820414D03*
Y837146D03*
Y830453D03*
Y827107D03*
Y843839D03*
Y850532D03*
Y857225D03*
Y863918D03*
Y873957D03*
Y880650D03*
Y867264D03*
Y887343D03*
Y894036D03*
Y910768D03*
Y904075D03*
Y900729D03*
Y924154D03*
Y917461D03*
Y930847D03*
Y940886D03*
Y937540D03*
Y947579D03*
Y954272D03*
Y967658D03*
Y974351D03*
Y981044D03*
Y987736D03*
Y994429D03*
Y1001122D03*
Y1027894D03*
Y1034587D03*
Y1041280D03*
Y1047973D03*
Y1054666D03*
Y1061359D03*
Y1071398D03*
Y1064705D03*
Y1078091D03*
Y1088130D03*
Y1084784D03*
Y1094823D03*
Y1101516D03*
Y1108209D03*
Y1114902D03*
Y1131634D03*
Y1124941D03*
Y1121595D03*
Y1138327D03*
Y1145020D03*
Y1151713D03*
Y1161752D03*
Y1158406D03*
Y1168445D03*
Y1175138D03*
Y1181831D03*
Y1188524D03*
Y1205256D03*
Y1198563D03*
Y1195217D03*
Y1211949D03*
Y1218642D03*
Y1225335D03*
Y1235374D03*
Y1232028D03*
Y1242067D03*
Y1248760D03*
X1134567Y780256D03*
Y786949D03*
Y803681D03*
Y793642D03*
Y796988D03*
Y817067D03*
Y810374D03*
Y823760D03*
Y830453D03*
Y833799D03*
Y840492D03*
Y847185D03*
Y853878D03*
Y860571D03*
Y877303D03*
Y867264D03*
Y870610D03*
Y883996D03*
Y890689D03*
Y897382D03*
Y904075D03*
Y907422D03*
Y914114D03*
Y920807D03*
Y927500D03*
Y934193D03*
Y940886D03*
Y950925D03*
Y944233D03*
Y964311D03*
Y957618D03*
Y971004D03*
Y977697D03*
Y984390D03*
Y1001122D03*
Y997776D03*
Y991083D03*
Y1031240D03*
Y1037933D03*
Y1044626D03*
Y1058012D03*
Y1051319D03*
Y1074744D03*
Y1081437D03*
Y1088130D03*
Y1098170D03*
Y1104862D03*
Y1091477D03*
Y1111555D03*
Y1118248D03*
Y1134981D03*
Y1124941D03*
Y1128288D03*
Y1148366D03*
Y1141674D03*
Y1155059D03*
Y1161752D03*
Y1165099D03*
Y1171792D03*
Y1178485D03*
Y1185177D03*
Y1191870D03*
Y1208603D03*
Y1198563D03*
Y1201910D03*
Y1215296D03*
Y1221988D03*
Y1228681D03*
Y1235374D03*
Y1238721D03*
Y1245414D03*
Y1252107D03*
X1150709Y776910D03*
Y783603D03*
Y790296D03*
Y800335D03*
Y807028D03*
Y793642D03*
Y813721D03*
Y820414D03*
Y837146D03*
Y830453D03*
Y827107D03*
Y843839D03*
Y850532D03*
Y857225D03*
Y863918D03*
Y873957D03*
Y880650D03*
Y867264D03*
Y887343D03*
Y894036D03*
Y910768D03*
Y904075D03*
Y900729D03*
Y924154D03*
Y917461D03*
Y930847D03*
Y940886D03*
Y937540D03*
Y947579D03*
Y954272D03*
Y967658D03*
Y974351D03*
Y981044D03*
Y987736D03*
Y994429D03*
Y1001122D03*
Y1027894D03*
Y1034587D03*
Y1041280D03*
Y1047973D03*
Y1054666D03*
Y1061359D03*
Y1071398D03*
Y1064705D03*
Y1078091D03*
Y1088130D03*
Y1084784D03*
Y1094823D03*
Y1101516D03*
Y1108209D03*
Y1114902D03*
Y1131634D03*
Y1124941D03*
Y1121595D03*
Y1138327D03*
Y1145020D03*
Y1151713D03*
Y1161752D03*
Y1158406D03*
Y1168445D03*
Y1175138D03*
Y1181831D03*
Y1188524D03*
Y1205256D03*
Y1198563D03*
Y1195217D03*
Y1211949D03*
Y1218642D03*
Y1225335D03*
Y1235374D03*
Y1232028D03*
Y1242067D03*
Y1248760D03*
X1170986Y1516590D03*
Y1513190D03*
Y1534990D03*
Y1538390D03*
X1177404Y-21711D03*
Y-18311D03*
Y-11711D03*
Y-8311D03*
Y18289D03*
Y21689D03*
X1183924Y1485895D03*
X1180624Y1495595D03*
X1177224D03*
X1185910Y960965D03*
X1187324Y1485895D03*
X1200724Y1505295D03*
X1197324D03*
X1196039Y1625380D03*
X1199439D03*
X1196039Y1657292D03*
X1199439D03*
X1214124Y1485895D03*
X1210724D03*
X1207424Y1495595D03*
X1204024D03*
X1208099Y1625380D03*
X1211499D03*
X1208099Y1657292D03*
X1211499D03*
X1227524Y1505295D03*
X1224124D03*
X1230824Y1495595D03*
X1220159Y1625380D03*
X1223559D03*
X1220159Y1657292D03*
X1223559D03*
X1240924Y1485895D03*
X1237524D03*
X1234224Y1495595D03*
X1232219Y1625380D03*
X1244279D03*
X1235619D03*
X1232219Y1657292D03*
X1244279D03*
X1235619D03*
X1245840Y-28311D03*
Y-31711D03*
Y-18311D03*
Y-21711D03*
Y1689D03*
Y-1711D03*
Y11689D03*
Y8289D03*
X1254324Y1505295D03*
X1250924D03*
X1257624Y1495595D03*
X1256339Y1625380D03*
X1247679D03*
X1259739D03*
X1256339Y1657292D03*
X1247679D03*
X1259739D03*
X1267724Y1485895D03*
X1264324D03*
X1261024Y1495595D03*
X1268399Y1625380D03*
X1271799D03*
X1268399Y1657292D03*
X1271799D03*
X1277724Y1485895D03*
X1281124D03*
X1288494Y1517082D03*
Y1513682D03*
Y1530482D03*
Y1527082D03*
X1280459Y1625380D03*
X1283859D03*
X1280459Y1657292D03*
X1283859D03*
X1305286Y1495595D03*
X1299048Y1516590D03*
Y1513190D03*
Y1534990D03*
Y1538390D03*
X1292519Y1625380D03*
X1304579D03*
X1295919D03*
X1292519Y1657292D03*
X1304579D03*
X1295919D03*
X1315386Y1485895D03*
X1311986D03*
X1308686Y1495595D03*
X1316639Y1625380D03*
X1320039D03*
X1307979D03*
X1316639Y1657292D03*
X1320039D03*
X1307979D03*
X1328786Y1505295D03*
X1325386D03*
X1332086Y1495595D03*
X1328699Y1625380D03*
X1332099D03*
X1328699Y1657292D03*
X1332099D03*
X1342186Y1485895D03*
X1338786D03*
X1335486Y1495595D03*
X1340759Y1625380D03*
X1344159D03*
X1340759Y1657292D03*
X1344159D03*
X1355586Y1505295D03*
X1362286Y1495595D03*
X1352186Y1505295D03*
X1358886Y1495595D03*
X1352819Y1625380D03*
X1356219D03*
X1352819Y1657292D03*
X1356219D03*
X1368986Y1485895D03*
X1365586D03*
X1378986Y1505295D03*
X1364879Y1625380D03*
X1376939D03*
X1368279D03*
X1364879Y1657292D03*
X1376939D03*
X1368279D03*
X1392386Y1485895D03*
X1382386Y1505295D03*
X1389086Y1495595D03*
X1385686D03*
X1380339Y1625380D03*
Y1657292D03*
X1395786Y1485895D03*
X1409186D03*
X1405786D03*
X1416556Y1513682D03*
Y1517082D03*
Y1530482D03*
Y1527082D03*
X1436263Y-28311D03*
Y-31711D03*
Y-18311D03*
Y-21711D03*
Y1689D03*
Y-1711D03*
Y11689D03*
Y8289D03*
X1435160Y1516590D03*
Y1513190D03*
Y1534990D03*
Y1538390D03*
X1451498Y1485895D03*
X1448098D03*
X1444798Y1495595D03*
X1441398D03*
X1464898Y1505295D03*
X1461498D03*
X1468198Y1495595D03*
X1460213Y1625380D03*
X1463613D03*
X1460213Y1657292D03*
X1463613D03*
X1478298Y1485895D03*
X1474898D03*
X1471598Y1495595D03*
X1472273Y1625380D03*
X1475673D03*
X1472273Y1657292D03*
X1475673D03*
X1491698Y1505295D03*
X1488298D03*
X1498398Y1495595D03*
X1494998D03*
X1484333Y1625380D03*
X1496393D03*
X1487733D03*
X1484333Y1657292D03*
X1496393D03*
X1487733D03*
X1505098Y1485895D03*
X1501698D03*
X1508453Y1625380D03*
X1499793D03*
X1511853D03*
X1508453Y1657292D03*
X1499793D03*
X1511853D03*
X1528498Y1485895D03*
X1518498Y1505295D03*
X1525198Y1495595D03*
X1515098Y1505295D03*
X1521798Y1495595D03*
X1520513Y1625380D03*
X1523913D03*
X1520513Y1657292D03*
X1523913D03*
X1539134Y-22512D03*
Y-25912D03*
X1535566Y69340D03*
X1538966D03*
X1531898Y1485895D03*
X1541898D03*
X1532573Y1625380D03*
X1535973D03*
X1532573Y1657292D03*
X1535973D03*
X1552674Y26477D03*
X1556379Y19541D03*
X1549274Y26477D03*
X1557566Y69340D03*
X1546562Y75343D03*
X1549962D03*
X1545298Y1485895D03*
X1552668Y1513682D03*
Y1517082D03*
Y1530482D03*
Y1527082D03*
X1544633Y1625380D03*
X1556693D03*
X1548033D03*
X1544633Y1657292D03*
X1556693D03*
X1548033D03*
X1566847Y26477D03*
X1559779Y19541D03*
X1570552D03*
X1563447Y26477D03*
X1568566Y75340D03*
X1571966D03*
X1560966Y69340D03*
X1568753Y1625380D03*
X1560093D03*
X1572153D03*
X1568753Y1657292D03*
X1560093D03*
X1572153D03*
X1588125Y19541D03*
X1581020Y26477D03*
X1573952Y19541D03*
X1584725D03*
X1577620Y26477D03*
X1579566Y69340D03*
X1582966D03*
X1580813Y1625380D03*
X1584213D03*
X1580813Y1657292D03*
X1584213D03*
X1602299Y19541D03*
X1595194Y26477D03*
X1598899Y19541D03*
X1591794Y26477D03*
X1590566Y75340D03*
X1601562Y69343D03*
X1593966Y75340D03*
X1592873Y1625380D03*
X1596273D03*
X1592873Y1657292D03*
X1596273D03*
X1612566Y75340D03*
X1615966D03*
X1604962Y69343D03*
X1604933Y1625380D03*
X1616993D03*
X1608333D03*
X1604933Y1657292D03*
X1616993D03*
X1608333D03*
X1631060Y26477D03*
X1627660D03*
X1623562Y69343D03*
X1626962D03*
X1629053Y1625380D03*
X1620393D03*
X1632453D03*
X1629053Y1657292D03*
X1620393D03*
X1632453D03*
X1645233Y26477D03*
X1638165Y19541D03*
X1641833Y26477D03*
X1634765Y19541D03*
X1646770Y69340D03*
X1635770Y75340D03*
X1639170D03*
X1641113Y1625380D03*
X1644513D03*
X1641113Y1657292D03*
X1644513D03*
X1652338Y19541D03*
X1648938D03*
X1657766Y75343D03*
X1661166D03*
X1650170Y69340D03*
X1675194Y26477D03*
X1671794D03*
X1668770Y69340D03*
X1672170D03*
X1663839Y960965D03*
X1689367Y26477D03*
X1682299Y19541D03*
X1685967Y26477D03*
X1678899Y19541D03*
X1690900Y69343D03*
X1679904Y75340D03*
X1683304D03*
X1682898Y780256D03*
Y786949D03*
Y803681D03*
Y793642D03*
Y796988D03*
Y817067D03*
Y810374D03*
Y823760D03*
Y830453D03*
Y833799D03*
Y840492D03*
Y847185D03*
Y853878D03*
Y860571D03*
Y877303D03*
Y867264D03*
Y870610D03*
Y883996D03*
Y890689D03*
Y897382D03*
Y904075D03*
Y907422D03*
Y914114D03*
Y920807D03*
Y927500D03*
Y934193D03*
Y940886D03*
Y950925D03*
Y944233D03*
Y964311D03*
Y957618D03*
Y971004D03*
Y977697D03*
Y984390D03*
Y1001122D03*
Y997776D03*
Y991083D03*
Y1031240D03*
Y1037933D03*
Y1044626D03*
Y1058012D03*
Y1051319D03*
Y1074744D03*
Y1081437D03*
Y1088130D03*
Y1098170D03*
Y1104862D03*
Y1091477D03*
Y1111555D03*
Y1118248D03*
Y1134981D03*
Y1124941D03*
Y1128288D03*
Y1148366D03*
Y1141674D03*
Y1155059D03*
Y1161752D03*
Y1165099D03*
Y1171792D03*
Y1178485D03*
Y1185177D03*
Y1191870D03*
Y1208603D03*
Y1198563D03*
Y1201910D03*
Y1215296D03*
Y1221988D03*
Y1228681D03*
Y1235374D03*
Y1238721D03*
Y1245414D03*
Y1252107D03*
X1696472Y19541D03*
X1693072D03*
X1701904Y75340D03*
X1705304D03*
X1694300Y69343D03*
X1699040Y776910D03*
Y783603D03*
Y790296D03*
Y800335D03*
Y807028D03*
Y793642D03*
Y813721D03*
Y820414D03*
Y837146D03*
Y830453D03*
Y827107D03*
Y843839D03*
Y850532D03*
Y857225D03*
Y863918D03*
Y873957D03*
Y880650D03*
Y867264D03*
Y887343D03*
Y894036D03*
Y910768D03*
Y904075D03*
Y900729D03*
Y924154D03*
Y917461D03*
Y930847D03*
Y940886D03*
Y937540D03*
Y947579D03*
Y954272D03*
Y967658D03*
Y974351D03*
Y981044D03*
Y987736D03*
Y994429D03*
Y1001122D03*
Y1027894D03*
Y1034587D03*
Y1041280D03*
Y1047973D03*
Y1054666D03*
Y1061359D03*
Y1071398D03*
Y1064705D03*
Y1078091D03*
Y1088130D03*
Y1084784D03*
Y1094823D03*
Y1101516D03*
Y1108209D03*
Y1114902D03*
Y1131634D03*
Y1124941D03*
Y1121595D03*
Y1138327D03*
Y1145020D03*
Y1151713D03*
Y1161752D03*
Y1158406D03*
Y1168445D03*
Y1175138D03*
Y1181831D03*
Y1188524D03*
Y1205256D03*
Y1198563D03*
Y1195217D03*
Y1211949D03*
Y1218642D03*
Y1225335D03*
Y1235374D03*
Y1232028D03*
Y1242067D03*
Y1248760D03*
X1712599Y780256D03*
Y786949D03*
Y803681D03*
Y793642D03*
Y796988D03*
Y817067D03*
Y810374D03*
Y823760D03*
Y830453D03*
Y833799D03*
Y840492D03*
Y847185D03*
Y853878D03*
Y860571D03*
Y877303D03*
Y867264D03*
Y870610D03*
Y883996D03*
Y890689D03*
Y897382D03*
Y904075D03*
Y907422D03*
Y914114D03*
Y920807D03*
Y927500D03*
Y934193D03*
Y940886D03*
Y950925D03*
Y944233D03*
Y964311D03*
Y957618D03*
Y971004D03*
Y977697D03*
Y984390D03*
Y1001122D03*
Y997776D03*
Y991083D03*
Y1031240D03*
Y1037933D03*
Y1044626D03*
Y1058012D03*
Y1051319D03*
Y1074744D03*
Y1081437D03*
Y1088130D03*
Y1098170D03*
Y1104862D03*
Y1091477D03*
Y1111555D03*
Y1118248D03*
Y1134981D03*
Y1124941D03*
Y1128288D03*
Y1148366D03*
Y1141674D03*
Y1155059D03*
Y1161752D03*
Y1165099D03*
Y1171792D03*
Y1178485D03*
Y1185177D03*
Y1191870D03*
Y1208603D03*
Y1198563D03*
Y1201910D03*
Y1215296D03*
Y1221988D03*
Y1228681D03*
Y1235374D03*
Y1238721D03*
Y1245414D03*
Y1252107D03*
X1729557Y-22512D03*
Y-25912D03*
X1728741Y776910D03*
Y783603D03*
Y790296D03*
Y800335D03*
Y807028D03*
Y793642D03*
Y813721D03*
Y820414D03*
Y837146D03*
Y830453D03*
Y827107D03*
Y843839D03*
Y850532D03*
Y857225D03*
Y863918D03*
Y873957D03*
Y880650D03*
Y867264D03*
Y887343D03*
Y894036D03*
Y910768D03*
Y904075D03*
Y900729D03*
Y924154D03*
Y917461D03*
Y930847D03*
Y940886D03*
Y937540D03*
Y947579D03*
Y954272D03*
Y967658D03*
Y974351D03*
Y981044D03*
Y987736D03*
Y994429D03*
Y1001122D03*
Y1027894D03*
Y1034587D03*
Y1041280D03*
Y1047973D03*
Y1054666D03*
Y1061359D03*
Y1071398D03*
Y1064705D03*
Y1078091D03*
Y1088130D03*
Y1084784D03*
Y1094823D03*
Y1101516D03*
Y1108209D03*
Y1114902D03*
Y1131634D03*
Y1124941D03*
Y1121595D03*
Y1138327D03*
Y1145020D03*
Y1151713D03*
Y1161752D03*
Y1158406D03*
Y1168445D03*
Y1175138D03*
Y1181831D03*
Y1188524D03*
Y1205256D03*
Y1198563D03*
Y1195217D03*
Y1211949D03*
Y1218642D03*
Y1225335D03*
Y1235374D03*
Y1232028D03*
Y1242067D03*
Y1248760D03*
X1742300Y780256D03*
Y786949D03*
Y803681D03*
Y793642D03*
Y796988D03*
Y817067D03*
Y810374D03*
Y823760D03*
Y830453D03*
Y833799D03*
Y840492D03*
Y847185D03*
Y853878D03*
Y860571D03*
Y877303D03*
Y867264D03*
Y870610D03*
Y883996D03*
Y890689D03*
Y897382D03*
Y904075D03*
Y907422D03*
Y914114D03*
Y920807D03*
Y927500D03*
Y934193D03*
Y940886D03*
Y950925D03*
Y944233D03*
Y964311D03*
Y957618D03*
Y971004D03*
Y977697D03*
Y984390D03*
Y1001122D03*
Y997776D03*
Y991083D03*
Y1031240D03*
Y1037933D03*
Y1044626D03*
Y1058012D03*
Y1051319D03*
Y1074744D03*
Y1081437D03*
Y1088130D03*
Y1098170D03*
Y1104862D03*
Y1091477D03*
Y1111555D03*
Y1118248D03*
Y1134981D03*
Y1124941D03*
Y1128288D03*
Y1148366D03*
Y1141674D03*
Y1155059D03*
Y1161752D03*
Y1165099D03*
Y1171792D03*
Y1178485D03*
Y1185177D03*
Y1191870D03*
Y1208603D03*
Y1198563D03*
Y1201910D03*
Y1215296D03*
Y1221988D03*
Y1228681D03*
Y1235374D03*
Y1238721D03*
Y1245414D03*
Y1252107D03*
X1758442Y776910D03*
Y783603D03*
Y790296D03*
Y800335D03*
Y807028D03*
Y793642D03*
Y813721D03*
Y820414D03*
Y837146D03*
Y830453D03*
Y827107D03*
Y843839D03*
Y850532D03*
Y857225D03*
Y863918D03*
Y873957D03*
Y880650D03*
Y867264D03*
Y887343D03*
Y894036D03*
Y910768D03*
Y904075D03*
Y900729D03*
Y924154D03*
Y917461D03*
Y930847D03*
Y940886D03*
Y937540D03*
Y947579D03*
Y954272D03*
Y967658D03*
Y974351D03*
Y981044D03*
Y987736D03*
Y994429D03*
Y1001122D03*
Y1027894D03*
Y1034587D03*
Y1041280D03*
Y1047973D03*
Y1054666D03*
Y1061359D03*
Y1071398D03*
Y1064705D03*
Y1078091D03*
Y1088130D03*
Y1084784D03*
Y1094823D03*
Y1101516D03*
Y1108209D03*
Y1114902D03*
Y1131634D03*
Y1124941D03*
Y1121595D03*
Y1138327D03*
Y1145020D03*
Y1151713D03*
Y1161752D03*
Y1158406D03*
Y1168445D03*
Y1175138D03*
Y1181831D03*
Y1188524D03*
Y1205256D03*
Y1198563D03*
Y1195217D03*
Y1211949D03*
Y1218642D03*
Y1225335D03*
Y1235374D03*
Y1232028D03*
Y1242067D03*
Y1248760D03*
X1772000Y780256D03*
Y786949D03*
Y803681D03*
Y793642D03*
Y796988D03*
Y817067D03*
Y810374D03*
Y823760D03*
Y830453D03*
Y833799D03*
Y840492D03*
Y847185D03*
Y853878D03*
Y860571D03*
Y877303D03*
Y867264D03*
Y870610D03*
Y883996D03*
Y890689D03*
Y897382D03*
Y904075D03*
Y907422D03*
Y914114D03*
Y920807D03*
Y927500D03*
Y934193D03*
Y940886D03*
Y950925D03*
Y944233D03*
Y964311D03*
Y957618D03*
Y971004D03*
Y977697D03*
Y984390D03*
Y1001122D03*
Y997776D03*
Y991083D03*
Y1031240D03*
Y1037933D03*
Y1044626D03*
Y1058012D03*
Y1051319D03*
Y1074744D03*
Y1081437D03*
Y1088130D03*
Y1098170D03*
Y1104862D03*
Y1091477D03*
Y1111555D03*
Y1118248D03*
Y1134981D03*
Y1124941D03*
Y1128288D03*
Y1148366D03*
Y1141674D03*
Y1155059D03*
Y1161752D03*
Y1165099D03*
Y1171792D03*
Y1178485D03*
Y1185177D03*
Y1191870D03*
Y1208603D03*
Y1198563D03*
Y1201910D03*
Y1215296D03*
Y1221988D03*
Y1228681D03*
Y1235374D03*
Y1238721D03*
Y1245414D03*
Y1252107D03*
X1788142Y776910D03*
Y783603D03*
Y790296D03*
Y800335D03*
Y807028D03*
Y793642D03*
Y813721D03*
Y820414D03*
Y837146D03*
Y830453D03*
Y827107D03*
Y843839D03*
Y850532D03*
Y857225D03*
Y863918D03*
Y873957D03*
Y880650D03*
Y867264D03*
Y887343D03*
Y894036D03*
Y910768D03*
Y904075D03*
Y900729D03*
Y924154D03*
Y917461D03*
Y930847D03*
Y940886D03*
Y937540D03*
Y947579D03*
Y954272D03*
Y967658D03*
Y974351D03*
Y981044D03*
Y987736D03*
Y994429D03*
Y1001122D03*
Y1027894D03*
Y1034587D03*
Y1041280D03*
Y1047973D03*
Y1054666D03*
Y1061359D03*
Y1071398D03*
Y1064705D03*
Y1078091D03*
Y1088130D03*
Y1084784D03*
Y1094823D03*
Y1101516D03*
Y1108209D03*
Y1114902D03*
Y1131634D03*
Y1124941D03*
Y1121595D03*
Y1138327D03*
Y1145020D03*
Y1151713D03*
Y1161752D03*
Y1158406D03*
Y1168445D03*
Y1175138D03*
Y1181831D03*
Y1188524D03*
Y1205256D03*
Y1198563D03*
Y1195217D03*
Y1211949D03*
Y1218642D03*
Y1225335D03*
Y1235374D03*
Y1232028D03*
Y1242067D03*
Y1248760D03*
G54D22*
X60303Y20354D03*
X312921Y24291D03*
X505185Y41141D03*
X757803Y45078D03*
X929331Y160413D03*
X922441Y237697D03*
X1534712Y20354D03*
X1787330Y24291D03*
G54D32*
X205478Y1536063D03*
X210202D03*
X219651D03*
X229100D03*
X233824D03*
X243273D03*
X253002Y1514243D03*
X252722Y1536063D03*
X302413Y906182D03*
Y912560D03*
Y918938D03*
Y925316D03*
Y931694D03*
Y938072D03*
Y944450D03*
Y950828D03*
Y957206D03*
Y963584D03*
Y969962D03*
Y976340D03*
Y982718D03*
Y989096D03*
Y995474D03*
Y1008230D03*
Y1001852D03*
X303594Y1030198D03*
Y1036576D03*
Y1042954D03*
Y1055710D03*
Y1049332D03*
Y1062088D03*
Y1074844D03*
Y1068466D03*
Y1081222D03*
Y1087600D03*
Y1093978D03*
Y1100356D03*
Y1106734D03*
Y1113112D03*
Y1119490D03*
Y1125868D03*
Y1132246D03*
Y1138623D03*
Y1145001D03*
Y1157757D03*
Y1151379D03*
X333540Y1536063D03*
X338264D03*
X347713D03*
X357162D03*
X361886D03*
X380784D03*
X371335D03*
X381064Y1514243D03*
X408614Y997608D03*
X410464Y1007175D03*
X404923Y1010366D03*
X423417Y997608D03*
X416015D03*
X430819D03*
X445622D03*
X453023D03*
X467826D03*
X460425D03*
X469651Y1536063D03*
X483824D03*
X474375D03*
X497997D03*
X493273D03*
X507446D03*
X526370Y1165290D03*
X515268D03*
X518969D03*
X522670D03*
X517175Y1514243D03*
X516895Y1536063D03*
X533772Y1165290D03*
X530071D03*
X602437Y1536063D03*
X597713D03*
X611886D03*
X626059D03*
X621335D03*
X645237Y1514243D03*
X644957Y1536063D03*
X635508D03*
X1213351Y1569063D03*
X1227524D03*
X1218075D03*
X1241697D03*
X1236973D03*
X1251146D03*
X1260875Y1547243D03*
X1260595Y1569063D03*
X1278555Y906181D03*
Y912559D03*
Y918937D03*
Y925315D03*
Y931693D03*
Y938071D03*
Y950827D03*
Y944449D03*
Y957205D03*
Y963583D03*
Y969961D03*
Y976339D03*
Y982717D03*
Y995473D03*
Y989095D03*
Y1008229D03*
Y1001851D03*
X1279736Y1030197D03*
Y1042953D03*
Y1036575D03*
Y1055709D03*
Y1049331D03*
Y1062087D03*
Y1068465D03*
Y1074843D03*
Y1081221D03*
Y1087599D03*
Y1093977D03*
Y1100355D03*
Y1106733D03*
Y1113111D03*
Y1119489D03*
Y1125867D03*
Y1132245D03*
Y1138622D03*
Y1145000D03*
Y1151378D03*
Y1157756D03*
X1346137Y1569063D03*
X1341413D03*
X1355586D03*
X1379208D03*
X1369759D03*
X1365035D03*
X1384756Y997607D03*
X1392157D03*
X1386606Y1007174D03*
X1381065Y1010365D03*
X1388937Y1547243D03*
X1388657Y1569063D03*
X1406961Y997607D03*
X1399559D03*
X1421764D03*
X1436567D03*
X1429165D03*
X1443968D03*
X1482249Y1569063D03*
X1477525D03*
X1491698D03*
X1502512Y1165289D03*
X1505871Y1569063D03*
X1501147D03*
X1525049Y1547243D03*
X1524769Y1569063D03*
X1515320D03*
X1610311D03*
X1605587D03*
X1629209D03*
X1619760D03*
X1643382D03*
X1633933D03*
X1653111Y1547243D03*
X1652831Y1569063D03*
G54D44*
X381770Y-30570D03*
X385023Y-30584D03*
X388048Y-29264D03*
X381755Y-28055D03*
X385008Y-28069D03*
X381740Y-25540D03*
X381725Y-23025D03*
X723479Y-19234D03*
Y-9234D03*
X833421Y-36647D03*
X839699Y-35341D03*
X833406Y-34132D03*
X836674Y-36661D03*
X836659Y-34146D03*
X833391Y-31617D03*
X833376Y-29102D03*
X836644Y-31631D03*
X836629Y-29116D03*
X1174958Y-15374D03*
Y-5374D03*
Y24626D03*
X1433817Y-25374D03*
Y-15374D03*
Y14626D03*
X1530063Y-40911D03*
X1530033Y-35881D03*
X1530018Y-33366D03*
X1530048Y-38396D03*
X1533316Y-40925D03*
X1536341Y-39605D03*
X1533301Y-38410D03*
X1727111Y-19575D03*
G54D83*
X1898799Y1198198D03*
X1908799D03*
X1921395Y-39963D03*
X1931395D03*
X1942395Y572417D03*
X1940886Y1198170D03*
X1963362Y-39821D03*
X1952395Y572417D03*
X1950886Y1198170D03*
X1973362Y-39821D03*
X1984482Y572389D03*
X1982856Y1198350D03*
X1992856D03*
X2005452Y-39811D03*
X1994482Y572389D03*
X2015452Y-39811D03*
X2026452Y572569D03*
X2036452D03*
X2047419Y-39669D03*
X2057419D03*
X2068539Y572541D03*
X2078539D03*
G54D48*
X539016Y274272D03*
X559016D03*
X569016D03*
X579016D03*
X589016D03*
X599016D03*
X609016D03*
G54D62*
X918780Y1684890D03*
Y1694890D03*
Y1714890D03*
X928780Y1684890D03*
Y1694890D03*
Y1704890D03*
Y1714890D03*
X938780Y1684890D03*
Y1694890D03*
Y1704890D03*
Y1714890D03*
G54D67*
X1225530Y67471D03*
X1454797Y80345D03*
G54D81*
X1900275Y-29973D03*
Y562227D03*
X1898799Y1208198D03*
Y1800398D03*
X1910275Y-29973D03*
Y562227D03*
X1908799Y1208198D03*
Y1800398D03*
X1921395Y-29963D03*
X1931395D03*
Y562237D03*
X1921395D03*
X1931395Y582237D03*
X1921395D03*
Y1174437D03*
X1931395D03*
X1929766Y1208160D03*
X1919766D03*
Y1800360D03*
X1929766D03*
X1942395Y-29783D03*
Y562417D03*
Y582417D03*
Y1174617D03*
X1940886Y1208170D03*
Y1800370D03*
X1952395Y-29783D03*
Y562417D03*
Y582417D03*
Y1174617D03*
X1950886Y1208170D03*
X1961856D03*
X1950886Y1800370D03*
X1961856D03*
X1963362Y-29821D03*
X1973362D03*
Y562379D03*
X1963362D03*
X1973362Y582379D03*
X1963362D03*
Y1174579D03*
X1973362D03*
X1971856Y1208170D03*
Y1800370D03*
X1984482Y-29811D03*
Y562389D03*
Y582389D03*
Y1174589D03*
X1982856Y1208350D03*
Y1800550D03*
X1994482Y-29811D03*
X2005452D03*
X1994482Y562389D03*
X2005452D03*
Y582389D03*
X1994482D03*
Y1174589D03*
X2005452D03*
X1992856Y1208350D03*
X2003823Y1208312D03*
X1992856Y1800550D03*
X2003823Y1800512D03*
X2015452Y-29811D03*
Y562389D03*
Y582389D03*
Y1174589D03*
X2013823Y1208312D03*
Y1800512D03*
X2036452Y-29631D03*
X2026452D03*
Y562569D03*
X2036452D03*
X2026452Y582569D03*
X2036452D03*
Y1174769D03*
X2026452D03*
X2047419Y-29669D03*
Y562531D03*
Y582531D03*
Y1174731D03*
X2057419Y-29669D03*
Y562531D03*
Y582531D03*
Y1174731D03*
X2068539Y582541D03*
X2078539D03*
Y1174741D03*
X2068539D03*
G54D82*
X1900275Y572227D03*
X1910275D03*
X1921395Y1184437D03*
X1931395D03*
X1919766Y1810360D03*
X1929766D03*
X1942395Y572417D03*
X1952395D03*
X1963362Y1184579D03*
X1961856Y1810370D03*
X1973362Y1184579D03*
X1971856Y1810370D03*
X1984482Y572389D03*
X1994482D03*
X2005452Y1184589D03*
X2003823Y1810512D03*
X2015452Y1184589D03*
X2013823Y1810512D03*
X2026452Y572569D03*
X2036452D03*
X2047419Y1184731D03*
X2057419D03*
G54D51*
X676509Y224606D03*
G54D31*
X188155Y1530608D03*
X192879D03*
X197604D03*
X189730Y1533336D03*
X194454D03*
X199178D03*
X202328Y1530608D03*
X207052D03*
X211777D03*
X216501D03*
X203903Y1533336D03*
X208627D03*
X213352D03*
X221226Y1530608D03*
X225950D03*
X230674D03*
X218076Y1533336D03*
X222800D03*
X227525D03*
X235399Y1530608D03*
X240123D03*
X244848D03*
X236974Y1533336D03*
X241698D03*
X246422D03*
X232249D03*
X249572Y1530608D03*
X254297D03*
X259021D03*
X251147Y1533336D03*
X255871D03*
X260596D03*
X317957Y886002D03*
X319807Y889191D03*
Y895569D03*
X317957Y892380D03*
X319807Y908325D03*
X317957Y898758D03*
X319807Y901947D03*
X317957Y905135D03*
Y911513D03*
Y917891D03*
X319807Y921080D03*
X317957Y924269D03*
X319807Y914702D03*
Y927458D03*
X317957Y937025D03*
X319807Y940214D03*
Y933836D03*
X317957Y930647D03*
Y943403D03*
X319807Y946592D03*
X317957Y956159D03*
X319807Y952970D03*
X317957Y949781D03*
Y962537D03*
X319807Y965726D03*
Y959348D03*
X317957Y968915D03*
Y975293D03*
X319807Y978482D03*
Y972104D03*
X317957Y994427D03*
X319807Y997616D03*
X317957Y1000805D03*
X319807Y991238D03*
Y1010372D03*
X317957Y1007183D03*
X319807Y1003994D03*
X320988Y1034434D03*
X319138Y1037623D03*
X320988Y1040812D03*
X319138Y1044001D03*
X320988Y1059946D03*
X319138Y1050379D03*
X320988Y1053568D03*
Y1072702D03*
X319138Y1063135D03*
Y1069513D03*
X320988Y1066324D03*
X319138Y1075891D03*
X320988Y1079080D03*
X319138Y1082269D03*
Y1088647D03*
X320988Y1085458D03*
X319138Y1101403D03*
X320988Y1091836D03*
X319138Y1095025D03*
X320988Y1098214D03*
Y1104592D03*
Y1110970D03*
X319138Y1114159D03*
X320988Y1117348D03*
X319138Y1107781D03*
Y1120537D03*
X320988Y1130103D03*
X319138Y1133293D03*
Y1126915D03*
X320988Y1123726D03*
Y1136481D03*
X319138Y1139670D03*
X320988Y1149237D03*
X319138Y1146048D03*
X320988Y1142859D03*
X319138Y1152426D03*
X316217Y1516970D03*
X320941D03*
X317792Y1519698D03*
X316217Y1530608D03*
X320941D03*
X317792Y1533336D03*
X323508Y889191D03*
X325358Y892380D03*
X323508Y895569D03*
X332760Y886002D03*
X330910Y889191D03*
Y895569D03*
X332760Y892380D03*
X325358Y911513D03*
X323508Y901947D03*
X325358Y905135D03*
X323508Y908325D03*
X325358Y898758D03*
X330910Y908325D03*
X332760Y898758D03*
X330910Y901947D03*
X332760Y905135D03*
Y911513D03*
X323508Y921080D03*
X325358Y924269D03*
X323508Y914702D03*
X325358Y917891D03*
X332760D03*
X330910Y921080D03*
X332760Y924269D03*
X330910Y914702D03*
X323508Y927458D03*
X325358Y930647D03*
X323508Y940214D03*
Y933836D03*
X325358Y937025D03*
X330910Y927458D03*
X332760Y937025D03*
X330910Y940214D03*
Y933836D03*
X332760Y930647D03*
X325358Y943403D03*
X323508Y946592D03*
X325358Y949781D03*
X323508Y952970D03*
X325358Y956159D03*
X332760Y943403D03*
X330910Y946592D03*
X332760Y956159D03*
X330910Y952970D03*
X332760Y949781D03*
X323508Y965726D03*
X325358Y968915D03*
X323508Y959348D03*
X325358Y962537D03*
X332760D03*
X330910Y965726D03*
Y959348D03*
X332760Y968915D03*
X323508Y984860D03*
Y978482D03*
X325358Y981671D03*
X323508Y972104D03*
X325358Y975293D03*
X332760D03*
X330910Y978482D03*
Y972104D03*
X325358Y988049D03*
X323508Y997616D03*
X325358Y1000805D03*
Y994427D03*
X332760D03*
X330910Y997616D03*
X332760Y1000805D03*
X330910Y991238D03*
X323508Y1003994D03*
X325358Y1007183D03*
X330910Y1010372D03*
X332760Y1007183D03*
X330910Y1003994D03*
X326539Y1031245D03*
X324689Y1034434D03*
X326539Y1037623D03*
X324689Y1040812D03*
X332091Y1034434D03*
X333941Y1037623D03*
X332091Y1040812D03*
X333941Y1044001D03*
X326539Y1050379D03*
X324689Y1047190D03*
X332091Y1059946D03*
X333941Y1050379D03*
X332091Y1053568D03*
X326539Y1063135D03*
X324689Y1066324D03*
X326539Y1069513D03*
X324689Y1072702D03*
X332091D03*
X333941Y1063135D03*
Y1069513D03*
X332091Y1066324D03*
X326539Y1075891D03*
X324689Y1079080D03*
X326539Y1082269D03*
X324689Y1085458D03*
X326539Y1088647D03*
X333941Y1075891D03*
X332091Y1079080D03*
X333941Y1082269D03*
Y1088647D03*
X332091Y1085458D03*
X324689Y1104592D03*
X326539Y1095025D03*
X324689Y1098214D03*
X326539Y1101403D03*
X324689Y1091836D03*
X333941Y1101403D03*
X332091Y1091836D03*
X333941Y1095025D03*
X332091Y1098214D03*
Y1104592D03*
X326539Y1114159D03*
X324689Y1117348D03*
X326539Y1107781D03*
X324689Y1110970D03*
X332091D03*
X333941Y1114159D03*
X332091Y1117348D03*
X333941Y1107781D03*
X326539Y1120537D03*
X324689Y1123726D03*
X326539Y1133293D03*
Y1126915D03*
X324689Y1130103D03*
X333941Y1120537D03*
X332091Y1130103D03*
X333941Y1133293D03*
Y1126915D03*
X332091Y1123726D03*
X324689Y1136481D03*
X326539Y1139670D03*
X324689Y1142859D03*
X326539Y1146048D03*
X324689Y1149237D03*
X332091Y1136481D03*
X333941Y1139670D03*
X332091Y1149237D03*
X333941Y1146048D03*
X332091Y1142859D03*
X326539Y1152426D03*
X324689Y1155615D03*
X333941Y1152426D03*
X332091Y1155615D03*
X325666Y1516970D03*
X330390D03*
X335114D03*
X322516Y1519698D03*
X327240D03*
X331965D03*
X325666Y1530608D03*
X330390D03*
X335114D03*
X322516Y1533336D03*
X327240D03*
X331965D03*
X338311Y889191D03*
X336461Y892380D03*
X338311Y895569D03*
X336461Y911513D03*
X338311Y901947D03*
X336461Y905135D03*
X338311Y908325D03*
X336461Y898758D03*
X338311Y921080D03*
X336461Y924269D03*
X338311Y914702D03*
X336461Y917891D03*
X338311Y927458D03*
X336461Y930647D03*
X338311Y940214D03*
Y933836D03*
X336461Y937025D03*
Y943403D03*
X338311Y946592D03*
X336461Y949781D03*
X338311Y952970D03*
X336461Y956159D03*
X338311Y965726D03*
X336461Y968915D03*
X338311Y959348D03*
X336461Y962537D03*
X338311Y984860D03*
Y978482D03*
X336461Y981671D03*
X338311Y972104D03*
X336461Y975293D03*
Y988049D03*
X338311Y997616D03*
X336461Y1000805D03*
Y994427D03*
X338311Y1003994D03*
X336461Y1007183D03*
X337642Y1031245D03*
X339492Y1034434D03*
X337642Y1037623D03*
X339492Y1040812D03*
X337642Y1050379D03*
X339492Y1047190D03*
X337642Y1063135D03*
X339492Y1066324D03*
X337642Y1069513D03*
X339492Y1072702D03*
X337642Y1075891D03*
X339492Y1079080D03*
X337642Y1082269D03*
X339492Y1085458D03*
X337642Y1088647D03*
X339492Y1104592D03*
X337642Y1095025D03*
X339492Y1098214D03*
X337642Y1101403D03*
X339492Y1091836D03*
X337642Y1114159D03*
X339492Y1117348D03*
X337642Y1107781D03*
X339492Y1110970D03*
X337642Y1120537D03*
X339492Y1123726D03*
X337642Y1133293D03*
Y1126915D03*
X339492Y1130103D03*
Y1136481D03*
X337642Y1139670D03*
X339492Y1142859D03*
X337642Y1146048D03*
X339492Y1149237D03*
X337642Y1152426D03*
X339839Y1516970D03*
X344563D03*
X349288D03*
X336689Y1519698D03*
X341414D03*
X346138D03*
X350862D03*
X339839Y1530608D03*
X344563D03*
X349288D03*
X336689Y1533336D03*
X341414D03*
X346138D03*
X350862D03*
X358665Y886002D03*
X364217Y889191D03*
X356815D03*
X362366Y892380D03*
X356815Y895569D03*
X364217D03*
X358665Y892380D03*
X356815Y908325D03*
X362366Y911513D03*
X358665Y898758D03*
X364217Y901947D03*
X356815D03*
X362366Y905135D03*
X358665D03*
X364217Y908325D03*
X358665Y911513D03*
X362366Y898758D03*
X358665Y917891D03*
X364217Y921080D03*
X356815D03*
X362366Y924269D03*
X358665D03*
X356815Y914702D03*
X364217D03*
X362366Y917891D03*
X364217Y927458D03*
X356815D03*
X362366Y930647D03*
X358665Y937025D03*
X364217Y940214D03*
X356815D03*
Y933836D03*
X364217D03*
X358665Y930647D03*
X362366Y937025D03*
Y943403D03*
X358665D03*
X364217Y946592D03*
X356815D03*
X362366Y949781D03*
X358665Y956159D03*
X356815Y952970D03*
X364217D03*
X358665Y949781D03*
X362366Y956159D03*
X358665Y962537D03*
X364217Y965726D03*
X356815D03*
X362366Y968915D03*
X364217Y959348D03*
X356815D03*
X362366Y962537D03*
X358665Y968915D03*
X364217Y984860D03*
X358665Y975293D03*
X364217Y978482D03*
X356815D03*
X362366Y981671D03*
X356815Y972104D03*
X364217D03*
X362366Y975293D03*
Y988049D03*
X358665Y994427D03*
X356815Y997616D03*
X364217D03*
X362366Y1000805D03*
X358665D03*
X356815Y991238D03*
X362366Y994427D03*
X356815Y1010372D03*
X358665Y1007183D03*
X356815Y1003994D03*
X364217D03*
X362366Y1007183D03*
X363547Y1031245D03*
X365398Y1034434D03*
X357996D03*
X359847Y1037623D03*
X363547D03*
X365398Y1040812D03*
X357996D03*
X359847Y1044001D03*
X363547Y1050379D03*
X357996Y1059946D03*
X365398Y1047190D03*
X359847Y1050379D03*
X357996Y1053568D03*
Y1072702D03*
X363547Y1063135D03*
X359847D03*
X365398Y1066324D03*
X363547Y1069513D03*
X359847D03*
X365398Y1072702D03*
X357996Y1066324D03*
X363547Y1075891D03*
X359847D03*
X365398Y1079080D03*
X357996D03*
X363547Y1082269D03*
X359847D03*
X365398Y1085458D03*
X359847Y1088647D03*
X363547D03*
X357996Y1085458D03*
X359847Y1101403D03*
X365398Y1104592D03*
X357996Y1091836D03*
X363547Y1095025D03*
X359847D03*
X365398Y1098214D03*
X357996D03*
X363547Y1101403D03*
X357996Y1104592D03*
X365398Y1091836D03*
X357996Y1110970D03*
X363547Y1114159D03*
X359847D03*
X365398Y1117348D03*
X357996D03*
X359847Y1107781D03*
X363547D03*
X365398Y1110970D03*
X363547Y1120537D03*
X359847D03*
X365398Y1123726D03*
X357996Y1130103D03*
X363547Y1133293D03*
X359847D03*
Y1126915D03*
X363547D03*
X357996Y1123726D03*
X365398Y1130103D03*
Y1136481D03*
X357996D03*
X363547Y1139670D03*
X359847D03*
X365398Y1142859D03*
X357996Y1149237D03*
X359847Y1146048D03*
X363547D03*
X357996Y1142859D03*
X365398Y1149237D03*
X363547Y1152426D03*
X359847D03*
X357996Y1155615D03*
X363461Y1516970D03*
X354012D03*
X358736D03*
X365036Y1519698D03*
X355587D03*
X360311D03*
X363461Y1530608D03*
X354012D03*
X358736D03*
X365036Y1533336D03*
X355587D03*
X360311D03*
X369768Y886002D03*
X375319Y889191D03*
X371618D03*
X377169Y892380D03*
X371618Y895569D03*
X375319D03*
X369768Y892380D03*
X371618Y908325D03*
X377169Y911513D03*
X369768Y898758D03*
X375319Y901947D03*
X371618D03*
X377169Y905135D03*
X369768D03*
X375319Y908325D03*
X369768Y911513D03*
X377169Y898758D03*
X369768Y917891D03*
X375319Y921080D03*
X371618D03*
X377169Y924269D03*
X369768D03*
X371618Y914702D03*
X375319D03*
X377169Y917891D03*
X375319Y927458D03*
X371618D03*
X377169Y930647D03*
X369768Y937025D03*
X375319Y940214D03*
X371618D03*
Y933836D03*
X375319D03*
X369768Y930647D03*
X377169Y937025D03*
Y943403D03*
X369768D03*
X375319Y946592D03*
X371618D03*
X377169Y949781D03*
X369768Y956159D03*
X371618Y952970D03*
X375319D03*
X369768Y949781D03*
X377169Y956159D03*
X369768Y962537D03*
X375319Y965726D03*
X371618D03*
X377169Y968915D03*
X375319Y959348D03*
X371618D03*
X377169Y962537D03*
X369768Y968915D03*
X375319Y984860D03*
X369768Y975293D03*
X375319Y978482D03*
X371618D03*
X377169Y981671D03*
X371618Y972104D03*
X375319D03*
X377169Y975293D03*
Y988049D03*
X369768Y994427D03*
X371618Y997616D03*
X375319D03*
X377169Y1000805D03*
X369768D03*
X371618Y991238D03*
X377169Y994427D03*
X371618Y1010372D03*
X369768Y1007183D03*
X371618Y1003994D03*
X375319D03*
X377169Y1007183D03*
X378351Y1031245D03*
X376500Y1034434D03*
X372799D03*
X370949Y1037623D03*
X378351D03*
X376500Y1040812D03*
X372799D03*
X370949Y1044001D03*
X378351Y1050379D03*
X372799Y1059946D03*
X376500Y1047190D03*
X370949Y1050379D03*
X372799Y1053568D03*
Y1072702D03*
X378351Y1063135D03*
X370949D03*
X376500Y1066324D03*
X378351Y1069513D03*
X370949D03*
X376500Y1072702D03*
X372799Y1066324D03*
X378351Y1075891D03*
X370949D03*
X376500Y1079080D03*
X372799D03*
X378351Y1082269D03*
X370949D03*
X376500Y1085458D03*
X370949Y1088647D03*
X378351D03*
X372799Y1085458D03*
X370949Y1101403D03*
X376500Y1104592D03*
X372799Y1091836D03*
X378351Y1095025D03*
X370949D03*
X376500Y1098214D03*
X372799D03*
X378351Y1101403D03*
X372799Y1104592D03*
X376500Y1091836D03*
X372799Y1110970D03*
X378351Y1114159D03*
X370949D03*
X376500Y1117348D03*
X372799D03*
X370949Y1107781D03*
X378351D03*
X376500Y1110970D03*
X378351Y1120537D03*
X370949D03*
X376500Y1123726D03*
X372799Y1130103D03*
X378351Y1133293D03*
X370949D03*
Y1126915D03*
X378351D03*
X372799Y1123726D03*
X376500Y1130103D03*
Y1136481D03*
X372799D03*
X378351Y1139670D03*
X370949D03*
X376500Y1142859D03*
X372799Y1149237D03*
X370949Y1146048D03*
X378351D03*
X372799Y1142859D03*
X376500Y1149237D03*
X378351Y1152426D03*
X370949D03*
X376500Y1155615D03*
X368185Y1516970D03*
X372910D03*
X377634D03*
X369760Y1519698D03*
X374484D03*
X379209D03*
X368185Y1530608D03*
X372910D03*
X377634D03*
X369760Y1533336D03*
X374484D03*
X379209D03*
X388272Y892380D03*
X384571D03*
X395673D03*
X388272Y911513D03*
Y898758D03*
Y905135D03*
X384571Y911513D03*
Y898758D03*
Y905135D03*
X395673Y898758D03*
Y905135D03*
Y911513D03*
X388272Y924269D03*
Y917891D03*
X384571Y924269D03*
Y917891D03*
X395673Y924269D03*
Y917891D03*
X388272Y930647D03*
X384571D03*
X395673D03*
X384571Y949781D03*
Y943403D03*
Y956159D03*
X395673Y949781D03*
Y943403D03*
Y956159D03*
X388272Y949781D03*
Y943403D03*
Y956159D03*
X395673Y962537D03*
Y968915D03*
X384571Y962537D03*
Y968915D03*
X388272Y962537D03*
Y968915D03*
X395673Y975293D03*
X384571D03*
X388272D03*
X385752Y1088647D03*
Y1082269D03*
X389453Y1088647D03*
Y1082269D03*
X385752Y1095025D03*
X389453D03*
Y1114159D03*
Y1107781D03*
X385752Y1114159D03*
Y1107781D03*
X389453Y1120537D03*
X385752D03*
X389453Y1126915D03*
Y1133293D03*
X385752Y1126915D03*
Y1133293D03*
X389453Y1139670D03*
Y1146048D03*
X385752Y1139670D03*
Y1146048D03*
Y1158804D03*
X382051D03*
X393154D03*
X389453Y1152426D03*
X385752D03*
X382359Y1516970D03*
X387083D03*
X383933Y1519698D03*
X388658D03*
X382359Y1530608D03*
X387083D03*
X383933Y1533336D03*
X388658D03*
X399374Y892380D03*
X410477D03*
X406776D03*
X399374Y898758D03*
Y905135D03*
X410477Y898758D03*
Y905135D03*
X406776Y898758D03*
Y905135D03*
X399374Y911513D03*
X410477D03*
X406776D03*
X399374Y924269D03*
Y917891D03*
X410477D03*
Y924269D03*
X406776Y917891D03*
Y924269D03*
X399374Y930647D03*
X406776Y949781D03*
Y943403D03*
Y956159D03*
X399374Y949781D03*
Y943403D03*
Y956159D03*
X410477Y949781D03*
Y943403D03*
Y956159D03*
X406776Y962537D03*
Y968915D03*
X399374Y962537D03*
Y968915D03*
X410477Y962537D03*
Y968915D03*
X406776Y975293D03*
X399374D03*
X410477D03*
X396855Y1088647D03*
Y1082269D03*
X407957Y1088647D03*
Y1082269D03*
X400555Y1088647D03*
Y1082269D03*
X396855Y1095025D03*
X407957D03*
X400555D03*
Y1114159D03*
Y1107781D03*
X396855Y1114159D03*
Y1107781D03*
X407957Y1114159D03*
X400555Y1120537D03*
Y1126915D03*
X396855Y1120537D03*
Y1126915D03*
X407957Y1120537D03*
Y1126915D03*
X400555Y1133293D03*
X396855D03*
X407957D03*
X400555Y1139670D03*
Y1146048D03*
X396855Y1139670D03*
Y1146048D03*
X407957Y1139670D03*
Y1146048D03*
X396855Y1158804D03*
X407957D03*
X404256D03*
X400555Y1152426D03*
X396855D03*
X407957D03*
X421579Y892380D03*
X417878D03*
X421579Y898758D03*
Y905135D03*
X417878Y898758D03*
Y905135D03*
X421579Y911513D03*
X417878D03*
X421579Y917891D03*
Y924269D03*
X417878Y917891D03*
Y924269D03*
Y937025D03*
X421579D03*
X417878Y943403D03*
Y956159D03*
Y949781D03*
X421579Y943403D03*
Y956159D03*
Y949781D03*
X417878Y962537D03*
Y968915D03*
X421579Y962537D03*
Y968915D03*
X417878Y975293D03*
X421579D03*
X419059Y1082269D03*
Y1088647D03*
X422760Y1082269D03*
X411658Y1088647D03*
Y1082269D03*
X422760Y1088647D03*
X419059Y1095025D03*
Y1101403D03*
X422760Y1095025D03*
Y1101403D03*
X411658Y1095025D03*
X422760Y1114159D03*
X411658D03*
X419059D03*
X422760Y1120537D03*
Y1126915D03*
X411658Y1120537D03*
Y1126915D03*
X419059Y1120537D03*
Y1126915D03*
X422760Y1133293D03*
X411658D03*
X419059D03*
X422760Y1139670D03*
Y1146048D03*
X411658Y1139670D03*
Y1146048D03*
X419059Y1139670D03*
Y1146048D03*
Y1158804D03*
X415358D03*
X411658Y1152426D03*
X422760D03*
X419059D03*
X430831Y895569D03*
X427130D03*
X430831Y901947D03*
Y908325D03*
X427130Y901947D03*
Y908325D03*
X430831Y914702D03*
Y921080D03*
X427130Y914702D03*
Y921080D03*
X430831Y927458D03*
X427130D03*
Y940214D03*
X430831D03*
X427130Y946592D03*
Y952970D03*
X430831Y946592D03*
Y952970D03*
X427130Y959348D03*
Y965726D03*
X430831Y959348D03*
Y965726D03*
X427130Y978482D03*
Y972104D03*
X430831Y978482D03*
Y972104D03*
X428311Y1085458D03*
X432012D03*
X428311Y1098214D03*
Y1091836D03*
X432012Y1098214D03*
Y1091836D03*
Y1117348D03*
Y1110970D03*
X428311Y1117348D03*
Y1110970D03*
X432012Y1123726D03*
X428311D03*
X432012Y1130103D03*
X428311D03*
X432012Y1142859D03*
Y1136481D03*
X428311Y1142859D03*
Y1136481D03*
X449310Y895569D03*
X453011D03*
X449310Y908325D03*
Y901947D03*
X453011Y908325D03*
Y901947D03*
X449310Y921080D03*
Y914702D03*
X453011Y921080D03*
Y914702D03*
X449310Y927458D03*
X453011D03*
X454192Y1085458D03*
X450491D03*
X454192Y1091836D03*
Y1098214D03*
X450491Y1091836D03*
Y1098214D03*
Y1110970D03*
Y1117348D03*
X454192Y1110970D03*
Y1117348D03*
X450491Y1123726D03*
X454192D03*
X450491Y1130103D03*
X454192D03*
X450491Y1136481D03*
Y1142859D03*
X454192Y1136481D03*
Y1142859D03*
X452328Y1516970D03*
X453903Y1519698D03*
X452328Y1530608D03*
X453903Y1533336D03*
X458562Y892380D03*
X469664D03*
X462263D03*
X458562Y905135D03*
Y898758D03*
X469664Y905135D03*
Y898758D03*
X462263Y905135D03*
Y898758D03*
X458562Y911513D03*
X469664D03*
X462263D03*
X458562Y924269D03*
Y917891D03*
X469664Y924269D03*
Y917891D03*
X462263Y924269D03*
Y917891D03*
X463444Y1082269D03*
Y1088647D03*
X459743Y1082269D03*
Y1088647D03*
X463444Y1101403D03*
Y1095025D03*
X459743Y1101403D03*
Y1095025D03*
Y1114159D03*
X463444D03*
X459743Y1126915D03*
Y1120537D03*
X463444Y1126915D03*
Y1120537D03*
X459743Y1133293D03*
X463444D03*
X459743Y1146048D03*
Y1139670D03*
X463444Y1146048D03*
Y1139670D03*
X457052Y1516970D03*
X461777D03*
X466501D03*
X458627Y1519698D03*
X463351D03*
X468076D03*
X457052Y1530608D03*
X461777D03*
X466501D03*
X458627Y1533336D03*
X463351D03*
X468076D03*
X480767Y892380D03*
X484467D03*
X473365D03*
X480767Y898758D03*
Y905135D03*
X484467Y898758D03*
X473365Y905135D03*
Y898758D03*
X484467Y905135D03*
X480767Y911513D03*
X484467D03*
X473365D03*
X480767Y917891D03*
Y924269D03*
X484467Y917891D03*
Y924269D03*
X473365D03*
Y917891D03*
X480767Y930647D03*
X484467D03*
X474546Y1082269D03*
Y1088647D03*
X481948Y1082269D03*
Y1088647D03*
X470845Y1082269D03*
Y1088647D03*
X474546Y1095025D03*
X481948D03*
X470845D03*
X481948Y1114159D03*
X470845D03*
X481948Y1107781D03*
X474546Y1114159D03*
X481948Y1126915D03*
Y1120537D03*
X470845Y1126915D03*
Y1120537D03*
X474546Y1126915D03*
Y1120537D03*
X470845Y1133293D03*
X481948D03*
X474546D03*
X481948Y1146048D03*
Y1139670D03*
X470845Y1146048D03*
Y1139670D03*
X474546Y1146048D03*
Y1139670D03*
X471225Y1516970D03*
X475950D03*
X480674D03*
X472800Y1519698D03*
X477525D03*
X482249D03*
X471225Y1530608D03*
X475950D03*
X480674D03*
X472800Y1533336D03*
X477525D03*
X482249D03*
X491869Y892380D03*
X495570D03*
X491869Y905135D03*
Y898758D03*
Y911513D03*
X495570Y905135D03*
Y898758D03*
Y911513D03*
X491869Y917891D03*
Y924269D03*
X495570Y917891D03*
Y924269D03*
X491869Y930647D03*
X495570D03*
X485649Y1082269D03*
Y1088647D03*
X496751Y1082269D03*
Y1088647D03*
X493050Y1082269D03*
Y1088647D03*
X485649Y1095025D03*
X496751D03*
X493050D03*
Y1107781D03*
Y1114159D03*
X485649D03*
X496751Y1107781D03*
Y1114159D03*
X485649Y1107781D03*
X493050Y1120537D03*
X485649Y1126915D03*
Y1120537D03*
X496751D03*
X493050Y1133293D03*
Y1126915D03*
X496751Y1133293D03*
Y1126915D03*
X485649Y1133293D03*
X493050Y1146048D03*
Y1139670D03*
X485649Y1146048D03*
Y1139670D03*
X496751Y1146048D03*
Y1139670D03*
X499572Y1516970D03*
X485399D03*
X490123D03*
X494847D03*
X486973Y1519698D03*
X491698D03*
X496422D03*
X499572Y1530608D03*
X485399D03*
X490123D03*
X494847D03*
X486973Y1533336D03*
X491698D03*
X496422D03*
X510373Y886002D03*
X504822Y889191D03*
X508523D03*
X502971Y892380D03*
X508523Y895569D03*
X504822D03*
X510373Y892380D03*
X508523Y908325D03*
X502971Y911513D03*
X510373Y898758D03*
X504822Y901947D03*
X508523D03*
X502971Y905135D03*
X510373D03*
X504822Y908325D03*
X510373Y911513D03*
X502971Y898758D03*
X510373Y917891D03*
X504822Y921080D03*
X508523D03*
X502971Y924269D03*
X510373D03*
X508523Y914702D03*
X504822D03*
X502971Y917891D03*
X504822Y927458D03*
X508523D03*
X502971Y930647D03*
X510373Y937025D03*
X504822Y940214D03*
X508523D03*
Y933836D03*
X504822D03*
X510373Y930647D03*
X502971Y937025D03*
Y943403D03*
X510373D03*
X504822Y946592D03*
X508523D03*
X502971Y949781D03*
X510373Y956159D03*
X508523Y952970D03*
X504822D03*
X510373Y949781D03*
X502971Y956159D03*
X510373Y962537D03*
X504822Y965726D03*
X508523D03*
X502971Y968915D03*
X504822Y959348D03*
X508523D03*
X502971Y962537D03*
X510373Y968915D03*
X504822Y984860D03*
X510373Y975293D03*
X504822Y978482D03*
X508523D03*
X502971Y981671D03*
X508523Y972104D03*
X504822D03*
X502971Y975293D03*
Y988049D03*
X510373Y994427D03*
X508523Y997616D03*
X504822D03*
X502971Y1000805D03*
X510373D03*
Y988049D03*
X504822Y991238D03*
X508523Y1010372D03*
X510373Y1007183D03*
X508523Y1003994D03*
X504822D03*
X502971Y1007183D03*
X504153Y1031245D03*
X506003Y1034434D03*
X509704D03*
X511554Y1037623D03*
X504153D03*
X506003Y1040812D03*
X509704D03*
X504153Y1044001D03*
Y1050379D03*
X509704Y1059946D03*
X506003Y1047190D03*
X511554Y1050379D03*
X509704Y1053568D03*
Y1072702D03*
X504153Y1063135D03*
X511554D03*
X506003Y1066324D03*
X504153Y1069513D03*
X511554D03*
X506003Y1072702D03*
X509704Y1066324D03*
X504153Y1075891D03*
X511554D03*
X506003Y1079080D03*
X509704D03*
X504153Y1082269D03*
X511554D03*
X506003Y1085458D03*
X511554Y1088647D03*
X504153D03*
X509704Y1085458D03*
X511554Y1101403D03*
X506003Y1104592D03*
X509704Y1091836D03*
X504153Y1095025D03*
X511554D03*
X506003Y1098214D03*
X509704D03*
X504153Y1101403D03*
X509704Y1104592D03*
X506003Y1091836D03*
X509704Y1110970D03*
X504153Y1114159D03*
X511554D03*
X506003Y1117348D03*
X509704D03*
X511554Y1107781D03*
X504153D03*
X506003Y1110970D03*
X504153Y1120537D03*
X511554D03*
X506003Y1123726D03*
X509704Y1130103D03*
X504153Y1133293D03*
X511554D03*
Y1126915D03*
X504153D03*
X509704Y1123726D03*
X506003Y1130103D03*
Y1136481D03*
X509704D03*
X504153Y1139670D03*
X511554D03*
X506003Y1142859D03*
X509704Y1149237D03*
X511554Y1146048D03*
X504153D03*
X509704Y1142859D03*
X506003Y1149237D03*
X504153Y1152426D03*
X511554D03*
X506003Y1155615D03*
X504296Y1516970D03*
X509021D03*
X513745D03*
X501147Y1519698D03*
X505871D03*
X510595D03*
X504296Y1530608D03*
X509021D03*
X513745D03*
X501147Y1533336D03*
X505871D03*
X510595D03*
X521475Y886002D03*
X515924Y889191D03*
X523326D03*
X517775Y892380D03*
X523326Y895569D03*
X515924D03*
X521475Y892380D03*
X523326Y908325D03*
X517775Y911513D03*
X521475Y898758D03*
X515924Y901947D03*
X523326D03*
X517775Y905135D03*
X521475D03*
X515924Y908325D03*
X521475Y911513D03*
X517775Y898758D03*
X521475Y917891D03*
X515924Y921080D03*
X523326D03*
X517775Y924269D03*
X521475D03*
X523326Y914702D03*
X515924D03*
X517775Y917891D03*
X515924Y927458D03*
X523326D03*
X517775Y930647D03*
X521475Y937025D03*
X515924Y940214D03*
X523326D03*
Y933836D03*
X515924D03*
X521475Y930647D03*
X517775Y937025D03*
Y943403D03*
X521475D03*
X515924Y946592D03*
X523326D03*
X517775Y949781D03*
X521475Y956159D03*
X523326Y952970D03*
X515924D03*
X521475Y949781D03*
X517775Y956159D03*
X521475Y962537D03*
X515924Y965726D03*
X523326D03*
X517775Y968915D03*
X515924Y959348D03*
X523326D03*
X517775Y962537D03*
X521475Y968915D03*
X515924Y984860D03*
X521475Y975293D03*
X515924Y978482D03*
X523326D03*
X517775Y981671D03*
X523326Y972104D03*
X515924D03*
X517775Y975293D03*
Y988049D03*
X521475Y994427D03*
X523326Y997616D03*
X515924D03*
X517775Y1000805D03*
X521475D03*
Y988049D03*
X515924Y991238D03*
X523326Y1010372D03*
X521475Y1007183D03*
X523326Y1003994D03*
X515924D03*
X517775Y1007183D03*
X518956Y1031245D03*
X517105Y1034434D03*
X524507D03*
X522657Y1037623D03*
X518956D03*
X517105Y1040812D03*
X524507D03*
X518956Y1044001D03*
Y1050379D03*
X524507Y1059946D03*
X517105Y1047190D03*
X522657Y1050379D03*
X524507Y1053568D03*
Y1072702D03*
X518956Y1063135D03*
X522657D03*
X517105Y1066324D03*
X518956Y1069513D03*
X522657D03*
X517105Y1072702D03*
X524507Y1066324D03*
X518956Y1075891D03*
X522657D03*
X517105Y1079080D03*
X524507D03*
X518956Y1082269D03*
X522657D03*
X517105Y1085458D03*
X522657Y1088647D03*
X518956D03*
X524507Y1085458D03*
X522657Y1101403D03*
X517105Y1104592D03*
X524507Y1091836D03*
X518956Y1095025D03*
X522657D03*
X517105Y1098214D03*
X524507D03*
X518956Y1101403D03*
X524507Y1104592D03*
X517105Y1091836D03*
X524507Y1110970D03*
X518956Y1114159D03*
X522657D03*
X517105Y1117348D03*
X524507D03*
X522657Y1107781D03*
X518956D03*
X517105Y1110970D03*
X518956Y1120537D03*
X522657D03*
X517105Y1123726D03*
X524507Y1130103D03*
X518956Y1133293D03*
X522657D03*
Y1126915D03*
X518956D03*
X524507Y1123726D03*
X517105Y1130103D03*
Y1136481D03*
X524507D03*
X518956Y1139670D03*
X522657D03*
X517105Y1142859D03*
X524507Y1149237D03*
X522657Y1146048D03*
X518956D03*
X524507Y1142859D03*
X517105Y1149237D03*
X518956Y1152426D03*
X522657D03*
X524507Y1155615D03*
X518470Y1516970D03*
X523194D03*
X515320Y1519698D03*
X520044D03*
X524769D03*
X518470Y1530608D03*
X523194D03*
X515320Y1533336D03*
X520044D03*
X524769D03*
X541830Y889191D03*
X543680Y892380D03*
X541830Y895569D03*
X543680Y911513D03*
X541830Y901947D03*
X543680Y905135D03*
X541830Y908325D03*
X543680Y898758D03*
X541830Y921080D03*
X543680Y924269D03*
X541830Y914702D03*
X543680Y917891D03*
X541830Y927458D03*
X543680Y930647D03*
X541830Y940214D03*
Y933836D03*
X543680Y937025D03*
Y943403D03*
X541830Y946592D03*
X543680Y949781D03*
X541830Y952970D03*
X543680Y956159D03*
X541830Y965726D03*
X543680Y968915D03*
X541830Y959348D03*
X543680Y962537D03*
X541830Y984860D03*
Y978482D03*
X543680Y981671D03*
X541830Y972104D03*
X543680Y975293D03*
Y988049D03*
X541830Y997616D03*
X543680Y1000805D03*
X541830Y991238D03*
Y1003994D03*
X543680Y1007183D03*
X543011Y1034434D03*
Y1040812D03*
Y1047190D03*
Y1066324D03*
Y1072702D03*
Y1079080D03*
Y1085458D03*
Y1104592D03*
Y1098214D03*
Y1091836D03*
Y1117348D03*
Y1110970D03*
Y1123726D03*
Y1130103D03*
Y1136481D03*
Y1142859D03*
Y1149237D03*
X556633Y889191D03*
X554783Y892380D03*
X556633Y895569D03*
X547381Y886002D03*
X549231Y889191D03*
Y895569D03*
X547381Y892380D03*
X554783Y911513D03*
X556633Y901947D03*
X554783Y905135D03*
X556633Y908325D03*
X554783Y898758D03*
X549231Y908325D03*
X547381Y898758D03*
X549231Y901947D03*
X547381Y905135D03*
Y911513D03*
X556633Y921080D03*
X554783Y924269D03*
X556633Y914702D03*
X554783Y917891D03*
X547381D03*
X549231Y921080D03*
X547381Y924269D03*
X549231Y914702D03*
X556633Y927458D03*
X554783Y930647D03*
X556633Y940214D03*
Y933836D03*
X554783Y937025D03*
X549231Y927458D03*
X547381Y937025D03*
X549231Y940214D03*
Y933836D03*
X547381Y930647D03*
X554783Y943403D03*
X556633Y946592D03*
X554783Y949781D03*
X556633Y952970D03*
X554783Y956159D03*
X547381Y943403D03*
X549231Y946592D03*
X547381Y956159D03*
X549231Y952970D03*
X547381Y949781D03*
X556633Y965726D03*
X554783Y968915D03*
X556633Y959348D03*
X554783Y962537D03*
X547381D03*
X549231Y965726D03*
Y959348D03*
X547381Y968915D03*
X556633Y984860D03*
Y978482D03*
X554783Y981671D03*
X556633Y972104D03*
X554783Y975293D03*
X547381D03*
X549231Y978482D03*
Y972104D03*
X554783Y988049D03*
X556633Y997616D03*
X554783Y1000805D03*
X556633Y991238D03*
X547381Y994427D03*
X549231Y997616D03*
X547381Y1000805D03*
Y988049D03*
X556633Y1003994D03*
X554783Y1007183D03*
X549231Y1010372D03*
X547381Y1007183D03*
X549231Y1003994D03*
X555964Y1031245D03*
X557814Y1034434D03*
X555964Y1037623D03*
X557814Y1040812D03*
X555964Y1044001D03*
X544861Y1031245D03*
X550412Y1034434D03*
X548562Y1037623D03*
X544861D03*
X550412Y1040812D03*
X544861Y1044001D03*
X555964Y1050379D03*
X557814Y1047190D03*
X544861Y1050379D03*
X550412Y1059946D03*
X548562Y1050379D03*
X550412Y1053568D03*
X555964Y1063135D03*
X557814Y1066324D03*
X555964Y1069513D03*
X557814Y1072702D03*
X550412D03*
X544861Y1063135D03*
X548562D03*
X544861Y1069513D03*
X548562D03*
X550412Y1066324D03*
X555964Y1075891D03*
X557814Y1079080D03*
X555964Y1082269D03*
X557814Y1085458D03*
X555964Y1088647D03*
X544861Y1075891D03*
X548562D03*
X550412Y1079080D03*
X544861Y1082269D03*
X548562D03*
Y1088647D03*
X544861D03*
X550412Y1085458D03*
X557814Y1104592D03*
X555964Y1095025D03*
X557814Y1098214D03*
X555964Y1101403D03*
X557814Y1091836D03*
X548562Y1101403D03*
X550412Y1091836D03*
X544861Y1095025D03*
X548562D03*
X550412Y1098214D03*
X544861Y1101403D03*
X550412Y1104592D03*
X555964Y1114159D03*
X557814Y1117348D03*
X555964Y1107781D03*
X557814Y1110970D03*
X550412D03*
X544861Y1114159D03*
X548562D03*
X550412Y1117348D03*
X548562Y1107781D03*
X544861D03*
X555964Y1120537D03*
X557814Y1123726D03*
X555964Y1133293D03*
Y1126915D03*
X557814Y1130103D03*
X544861Y1120537D03*
X548562D03*
X550412Y1130103D03*
X544861Y1133293D03*
X548562D03*
Y1126915D03*
X544861D03*
X550412Y1123726D03*
X557814Y1136481D03*
X555964Y1139670D03*
X557814Y1142859D03*
X555964Y1146048D03*
X557814Y1149237D03*
X550412Y1136481D03*
X544861Y1139670D03*
X548562D03*
X550412Y1149237D03*
X548562Y1146048D03*
X544861D03*
X550412Y1142859D03*
X555964Y1152426D03*
X557814Y1155615D03*
X544861Y1152426D03*
X548562D03*
X550412Y1155615D03*
X562184Y886002D03*
X560334Y889191D03*
Y895569D03*
X562184Y892380D03*
X560334Y908325D03*
X562184Y898758D03*
X560334Y901947D03*
X562184Y905135D03*
Y911513D03*
Y917891D03*
X560334Y921080D03*
X562184Y924269D03*
X560334Y914702D03*
Y927458D03*
X562184Y937025D03*
X560334Y940214D03*
Y933836D03*
X562184Y930647D03*
Y943403D03*
X560334Y946592D03*
X562184Y956159D03*
X560334Y952970D03*
X562184Y949781D03*
Y962537D03*
X560334Y965726D03*
Y959348D03*
X562184Y968915D03*
Y975293D03*
X560334Y978482D03*
Y972104D03*
X562184Y994427D03*
X560334Y997616D03*
X562184Y1000805D03*
Y988049D03*
X560334Y1010372D03*
X562184Y1007183D03*
X560334Y1003994D03*
X561515Y1034434D03*
X563365Y1037623D03*
X561515Y1040812D03*
Y1059946D03*
X563365Y1050379D03*
X561515Y1053568D03*
Y1072702D03*
X563365Y1063135D03*
Y1069513D03*
X561515Y1066324D03*
X563365Y1075891D03*
X561515Y1079080D03*
X563365Y1082269D03*
Y1088647D03*
X561515Y1085458D03*
X563365Y1101403D03*
X561515Y1091836D03*
X563365Y1095025D03*
X561515Y1098214D03*
Y1104592D03*
Y1110970D03*
X563365Y1114159D03*
X561515Y1117348D03*
X563365Y1107781D03*
Y1120537D03*
X561515Y1130103D03*
X563365Y1133293D03*
Y1126915D03*
X561515Y1123726D03*
Y1136481D03*
X563365Y1139670D03*
X561515Y1149237D03*
X563365Y1146048D03*
X561515Y1142859D03*
X563365Y1152426D03*
X580390Y1516970D03*
X585114D03*
X581965Y1519698D03*
X586689D03*
X580390Y1530608D03*
X585114D03*
X581965Y1533336D03*
X586689D03*
X589839Y1516970D03*
X594563D03*
X599287D03*
X604012D03*
X591413Y1519698D03*
X596138D03*
X600862D03*
X589839Y1530608D03*
X594563D03*
X599287D03*
X604012D03*
X591413Y1533336D03*
X596138D03*
X600862D03*
X608736Y1516970D03*
X613461D03*
X618185D03*
X605587Y1519698D03*
X610311D03*
X615035D03*
X608736Y1530608D03*
X613461D03*
X618185D03*
X605587Y1533336D03*
X610311D03*
X615035D03*
X627634Y1516970D03*
X632358D03*
X622909D03*
X629209Y1519698D03*
X633933D03*
X619760D03*
X624484D03*
X627634Y1530608D03*
X632358D03*
X622909D03*
X629209Y1533336D03*
X633933D03*
X619760D03*
X624484D03*
X637083Y1516970D03*
X641807D03*
X646532D03*
X638657Y1519698D03*
X643382D03*
X648106D03*
X637083Y1530608D03*
X641807D03*
X646532D03*
X638657Y1533336D03*
X643382D03*
X648106D03*
X651256Y1516970D03*
X652831Y1519698D03*
X651256Y1530608D03*
X652831Y1533336D03*
X1196028Y1563608D03*
X1197603Y1566336D03*
X1200752Y1563608D03*
X1205477D03*
X1210201D03*
X1214925D03*
X1202327Y1566336D03*
X1207051D03*
X1211776D03*
X1219650Y1563608D03*
X1224374D03*
X1229099D03*
X1216500Y1566336D03*
X1221225D03*
X1225949D03*
X1243272Y1563608D03*
X1233823D03*
X1238547D03*
X1244847Y1566336D03*
X1230673D03*
X1235398D03*
X1240122D03*
X1247996Y1563608D03*
X1252721D03*
X1257445D03*
X1249571Y1566336D03*
X1254295D03*
X1259020D03*
X1262170Y1563608D03*
X1266894D03*
X1263744Y1566336D03*
X1268469D03*
X1294099Y886001D03*
X1299650Y889190D03*
X1295949D03*
X1301500Y892379D03*
X1295949Y895568D03*
X1299650D03*
X1294099Y892379D03*
X1295949Y908324D03*
X1301500Y911512D03*
X1294099Y898757D03*
X1299650Y901946D03*
X1295949D03*
X1301500Y905134D03*
X1294099D03*
X1299650Y908324D03*
X1294099Y911512D03*
X1301500Y898757D03*
X1294099Y917890D03*
X1299650Y921079D03*
X1295949D03*
X1301500Y924268D03*
X1294099D03*
X1295949Y914701D03*
X1299650D03*
X1301500Y917890D03*
X1299650Y927457D03*
X1295949D03*
X1301500Y930646D03*
X1294099Y937024D03*
X1299650Y940213D03*
X1295949D03*
Y933835D03*
X1299650D03*
X1294099Y930646D03*
X1301500Y937024D03*
Y943402D03*
X1294099D03*
X1299650Y946591D03*
X1295949D03*
X1301500Y949780D03*
X1294099Y956158D03*
X1295949Y952969D03*
X1299650D03*
X1294099Y949780D03*
X1301500Y956158D03*
X1294099Y962536D03*
X1299650Y965725D03*
X1295949D03*
X1301500Y968914D03*
X1299650Y959347D03*
X1295949D03*
X1301500Y962536D03*
X1294099Y968914D03*
X1299650Y984859D03*
X1294099Y975292D03*
X1299650Y978481D03*
X1295949D03*
X1301500Y981670D03*
X1295949Y972103D03*
X1299650D03*
X1301500Y975292D03*
Y988048D03*
X1294099Y994426D03*
X1295949Y997615D03*
X1299650D03*
X1301500Y1000804D03*
X1294099D03*
X1295949Y991237D03*
X1301500Y994426D03*
X1295949Y1010371D03*
X1294099Y1007182D03*
X1295949Y1003993D03*
X1299650D03*
X1301500Y1007182D03*
X1302681Y1031244D03*
X1300831Y1034433D03*
X1297130D03*
X1295280Y1037622D03*
X1302681D03*
X1300831Y1040811D03*
X1297130D03*
X1295280Y1044000D03*
X1302681Y1050378D03*
X1297130Y1059945D03*
X1300831Y1047189D03*
X1295280Y1050378D03*
X1297130Y1053567D03*
Y1072701D03*
X1302681Y1063134D03*
X1295280D03*
X1300831Y1066323D03*
X1302681Y1069512D03*
X1295280D03*
X1300831Y1072701D03*
X1297130Y1066323D03*
X1302681Y1075890D03*
X1295280D03*
X1300831Y1079079D03*
X1297130D03*
X1302681Y1082268D03*
X1295280D03*
X1300831Y1085457D03*
X1295280Y1088646D03*
X1302681D03*
X1297130Y1085457D03*
X1295280Y1101402D03*
X1300831Y1104591D03*
X1297130Y1091835D03*
X1302681Y1095024D03*
X1295280D03*
X1300831Y1098213D03*
X1297130D03*
X1302681Y1101402D03*
X1297130Y1104591D03*
X1300831Y1091835D03*
X1297130Y1110969D03*
X1302681Y1114158D03*
X1295280D03*
X1300831Y1117347D03*
X1297130D03*
X1295280Y1107780D03*
X1302681D03*
X1300831Y1110969D03*
X1302681Y1120536D03*
X1295280D03*
X1300831Y1123725D03*
X1297130Y1130102D03*
X1302681Y1133292D03*
X1295280D03*
Y1126914D03*
X1302681D03*
X1297130Y1123725D03*
X1300831Y1130102D03*
Y1136480D03*
X1297130D03*
X1302681Y1139669D03*
X1295280D03*
X1300831Y1142858D03*
X1297130Y1149236D03*
X1295280Y1146047D03*
X1302681D03*
X1297130Y1142858D03*
X1300831Y1149236D03*
X1302681Y1152425D03*
X1295280D03*
X1300831Y1155614D03*
X1308902Y886001D03*
X1314453Y889190D03*
X1307052D03*
X1312603Y892379D03*
X1307052Y895568D03*
X1314453D03*
X1308902Y892379D03*
X1307052Y908324D03*
X1312603Y911512D03*
X1308902Y898757D03*
X1314453Y901946D03*
X1307052D03*
X1312603Y905134D03*
X1308902D03*
X1314453Y908324D03*
X1308902Y911512D03*
X1312603Y898757D03*
X1308902Y917890D03*
X1314453Y921079D03*
X1307052D03*
X1312603Y924268D03*
X1308902D03*
X1307052Y914701D03*
X1314453D03*
X1312603Y917890D03*
X1314453Y927457D03*
X1307052D03*
X1312603Y930646D03*
X1308902Y937024D03*
X1314453Y940213D03*
X1307052D03*
Y933835D03*
X1314453D03*
X1308902Y930646D03*
X1312603Y937024D03*
Y943402D03*
X1308902D03*
X1314453Y946591D03*
X1307052D03*
X1312603Y949780D03*
X1308902Y956158D03*
X1307052Y952969D03*
X1314453D03*
X1308902Y949780D03*
X1312603Y956158D03*
X1308902Y962536D03*
X1314453Y965725D03*
X1307052D03*
X1312603Y968914D03*
X1314453Y959347D03*
X1307052D03*
X1312603Y962536D03*
X1308902Y968914D03*
X1314453Y984859D03*
X1308902Y975292D03*
X1314453Y978481D03*
X1307052D03*
X1312603Y981670D03*
X1307052Y972103D03*
X1314453D03*
X1312603Y975292D03*
Y988048D03*
X1308902Y994426D03*
X1307052Y997615D03*
X1314453D03*
X1312603Y1000804D03*
X1308902D03*
X1307052Y991237D03*
X1312603Y994426D03*
X1307052Y1010371D03*
X1308902Y1007182D03*
X1307052Y1003993D03*
X1314453D03*
X1312603Y1007182D03*
X1313784Y1031244D03*
X1315634Y1034433D03*
X1308233D03*
X1310083Y1037622D03*
X1313784D03*
X1315634Y1040811D03*
X1308233D03*
X1310083Y1044000D03*
X1313784Y1050378D03*
X1308233Y1059945D03*
X1315634Y1047189D03*
X1310083Y1050378D03*
X1308233Y1053567D03*
Y1072701D03*
X1313784Y1063134D03*
X1310083D03*
X1315634Y1066323D03*
X1313784Y1069512D03*
X1310083D03*
X1315634Y1072701D03*
X1308233Y1066323D03*
X1313784Y1075890D03*
X1310083D03*
X1315634Y1079079D03*
X1308233D03*
X1313784Y1082268D03*
X1310083D03*
X1315634Y1085457D03*
X1310083Y1088646D03*
X1313784D03*
X1308233Y1085457D03*
X1310083Y1101402D03*
X1315634Y1104591D03*
X1308233Y1091835D03*
X1313784Y1095024D03*
X1310083D03*
X1315634Y1098213D03*
X1308233D03*
X1313784Y1101402D03*
X1308233Y1104591D03*
X1315634Y1091835D03*
X1308233Y1110969D03*
X1313784Y1114158D03*
X1310083D03*
X1315634Y1117347D03*
X1308233D03*
X1310083Y1107780D03*
X1313784D03*
X1315634Y1110969D03*
X1313784Y1120536D03*
X1310083D03*
X1315634Y1123725D03*
X1308233Y1130102D03*
X1313784Y1133292D03*
X1310083D03*
Y1126914D03*
X1313784D03*
X1308233Y1123725D03*
X1315634Y1130102D03*
Y1136480D03*
X1308233D03*
X1313784Y1139669D03*
X1310083D03*
X1315634Y1142858D03*
X1308233Y1149236D03*
X1310083Y1146047D03*
X1313784D03*
X1308233Y1142858D03*
X1315634Y1149236D03*
X1313784Y1152425D03*
X1310083D03*
X1308233Y1155614D03*
X1334807Y886001D03*
X1332957Y889190D03*
Y895568D03*
X1334807Y892379D03*
X1332957Y908324D03*
X1334807Y898757D03*
X1332957Y901946D03*
X1334807Y905134D03*
Y911512D03*
Y917890D03*
X1332957Y921079D03*
X1334807Y924268D03*
X1332957Y914701D03*
Y927457D03*
X1334807Y937024D03*
X1332957Y940213D03*
Y933835D03*
X1334807Y930646D03*
Y943402D03*
X1332957Y946591D03*
X1334807Y956158D03*
X1332957Y952969D03*
X1334807Y949780D03*
Y962536D03*
X1332957Y965725D03*
Y959347D03*
X1334807Y968914D03*
Y975292D03*
X1332957Y978481D03*
Y972103D03*
X1334807Y994426D03*
X1332957Y997615D03*
X1334807Y1000804D03*
X1332957Y991237D03*
Y1010371D03*
X1334807Y1007182D03*
X1332957Y1003993D03*
X1334138Y1034433D03*
Y1040811D03*
Y1059945D03*
Y1053567D03*
Y1072701D03*
Y1066323D03*
Y1079079D03*
Y1085457D03*
Y1091835D03*
Y1098213D03*
Y1104591D03*
Y1110969D03*
Y1117347D03*
Y1130102D03*
Y1123725D03*
Y1136480D03*
Y1149236D03*
Y1142858D03*
Y1155614D03*
X1324090Y1549970D03*
X1328814D03*
X1333539D03*
X1325665Y1552698D03*
X1330389D03*
X1324090Y1563608D03*
X1328814D03*
X1333539D03*
X1325665Y1566336D03*
X1330389D03*
X1345910Y886001D03*
X1347760Y889190D03*
Y895568D03*
X1345910Y892379D03*
X1340359Y889190D03*
X1338508Y892379D03*
X1340359Y895568D03*
X1347760Y908324D03*
X1345910Y898757D03*
X1347760Y901946D03*
X1345910Y905134D03*
Y911512D03*
X1338508D03*
X1340359Y901946D03*
X1338508Y905134D03*
X1340359Y908324D03*
X1338508Y898757D03*
X1345910Y917890D03*
X1347760Y921079D03*
X1345910Y924268D03*
X1347760Y914701D03*
X1340359Y921079D03*
X1338508Y924268D03*
X1340359Y914701D03*
X1338508Y917890D03*
X1347760Y927457D03*
X1345910Y937024D03*
X1347760Y940213D03*
Y933835D03*
X1345910Y930646D03*
X1340359Y927457D03*
X1338508Y930646D03*
X1340359Y940213D03*
Y933835D03*
X1338508Y937024D03*
X1345910Y943402D03*
X1347760Y946591D03*
X1345910Y956158D03*
X1347760Y952969D03*
X1345910Y949780D03*
X1338508Y943402D03*
X1340359Y946591D03*
X1338508Y949780D03*
X1340359Y952969D03*
X1338508Y956158D03*
X1345910Y962536D03*
X1347760Y965725D03*
Y959347D03*
X1345910Y968914D03*
X1340359Y965725D03*
X1338508Y968914D03*
X1340359Y959347D03*
X1338508Y962536D03*
X1345910Y975292D03*
X1347760Y978481D03*
Y972103D03*
X1340359Y984859D03*
Y978481D03*
X1338508Y981670D03*
X1340359Y972103D03*
X1338508Y975292D03*
X1345910Y994426D03*
X1347760Y997615D03*
X1345910Y1000804D03*
X1347760Y991237D03*
X1338508Y988048D03*
X1340359Y997615D03*
X1338508Y1000804D03*
Y994426D03*
X1347760Y1010371D03*
X1345910Y1007182D03*
X1347760Y1003993D03*
X1340359D03*
X1338508Y1007182D03*
X1348941Y1034433D03*
X1347091Y1037622D03*
X1348941Y1040811D03*
X1347091Y1044000D03*
X1339689Y1031244D03*
X1341540Y1034433D03*
X1335989Y1037622D03*
X1339689D03*
X1341540Y1040811D03*
X1335989Y1044000D03*
X1348941Y1059945D03*
X1347091Y1050378D03*
X1348941Y1053567D03*
X1339689Y1050378D03*
X1341540Y1047189D03*
X1335989Y1050378D03*
X1348941Y1072701D03*
X1347091Y1063134D03*
Y1069512D03*
X1348941Y1066323D03*
X1339689Y1063134D03*
X1335989D03*
X1341540Y1066323D03*
X1339689Y1069512D03*
X1335989D03*
X1341540Y1072701D03*
X1347091Y1075890D03*
X1348941Y1079079D03*
X1347091Y1082268D03*
Y1088646D03*
X1348941Y1085457D03*
X1339689Y1075890D03*
X1335989D03*
X1341540Y1079079D03*
X1339689Y1082268D03*
X1335989D03*
X1341540Y1085457D03*
X1335989Y1088646D03*
X1339689D03*
X1347091Y1101402D03*
X1348941Y1091835D03*
X1347091Y1095024D03*
X1348941Y1098213D03*
Y1104591D03*
X1335989Y1101402D03*
X1341540Y1104591D03*
X1339689Y1095024D03*
X1335989D03*
X1341540Y1098213D03*
X1339689Y1101402D03*
X1341540Y1091835D03*
X1348941Y1110969D03*
X1347091Y1114158D03*
X1348941Y1117347D03*
X1347091Y1107780D03*
X1339689Y1114158D03*
X1335989D03*
X1341540Y1117347D03*
X1335989Y1107780D03*
X1339689D03*
X1341540Y1110969D03*
X1347091Y1120536D03*
X1348941Y1130102D03*
X1347091Y1133292D03*
Y1126914D03*
X1348941Y1123725D03*
X1339689Y1120536D03*
X1335989D03*
X1341540Y1123725D03*
X1339689Y1133292D03*
X1335989D03*
Y1126914D03*
X1339689D03*
X1341540Y1130102D03*
X1348941Y1136480D03*
X1347091Y1139669D03*
X1348941Y1149236D03*
X1347091Y1146047D03*
X1348941Y1142858D03*
X1341540Y1136480D03*
X1339689Y1139669D03*
X1335989D03*
X1341540Y1142858D03*
X1335989Y1146047D03*
X1339689D03*
X1341540Y1149236D03*
X1347091Y1152425D03*
X1339689D03*
X1335989D03*
X1338263Y1549970D03*
X1342987D03*
X1347712D03*
X1335113Y1552698D03*
X1339838D03*
X1344562D03*
X1349287D03*
X1338263Y1563608D03*
X1342987D03*
X1347712D03*
X1335113Y1566336D03*
X1339838D03*
X1344562D03*
X1349287D03*
X1364414Y892379D03*
X1360713D03*
X1351461Y889190D03*
X1353311Y892379D03*
X1351461Y895568D03*
X1364414Y905134D03*
Y898757D03*
Y911512D03*
X1360713Y905134D03*
Y898757D03*
Y911512D03*
X1353311D03*
X1351461Y901946D03*
X1353311Y905134D03*
X1351461Y908324D03*
X1353311Y898757D03*
X1364414Y917890D03*
Y924268D03*
X1360713Y917890D03*
Y924268D03*
X1351461Y921079D03*
X1353311Y924268D03*
X1351461Y914701D03*
X1353311Y917890D03*
X1364414Y930646D03*
X1360713D03*
X1351461Y927457D03*
X1353311Y930646D03*
X1351461Y940213D03*
Y933835D03*
X1353311Y937024D03*
Y943402D03*
X1351461Y946591D03*
X1353311Y949780D03*
X1351461Y952969D03*
X1353311Y956158D03*
X1351461Y965725D03*
X1353311Y968914D03*
X1351461Y959347D03*
X1353311Y962536D03*
X1351461Y984859D03*
Y978481D03*
X1353311Y981670D03*
X1351461Y972103D03*
X1353311Y975292D03*
Y988048D03*
X1351461Y997615D03*
X1353311Y1000804D03*
Y994426D03*
X1351461Y1003993D03*
X1353311Y1007182D03*
X1354493Y1031244D03*
X1352642Y1034433D03*
X1354493Y1037622D03*
X1352642Y1040811D03*
X1354493Y1050378D03*
X1352642Y1047189D03*
X1354493Y1063134D03*
X1352642Y1066323D03*
X1354493Y1069512D03*
X1352642Y1072701D03*
X1354493Y1075890D03*
X1352642Y1079079D03*
X1354493Y1082268D03*
X1352642Y1085457D03*
X1354493Y1088646D03*
X1361894D03*
Y1082268D03*
X1352642Y1104591D03*
X1354493Y1095024D03*
X1352642Y1098213D03*
X1354493Y1101402D03*
X1352642Y1091835D03*
X1361894Y1095024D03*
X1354493Y1114158D03*
X1352642Y1117347D03*
X1354493Y1107780D03*
X1352642Y1110969D03*
X1361894Y1114158D03*
Y1107780D03*
X1354493Y1120536D03*
X1352642Y1123725D03*
X1354493Y1133292D03*
Y1126914D03*
X1352642Y1130102D03*
X1361894Y1120536D03*
Y1126914D03*
Y1133292D03*
X1352642Y1136480D03*
X1354493Y1139669D03*
X1352642Y1142858D03*
X1354493Y1146047D03*
X1352642Y1149236D03*
X1361894Y1139669D03*
Y1146047D03*
X1354493Y1152425D03*
X1352642Y1155614D03*
X1361894Y1158803D03*
X1358193D03*
X1361894Y1152425D03*
X1352436Y1549970D03*
X1357161D03*
X1361885D03*
X1354011Y1552698D03*
X1358735D03*
X1363460D03*
X1352436Y1563608D03*
X1357161D03*
X1361885D03*
X1354011Y1566336D03*
X1358735D03*
X1363460D03*
X1375516Y892379D03*
X1371815D03*
X1375516Y898757D03*
Y905134D03*
X1371815Y898757D03*
Y905134D03*
X1375516Y911512D03*
X1371815D03*
X1375516Y917890D03*
Y924268D03*
X1371815Y917890D03*
Y924268D03*
X1375516Y930646D03*
X1371815D03*
X1372997Y1088646D03*
Y1082268D03*
X1365595Y1088646D03*
Y1082268D03*
X1376697Y1088646D03*
Y1082268D03*
X1372997Y1095024D03*
X1365595D03*
X1376697D03*
X1365595Y1114158D03*
Y1107780D03*
X1376697Y1114158D03*
Y1107780D03*
X1372997Y1114158D03*
Y1107780D03*
X1365595Y1120536D03*
X1376697D03*
Y1126914D03*
X1372997Y1120536D03*
Y1126914D03*
X1365595D03*
Y1133292D03*
X1376697D03*
X1372997D03*
X1365595Y1139669D03*
Y1146047D03*
X1376697Y1139669D03*
Y1146047D03*
X1372997Y1139669D03*
Y1146047D03*
Y1158803D03*
X1369296D03*
X1365595Y1152425D03*
X1376697D03*
X1372997D03*
X1371334Y1549970D03*
X1376058D03*
X1366609D03*
X1372909Y1552698D03*
X1377633D03*
X1368184D03*
X1371334Y1563608D03*
X1376058D03*
X1366609D03*
X1372909Y1566336D03*
X1377633D03*
X1368184D03*
X1386619Y892379D03*
X1394020D03*
X1382918D03*
X1386619Y905134D03*
Y898757D03*
X1394020Y905134D03*
Y898757D03*
X1382918Y905134D03*
Y898757D03*
X1386619Y911512D03*
X1394020D03*
X1382918D03*
X1386619Y924268D03*
Y917890D03*
X1394020Y924268D03*
Y917890D03*
X1382918Y924268D03*
Y917890D03*
X1384099Y1088646D03*
Y1082268D03*
X1387800Y1088646D03*
Y1082268D03*
X1384099Y1095024D03*
X1387800D03*
Y1114158D03*
X1384099D03*
X1387800Y1120536D03*
Y1126914D03*
X1384099Y1120536D03*
Y1126914D03*
X1387800Y1133292D03*
X1384099D03*
X1387800Y1139669D03*
Y1146047D03*
X1384099Y1139669D03*
Y1146047D03*
Y1158803D03*
X1380398D03*
X1391500D03*
X1387800Y1152425D03*
X1384099D03*
X1380783Y1549970D03*
X1385507D03*
X1390232D03*
X1382357Y1552698D03*
X1387082D03*
X1391806D03*
X1380783Y1563608D03*
X1385507D03*
X1390232D03*
X1382357Y1566336D03*
X1387082D03*
X1391806D03*
X1406973Y895568D03*
X1397721Y892379D03*
X1403272Y895568D03*
X1406973Y908324D03*
Y901946D03*
X1397721Y905134D03*
Y898757D03*
X1403272Y908324D03*
Y901946D03*
X1397721Y911512D03*
X1406973Y921079D03*
Y914701D03*
X1397721Y924268D03*
Y917890D03*
X1403272Y921079D03*
Y914701D03*
X1406973Y927457D03*
X1403272D03*
X1395201Y1082268D03*
X1404453Y1085457D03*
X1395201Y1088646D03*
X1398902Y1082268D03*
X1408154Y1085457D03*
X1398902Y1088646D03*
X1395201Y1095024D03*
Y1101402D03*
X1404453Y1098213D03*
Y1091835D03*
X1398902Y1095024D03*
Y1101402D03*
X1408154Y1098213D03*
Y1091835D03*
X1398902Y1114158D03*
X1408154Y1117347D03*
Y1110969D03*
X1395201Y1114158D03*
X1404453Y1117347D03*
Y1110969D03*
X1398902Y1120536D03*
Y1126914D03*
X1408154Y1123725D03*
X1395201Y1120536D03*
Y1126914D03*
X1404453Y1123725D03*
X1398902Y1133292D03*
X1408154Y1130102D03*
X1395201Y1133292D03*
X1404453Y1130102D03*
X1398902Y1139669D03*
Y1146047D03*
X1408154Y1142858D03*
Y1136480D03*
X1395201Y1139669D03*
Y1146047D03*
X1404453Y1142858D03*
Y1136480D03*
X1395201Y1158803D03*
X1398902Y1152425D03*
X1395201D03*
X1394956Y1549970D03*
X1396531Y1552698D03*
X1394956Y1563608D03*
X1396531Y1566336D03*
X1434704Y892379D03*
X1425452Y895568D03*
X1438405Y892379D03*
X1429153Y895568D03*
X1434704Y898757D03*
Y905134D03*
X1425452Y901946D03*
Y908324D03*
X1438405Y898757D03*
Y905134D03*
X1429153Y901946D03*
Y908324D03*
X1434704Y911512D03*
X1438405D03*
X1434704Y917890D03*
Y924268D03*
X1425452Y914701D03*
Y921079D03*
X1438405Y917890D03*
Y924268D03*
X1429153Y914701D03*
Y921079D03*
X1438405Y937024D03*
X1429153Y940213D03*
X1434704Y937024D03*
X1425452Y940213D03*
Y927457D03*
X1429153D03*
X1438405Y943402D03*
Y956158D03*
X1429153Y946591D03*
Y952969D03*
X1438405Y949780D03*
X1434704Y943402D03*
Y956158D03*
X1425452Y946591D03*
Y952969D03*
X1434704Y949780D03*
X1438405Y962536D03*
X1429153Y965725D03*
Y959347D03*
X1438405Y968914D03*
X1434704Y962536D03*
X1425452Y965725D03*
Y959347D03*
X1434704Y968914D03*
X1438405Y975292D03*
X1429153Y972103D03*
Y978481D03*
X1434704Y975292D03*
X1425452Y972103D03*
Y978481D03*
X1435885Y1088646D03*
X1430334Y1085457D03*
X1426633D03*
X1435885Y1082268D03*
Y1101402D03*
Y1095024D03*
X1430334Y1091835D03*
Y1098213D03*
X1426633Y1091835D03*
Y1098213D03*
Y1110969D03*
Y1117347D03*
X1435885Y1114158D03*
X1430334Y1110969D03*
Y1117347D03*
Y1130102D03*
X1426633D03*
Y1123725D03*
X1435885Y1126914D03*
Y1120536D03*
X1430334Y1123725D03*
X1435885Y1133292D03*
Y1146047D03*
Y1139669D03*
X1426633Y1136480D03*
Y1142858D03*
X1430334Y1136480D03*
Y1142858D03*
X1445806Y892379D03*
X1449507D03*
X1445806Y898757D03*
Y905134D03*
X1449507Y898757D03*
Y905134D03*
X1445806Y911512D03*
X1449507D03*
X1445806Y917890D03*
Y924268D03*
X1449507Y917890D03*
Y924268D03*
Y949780D03*
Y943402D03*
Y956158D03*
X1445806Y949780D03*
Y943402D03*
Y956158D03*
X1449507Y968914D03*
Y962536D03*
X1445806Y968914D03*
Y962536D03*
X1449507Y975292D03*
X1445806D03*
X1439586Y1088646D03*
X1450688Y1082268D03*
X1446987D03*
X1439586D03*
X1450688Y1088646D03*
X1446987D03*
X1439586Y1101402D03*
Y1095024D03*
X1450688D03*
X1446987D03*
Y1114158D03*
X1439586D03*
X1450688D03*
X1446987Y1126914D03*
Y1120536D03*
X1439586Y1126914D03*
Y1120536D03*
X1450688Y1126914D03*
Y1120536D03*
X1446987Y1133292D03*
X1450688D03*
X1439586D03*
X1446987Y1139669D03*
X1450688D03*
X1446987Y1146047D03*
X1439586D03*
Y1139669D03*
X1450688Y1146047D03*
X1468011Y892379D03*
X1456909D03*
X1460609D03*
X1468011Y911512D03*
Y898757D03*
Y905134D03*
X1456909Y898757D03*
Y905134D03*
X1460609Y898757D03*
Y905134D03*
X1456909Y911512D03*
X1460609D03*
X1468011Y924268D03*
Y917890D03*
X1456909Y924268D03*
Y917890D03*
X1460609Y924268D03*
Y917890D03*
X1468011Y930646D03*
X1456909D03*
X1460609D03*
Y949780D03*
Y943402D03*
Y956158D03*
X1468011Y949780D03*
Y943402D03*
Y956158D03*
X1456909Y949780D03*
Y943402D03*
Y956158D03*
X1460609Y968914D03*
Y962536D03*
X1468011Y968914D03*
Y962536D03*
X1456909Y968914D03*
Y962536D03*
X1460609Y975292D03*
X1468011D03*
X1456909D03*
X1461791Y1082268D03*
Y1088646D03*
X1458090Y1082268D03*
Y1088646D03*
X1461791Y1095024D03*
X1458090D03*
Y1114158D03*
Y1107780D03*
X1461791Y1114158D03*
Y1107780D03*
X1458090Y1133292D03*
X1461791D03*
X1458090Y1126914D03*
Y1120536D03*
X1461791Y1126914D03*
Y1120536D03*
X1458090Y1146047D03*
Y1139669D03*
X1461791Y1146047D03*
Y1139669D03*
X1461777Y1552698D03*
X1460202Y1549970D03*
X1464926D03*
X1466501Y1552698D03*
X1460202Y1563608D03*
X1464926D03*
X1461777Y1566336D03*
X1466501D03*
X1471712Y892379D03*
X1480964Y889190D03*
X1479113Y892379D03*
X1480964Y895568D03*
X1471712Y911512D03*
Y898757D03*
Y905134D03*
X1479113Y911512D03*
X1480964Y901946D03*
X1479113Y905134D03*
X1480964Y908324D03*
X1479113Y898757D03*
X1480964Y921079D03*
X1479113Y924268D03*
X1480964Y914701D03*
X1479113Y917890D03*
X1471712Y924268D03*
Y917890D03*
X1480964Y927457D03*
X1479113Y930646D03*
X1480964Y940213D03*
Y933835D03*
X1479113Y937024D03*
X1471712Y930646D03*
Y949780D03*
Y943402D03*
Y956158D03*
X1479113Y943402D03*
X1480964Y946591D03*
X1479113Y949780D03*
X1480964Y952969D03*
X1479113Y956158D03*
X1480964Y965725D03*
X1479113Y968914D03*
X1480964Y959347D03*
X1479113Y962536D03*
X1471712Y968914D03*
Y962536D03*
X1480964Y984859D03*
Y978481D03*
X1479113Y981670D03*
X1480964Y972103D03*
X1479113Y975292D03*
X1471712D03*
X1479113Y988048D03*
X1480964Y997615D03*
X1479113Y1000804D03*
X1480964Y991237D03*
Y1003993D03*
X1479113Y1007182D03*
X1480295Y1031244D03*
X1482145Y1034433D03*
X1480295Y1037622D03*
X1482145Y1040811D03*
X1480295Y1044000D03*
Y1050378D03*
X1482145Y1047189D03*
X1480295Y1063134D03*
X1482145Y1066323D03*
X1480295Y1069512D03*
X1482145Y1072701D03*
X1480295Y1075890D03*
X1482145Y1079079D03*
X1480295Y1082268D03*
X1482145Y1085457D03*
X1480295Y1088646D03*
X1472893Y1082268D03*
Y1088646D03*
X1469192Y1082268D03*
Y1088646D03*
X1482145Y1104591D03*
X1480295Y1095024D03*
X1482145Y1098213D03*
X1480295Y1101402D03*
X1482145Y1091835D03*
X1472893Y1095024D03*
X1469192D03*
X1480295Y1114158D03*
X1482145Y1117347D03*
X1480295Y1107780D03*
X1482145Y1110969D03*
X1469192Y1107780D03*
Y1114158D03*
X1472893Y1107780D03*
Y1114158D03*
X1480295Y1120536D03*
X1482145Y1123725D03*
X1480295Y1133292D03*
Y1126914D03*
X1482145Y1130102D03*
X1469192Y1120536D03*
X1472893D03*
X1469192Y1133292D03*
Y1126914D03*
X1472893Y1133292D03*
Y1126914D03*
X1482145Y1136480D03*
X1480295Y1139669D03*
X1482145Y1142858D03*
X1480295Y1146047D03*
X1482145Y1149236D03*
X1469192Y1146047D03*
Y1139669D03*
X1472893Y1146047D03*
Y1139669D03*
X1480295Y1152425D03*
X1482145Y1155614D03*
X1479099Y1549970D03*
X1483824D03*
X1480674Y1552698D03*
X1469651Y1549970D03*
X1474375D03*
X1471225Y1552698D03*
X1475950D03*
X1469651Y1563608D03*
X1474375D03*
X1479099D03*
X1483824D03*
X1471225Y1566336D03*
X1475950D03*
X1480674D03*
X1486515Y886001D03*
X1484665Y889190D03*
Y895568D03*
X1486515Y892379D03*
X1497617Y886001D03*
X1492066Y889190D03*
X1493917Y892379D03*
X1492066Y895568D03*
X1497617Y892379D03*
X1484665Y908324D03*
X1486515Y898757D03*
X1484665Y901946D03*
X1486515Y905134D03*
Y911512D03*
X1493917D03*
X1497617Y898757D03*
X1492066Y901946D03*
X1493917Y905134D03*
X1497617D03*
X1492066Y908324D03*
X1497617Y911512D03*
X1493917Y898757D03*
X1486515Y917890D03*
X1484665Y921079D03*
X1486515Y924268D03*
X1484665Y914701D03*
X1497617Y917890D03*
X1492066Y921079D03*
X1493917Y924268D03*
X1497617D03*
X1492066Y914701D03*
X1493917Y917890D03*
X1484665Y927457D03*
X1486515Y937024D03*
X1484665Y940213D03*
Y933835D03*
X1486515Y930646D03*
X1492066Y927457D03*
X1493917Y930646D03*
X1497617Y937024D03*
X1492066Y940213D03*
Y933835D03*
X1497617Y930646D03*
X1493917Y937024D03*
X1486515Y943402D03*
X1484665Y946591D03*
X1486515Y956158D03*
X1484665Y952969D03*
X1486515Y949780D03*
X1493917Y943402D03*
X1497617D03*
X1492066Y946591D03*
X1493917Y949780D03*
X1497617Y956158D03*
X1492066Y952969D03*
X1497617Y949780D03*
X1493917Y956158D03*
X1486515Y962536D03*
X1484665Y965725D03*
Y959347D03*
X1486515Y968914D03*
X1497617Y962536D03*
X1492066Y965725D03*
X1493917Y968914D03*
X1492066Y959347D03*
X1493917Y962536D03*
X1497617Y968914D03*
X1486515Y975292D03*
X1484665Y978481D03*
Y972103D03*
X1492066Y984859D03*
X1497617Y975292D03*
X1492066Y978481D03*
X1493917Y981670D03*
X1492066Y972103D03*
X1493917Y975292D03*
X1486515Y994426D03*
X1484665Y997615D03*
X1486515Y1000804D03*
Y988048D03*
X1493917D03*
X1497617Y994426D03*
X1492066Y997615D03*
X1493917Y1000804D03*
X1497617D03*
Y988048D03*
X1492066Y991237D03*
X1484665Y1010371D03*
X1486515Y1007182D03*
X1484665Y1003993D03*
X1497617Y1007182D03*
X1492066Y1003993D03*
X1493917Y1007182D03*
X1485846Y1034433D03*
X1487696Y1037622D03*
X1485846Y1040811D03*
X1495098Y1031244D03*
X1493247Y1034433D03*
X1498799Y1037622D03*
X1495098D03*
X1493247Y1040811D03*
X1495098Y1044000D03*
X1485846Y1059945D03*
X1487696Y1050378D03*
X1485846Y1053567D03*
X1495098Y1050378D03*
X1493247Y1047189D03*
X1498799Y1050378D03*
X1485846Y1072701D03*
X1487696Y1063134D03*
Y1069512D03*
X1485846Y1066323D03*
X1495098Y1063134D03*
X1498799D03*
X1493247Y1066323D03*
X1495098Y1069512D03*
X1498799D03*
X1493247Y1072701D03*
X1487696Y1075890D03*
X1485846Y1079079D03*
X1487696Y1082268D03*
Y1088646D03*
X1485846Y1085457D03*
X1495098Y1075890D03*
X1498799D03*
X1493247Y1079079D03*
X1495098Y1082268D03*
X1498799D03*
X1493247Y1085457D03*
X1498799Y1088646D03*
X1495098D03*
X1487696Y1101402D03*
X1485846Y1091835D03*
X1487696Y1095024D03*
X1485846Y1098213D03*
Y1104591D03*
X1498799Y1101402D03*
X1493247Y1104591D03*
X1495098Y1095024D03*
X1498799D03*
X1493247Y1098213D03*
X1495098Y1101402D03*
X1493247Y1091835D03*
X1485846Y1110969D03*
X1487696Y1114158D03*
X1485846Y1117347D03*
X1487696Y1107780D03*
X1495098Y1114158D03*
X1498799D03*
X1493247Y1117347D03*
X1498799Y1107780D03*
X1495098D03*
X1493247Y1110969D03*
X1487696Y1120536D03*
X1485846Y1130102D03*
X1487696Y1133292D03*
Y1126914D03*
X1485846Y1123725D03*
X1495098Y1120536D03*
X1498799D03*
X1493247Y1123725D03*
X1495098Y1133292D03*
X1498799D03*
Y1126914D03*
X1495098D03*
X1493247Y1130102D03*
X1485846Y1136480D03*
X1487696Y1139669D03*
X1485846Y1149236D03*
X1487696Y1146047D03*
X1485846Y1142858D03*
X1493247Y1136480D03*
X1495098Y1139669D03*
X1498799D03*
X1493247Y1142858D03*
X1498799Y1146047D03*
X1495098D03*
X1493247Y1149236D03*
X1487696Y1152425D03*
X1495098D03*
X1498799D03*
X1497997Y1549970D03*
X1488548D03*
X1493273D03*
X1485399Y1552698D03*
X1490123D03*
X1494847D03*
X1488548Y1563608D03*
X1493273D03*
X1497997D03*
X1485399Y1566336D03*
X1490123D03*
X1494847D03*
X1499468Y889190D03*
Y895568D03*
Y908324D03*
Y901946D03*
Y921079D03*
Y914701D03*
Y927457D03*
Y940213D03*
Y933835D03*
Y946591D03*
Y952969D03*
Y965725D03*
Y959347D03*
Y978481D03*
Y972103D03*
Y997615D03*
Y1010371D03*
Y1003993D03*
X1500649Y1034433D03*
Y1040811D03*
Y1059945D03*
Y1053567D03*
Y1072701D03*
Y1066323D03*
Y1079079D03*
Y1085457D03*
Y1091835D03*
Y1098213D03*
Y1104591D03*
Y1110969D03*
Y1117347D03*
Y1130102D03*
Y1123725D03*
Y1136480D03*
Y1149236D03*
Y1142858D03*
Y1155614D03*
X1507446Y1549970D03*
X1512170D03*
X1502721D03*
X1509021Y1552698D03*
X1513745D03*
X1499572D03*
X1504296D03*
X1507446Y1563608D03*
X1512170D03*
X1502721D03*
X1509021Y1566336D03*
X1513745D03*
X1499572D03*
X1504296D03*
X1523523Y886001D03*
X1517972Y889190D03*
X1525373D03*
X1519822Y892379D03*
X1525373Y895568D03*
X1517972D03*
X1523523Y892379D03*
X1525373Y908324D03*
X1519822Y911512D03*
X1523523Y898757D03*
X1517972Y901946D03*
X1525373D03*
X1519822Y905134D03*
X1523523D03*
X1517972Y908324D03*
X1523523Y911512D03*
X1519822Y898757D03*
X1523523Y917890D03*
X1517972Y921079D03*
X1525373D03*
X1519822Y924268D03*
X1523523D03*
X1525373Y914701D03*
X1517972D03*
X1519822Y917890D03*
X1517972Y927457D03*
X1525373D03*
X1519822Y930646D03*
X1523523Y937024D03*
X1517972Y940213D03*
X1525373D03*
Y933835D03*
X1517972D03*
X1523523Y930646D03*
X1519822Y937024D03*
Y943402D03*
X1523523D03*
X1517972Y946591D03*
X1525373D03*
X1519822Y949780D03*
X1523523Y956158D03*
X1525373Y952969D03*
X1517972D03*
X1523523Y949780D03*
X1519822Y956158D03*
X1523523Y962536D03*
X1517972Y965725D03*
X1525373D03*
X1519822Y968914D03*
X1517972Y959347D03*
X1525373D03*
X1519822Y962536D03*
X1523523Y968914D03*
X1517972Y984859D03*
X1523523Y975292D03*
X1517972Y978481D03*
X1525373D03*
X1519822Y981670D03*
X1525373Y972103D03*
X1517972D03*
X1519822Y975292D03*
Y988048D03*
X1523523Y994426D03*
X1525373Y997615D03*
X1517972D03*
X1519822Y1000804D03*
X1523523D03*
Y988048D03*
X1517972Y991237D03*
X1525373Y1010371D03*
X1523523Y1007182D03*
X1525373Y1003993D03*
X1517972D03*
X1519822Y1007182D03*
X1521003Y1031244D03*
X1519153Y1034433D03*
X1526554D03*
X1524704Y1037622D03*
X1521003D03*
X1519153Y1040811D03*
X1526554D03*
X1521003Y1044000D03*
Y1050378D03*
X1526554Y1059945D03*
X1519153Y1047189D03*
X1524704Y1050378D03*
X1526554Y1053567D03*
Y1072701D03*
X1521003Y1063134D03*
X1524704D03*
X1519153Y1066323D03*
X1521003Y1069512D03*
X1524704D03*
X1519153Y1072701D03*
X1526554Y1066323D03*
X1521003Y1075890D03*
X1524704D03*
X1519153Y1079079D03*
X1526554D03*
X1521003Y1082268D03*
X1524704D03*
X1519153Y1085457D03*
X1524704Y1088646D03*
X1521003D03*
X1526554Y1085457D03*
X1524704Y1101402D03*
X1519153Y1104591D03*
X1526554Y1091835D03*
X1521003Y1095024D03*
X1524704D03*
X1519153Y1098213D03*
X1526554D03*
X1521003Y1101402D03*
X1526554Y1104591D03*
X1519153Y1091835D03*
X1526554Y1110969D03*
X1521003Y1114158D03*
X1524704D03*
X1519153Y1117347D03*
X1526554D03*
X1524704Y1107780D03*
X1521003D03*
X1519153Y1110969D03*
X1521003Y1120536D03*
X1524704D03*
X1519153Y1123725D03*
X1526554Y1130102D03*
X1521003Y1133292D03*
X1524704D03*
Y1126914D03*
X1521003D03*
X1526554Y1123725D03*
X1519153Y1130102D03*
Y1136480D03*
X1526554D03*
X1521003Y1139669D03*
X1524704D03*
X1519153Y1142858D03*
X1526554Y1149236D03*
X1524704Y1146047D03*
X1521003D03*
X1526554Y1142858D03*
X1519153Y1149236D03*
X1521003Y1152425D03*
X1524704D03*
X1526554Y1155614D03*
X1516895Y1549970D03*
X1521619D03*
X1526344D03*
X1518469Y1552698D03*
X1523194D03*
X1527918D03*
X1516895Y1563608D03*
X1521619D03*
X1526344D03*
X1518469Y1566336D03*
X1523194D03*
X1527918D03*
X1538326Y886001D03*
X1532775Y889190D03*
X1536476D03*
X1530925Y892379D03*
X1536476Y895568D03*
X1532775D03*
X1538326Y892379D03*
X1536476Y908324D03*
X1530925Y911512D03*
X1538326Y898757D03*
X1532775Y901946D03*
X1536476D03*
X1530925Y905134D03*
X1538326D03*
X1532775Y908324D03*
X1538326Y911512D03*
X1530925Y898757D03*
X1538326Y917890D03*
X1532775Y921079D03*
X1536476D03*
X1530925Y924268D03*
X1538326D03*
X1536476Y914701D03*
X1532775D03*
X1530925Y917890D03*
X1532775Y927457D03*
X1536476D03*
X1530925Y930646D03*
X1538326Y937024D03*
X1532775Y940213D03*
X1536476D03*
Y933835D03*
X1532775D03*
X1538326Y930646D03*
X1530925Y937024D03*
Y943402D03*
X1538326D03*
X1532775Y946591D03*
X1536476D03*
X1530925Y949780D03*
X1538326Y956158D03*
X1536476Y952969D03*
X1532775D03*
X1538326Y949780D03*
X1530925Y956158D03*
X1538326Y962536D03*
X1532775Y965725D03*
X1536476D03*
X1530925Y968914D03*
X1532775Y959347D03*
X1536476D03*
X1530925Y962536D03*
X1538326Y968914D03*
X1532775Y984859D03*
X1538326Y975292D03*
X1532775Y978481D03*
X1536476D03*
X1530925Y981670D03*
X1536476Y972103D03*
X1532775D03*
X1530925Y975292D03*
Y988048D03*
X1538326Y994426D03*
X1536476Y997615D03*
X1532775D03*
X1530925Y1000804D03*
X1538326D03*
Y988048D03*
X1532775Y991237D03*
X1536476Y1010371D03*
X1538326Y1007182D03*
X1536476Y1003993D03*
X1532775D03*
X1530925Y1007182D03*
X1532106Y1031244D03*
X1533956Y1034433D03*
X1537657D03*
X1539507Y1037622D03*
X1532106D03*
X1533956Y1040811D03*
X1537657D03*
X1532106Y1044000D03*
Y1050378D03*
X1537657Y1059945D03*
X1533956Y1047189D03*
X1539507Y1050378D03*
X1537657Y1053567D03*
Y1072701D03*
X1532106Y1063134D03*
X1539507D03*
X1533956Y1066323D03*
X1532106Y1069512D03*
X1539507D03*
X1533956Y1072701D03*
X1537657Y1066323D03*
X1532106Y1075890D03*
X1539507D03*
X1533956Y1079079D03*
X1537657D03*
X1532106Y1082268D03*
X1539507D03*
X1533956Y1085457D03*
X1539507Y1088646D03*
X1532106D03*
X1537657Y1085457D03*
X1539507Y1101402D03*
X1533956Y1104591D03*
X1537657Y1091835D03*
X1532106Y1095024D03*
X1539507D03*
X1533956Y1098213D03*
X1537657D03*
X1532106Y1101402D03*
X1537657Y1104591D03*
X1533956Y1091835D03*
X1537657Y1110969D03*
X1532106Y1114158D03*
X1539507D03*
X1533956Y1117347D03*
X1537657D03*
X1539507Y1107780D03*
X1532106D03*
X1533956Y1110969D03*
X1532106Y1120536D03*
X1539507D03*
X1533956Y1123725D03*
X1537657Y1130102D03*
X1532106Y1133292D03*
X1539507D03*
Y1126914D03*
X1532106D03*
X1537657Y1123725D03*
X1533956Y1130102D03*
Y1136480D03*
X1537657D03*
X1532106Y1139669D03*
X1539507D03*
X1533956Y1142858D03*
X1537657Y1149236D03*
X1539507Y1146047D03*
X1532106D03*
X1537657Y1142858D03*
X1533956Y1149236D03*
X1532106Y1152425D03*
X1539507D03*
X1533956Y1155614D03*
X1531068Y1549970D03*
X1532643Y1552698D03*
X1531068Y1563608D03*
X1532643Y1566336D03*
X1588264Y1549970D03*
Y1563608D03*
X1592988Y1549970D03*
X1597713D03*
X1602437D03*
X1589839Y1552698D03*
X1594563D03*
X1599287D03*
X1592988Y1563608D03*
X1597713D03*
X1602437D03*
X1589839Y1566336D03*
X1594563D03*
X1599287D03*
X1607161Y1549970D03*
X1611886D03*
X1616610D03*
X1604012Y1552698D03*
X1608736D03*
X1613461D03*
X1607161Y1563608D03*
X1611886D03*
X1616610D03*
X1604012Y1566336D03*
X1608736D03*
X1613461D03*
X1621335Y1549970D03*
X1626059D03*
X1630783D03*
X1618185Y1552698D03*
X1622909D03*
X1627634D03*
X1632358D03*
X1621335Y1563608D03*
X1626059D03*
X1630783D03*
X1618185Y1566336D03*
X1622909D03*
X1627634D03*
X1632358D03*
X1635508Y1549970D03*
X1640232D03*
X1644957D03*
X1637083Y1552698D03*
X1641807D03*
X1646531D03*
X1635508Y1563608D03*
X1640232D03*
X1644957D03*
X1637083Y1566336D03*
X1641807D03*
X1646531D03*
X1649681Y1549970D03*
X1654406D03*
X1659130D03*
X1651256Y1552698D03*
X1655980D03*
X1660705D03*
X1649681Y1563608D03*
X1654406D03*
X1659130D03*
X1651256Y1566336D03*
X1655980D03*
X1660705D03*
G54D34*
X230905Y1649173D03*
Y1653897D03*
Y1663346D03*
Y1668070D03*
Y1677519D03*
Y1682244D03*
Y1691692D03*
Y1696417D03*
X238779Y1653110D03*
Y1657834D03*
X246653Y1663346D03*
Y1668070D03*
Y1677519D03*
Y1682244D03*
X238779Y1681456D03*
Y1686180D03*
X246653Y1691692D03*
Y1696417D03*
X238779Y1695629D03*
Y1700354D03*
X254527Y1667283D03*
Y1672007D03*
Y1681456D03*
Y1686180D03*
Y1695629D03*
Y1700354D03*
X270275Y1653110D03*
Y1657834D03*
Y1667283D03*
Y1672007D03*
X262401Y1677519D03*
X270275Y1681456D03*
X262401Y1682244D03*
X270275Y1686180D03*
X262401Y1691692D03*
X270275Y1695629D03*
X262401Y1696417D03*
X270275Y1700354D03*
X278149Y1649173D03*
X286023Y1653110D03*
X278149Y1653897D03*
X286023Y1657834D03*
X278149Y1663346D03*
X286023Y1667283D03*
X278149Y1668070D03*
X286023Y1672007D03*
X278149Y1677519D03*
X286023Y1681456D03*
X278149Y1682244D03*
X286023Y1686180D03*
X278149Y1691692D03*
X286023Y1695629D03*
X278149Y1696417D03*
X286023Y1700354D03*
X297835Y1677519D03*
X305709Y1681456D03*
X297835Y1682244D03*
X305709Y1686180D03*
X297835Y1691692D03*
X305709Y1695629D03*
X297835Y1696417D03*
X305709Y1700354D03*
X313583Y1677519D03*
X321457Y1681456D03*
X313583Y1682244D03*
X321457Y1686180D03*
X313583Y1691692D03*
X321457Y1695629D03*
X313583Y1696417D03*
X321457Y1700354D03*
X329331Y1677519D03*
Y1682244D03*
Y1691692D03*
Y1696417D03*
X345079Y1677519D03*
Y1682244D03*
X337205Y1681456D03*
Y1686180D03*
X345079Y1691692D03*
Y1696417D03*
X337205Y1695629D03*
Y1700354D03*
X352953Y1681456D03*
Y1686180D03*
Y1695629D03*
Y1700354D03*
X495078Y1677519D03*
Y1682244D03*
Y1691692D03*
Y1696417D03*
X510826Y1677519D03*
Y1682244D03*
X502952Y1681456D03*
Y1686180D03*
X510826Y1691692D03*
Y1696417D03*
X502952Y1695629D03*
Y1700354D03*
X518700Y1681456D03*
Y1686180D03*
X526574Y1677519D03*
Y1682244D03*
X518700Y1695629D03*
Y1700354D03*
X526574Y1691692D03*
Y1696417D03*
X542322Y1677519D03*
Y1682244D03*
X534448Y1681456D03*
Y1686180D03*
X542322Y1691692D03*
Y1696417D03*
X534448Y1695629D03*
Y1700354D03*
X550196Y1681456D03*
Y1686180D03*
Y1695629D03*
Y1700354D03*
X562008Y1677519D03*
X569882Y1681456D03*
X562008Y1682244D03*
X569882Y1686180D03*
X562008Y1691692D03*
X569882Y1695629D03*
X562008Y1696417D03*
X569882Y1700354D03*
X577756Y1677519D03*
X585630Y1681456D03*
X577756Y1682244D03*
X585630Y1686180D03*
X577756Y1691692D03*
X585630Y1695629D03*
X577756Y1696417D03*
X585630Y1700354D03*
X593504Y1677519D03*
X601378Y1681456D03*
X593504Y1682244D03*
X601378Y1686180D03*
X593504Y1691692D03*
X601378Y1695629D03*
X593504Y1696417D03*
X601378Y1700354D03*
X609252Y1677519D03*
X617126Y1681456D03*
X609252Y1682244D03*
X617126Y1686180D03*
X609252Y1691692D03*
X617126Y1695629D03*
X609252Y1696417D03*
X617126Y1700354D03*
X1238778Y1677519D03*
Y1682244D03*
Y1691692D03*
Y1696417D03*
X1254526Y1677519D03*
Y1682244D03*
X1246652Y1681456D03*
Y1686180D03*
X1254526Y1691692D03*
Y1696417D03*
X1246652Y1695629D03*
Y1700354D03*
X1262400Y1681456D03*
Y1686180D03*
X1270274Y1677519D03*
Y1682244D03*
X1262400Y1695629D03*
Y1700354D03*
X1270274Y1691692D03*
Y1696417D03*
X1286022Y1677519D03*
Y1682244D03*
X1278148Y1681456D03*
Y1686180D03*
X1286022Y1691692D03*
Y1696417D03*
X1278148Y1695629D03*
Y1700354D03*
X1293896Y1681456D03*
Y1686180D03*
Y1695629D03*
Y1700354D03*
X1305708Y1677519D03*
X1313582Y1681456D03*
X1305708Y1682244D03*
X1313582Y1686180D03*
X1305708Y1691692D03*
X1313582Y1695629D03*
X1305708Y1696417D03*
X1313582Y1700354D03*
X1321456Y1677519D03*
X1329330Y1681456D03*
X1321456Y1682244D03*
X1329330Y1686180D03*
X1321456Y1691692D03*
X1329330Y1695629D03*
X1321456Y1696417D03*
X1329330Y1700354D03*
X1337204Y1677519D03*
X1345078Y1681456D03*
X1337204Y1682244D03*
X1345078Y1686180D03*
X1337204Y1691692D03*
X1345078Y1695629D03*
X1337204Y1696417D03*
X1345078Y1700354D03*
X1352952Y1677519D03*
X1360826Y1681456D03*
X1352952Y1682244D03*
X1360826Y1686180D03*
X1352952Y1691692D03*
X1360826Y1695629D03*
X1352952Y1696417D03*
X1360826Y1700354D03*
X1502952Y1677519D03*
X1510826Y1681456D03*
X1502952Y1682244D03*
X1510826Y1686180D03*
X1502952Y1691692D03*
X1510826Y1695629D03*
X1502952Y1696417D03*
X1510826Y1700354D03*
X1518700Y1677519D03*
X1526574Y1681456D03*
X1518700Y1682244D03*
X1526574Y1686180D03*
X1518700Y1691692D03*
X1526574Y1695629D03*
X1518700Y1696417D03*
X1526574Y1700354D03*
X1534448Y1677519D03*
X1542322Y1681456D03*
X1534448Y1682244D03*
X1542322Y1686180D03*
X1534448Y1691692D03*
X1542322Y1695629D03*
X1534448Y1696417D03*
X1542322Y1700354D03*
X1550196Y1677519D03*
X1558070Y1681456D03*
X1550196Y1682244D03*
X1558070Y1686180D03*
X1550196Y1691692D03*
X1558070Y1695629D03*
X1550196Y1696417D03*
X1558070Y1700354D03*
X1569882Y1677519D03*
Y1682244D03*
Y1691692D03*
Y1696417D03*
X1585630Y1677519D03*
Y1682244D03*
X1577756Y1681456D03*
Y1686180D03*
X1585630Y1691692D03*
Y1696417D03*
X1577756Y1695629D03*
Y1700354D03*
X1593504Y1681456D03*
Y1686180D03*
X1601378Y1677519D03*
Y1682244D03*
X1593504Y1695629D03*
Y1700354D03*
X1601378Y1691692D03*
Y1696417D03*
X1617126Y1677519D03*
Y1682244D03*
X1609252Y1681456D03*
Y1686180D03*
X1617126Y1691692D03*
Y1696417D03*
X1609252Y1695629D03*
Y1700354D03*
X1625000Y1681456D03*
Y1686180D03*
Y1695629D03*
Y1700354D03*
G54D50*
X676509Y145866D03*
G54D35*
X230905Y1705866D03*
Y1710590D03*
Y1720039D03*
Y1724763D03*
Y1734212D03*
X238779Y1643661D03*
X246653Y1649173D03*
Y1653897D03*
X238779Y1667283D03*
Y1672007D03*
X246653Y1705866D03*
Y1710590D03*
X238779Y1709803D03*
Y1714527D03*
X246653Y1720039D03*
Y1724763D03*
X238779Y1723976D03*
Y1728700D03*
X246653Y1734212D03*
X254527Y1643661D03*
Y1653110D03*
Y1657834D03*
Y1709803D03*
Y1714527D03*
Y1723976D03*
Y1728700D03*
X270275Y1643661D03*
X262401Y1649173D03*
Y1653897D03*
Y1663346D03*
Y1668070D03*
Y1705866D03*
X270275Y1709803D03*
X262401Y1710590D03*
X270275Y1714527D03*
X262401Y1720039D03*
X270275Y1723976D03*
X262401Y1724763D03*
X270275Y1728700D03*
X262401Y1734212D03*
X286023Y1643661D03*
X278149Y1705866D03*
X286023Y1709803D03*
X278149Y1710590D03*
X286023Y1714527D03*
X278149Y1720039D03*
X286023Y1723976D03*
X278149Y1724763D03*
X286023Y1728700D03*
X278149Y1734212D03*
X305709Y1672007D03*
X297835Y1705866D03*
X305709Y1709803D03*
X297835Y1710590D03*
X305709Y1714527D03*
X297835Y1720039D03*
X305709Y1723976D03*
X297835Y1724763D03*
X305709Y1728700D03*
X297835Y1734212D03*
X321457Y1672007D03*
X313583Y1705866D03*
X321457Y1709803D03*
X313583Y1710590D03*
X321457Y1714527D03*
X313583Y1720039D03*
X321457Y1723976D03*
X313583Y1724763D03*
X321457Y1728700D03*
X313583Y1734212D03*
X329331Y1705866D03*
Y1710590D03*
Y1720039D03*
Y1724763D03*
Y1734212D03*
X337205Y1672007D03*
X345079Y1705866D03*
Y1710590D03*
X337205Y1709803D03*
Y1714527D03*
X345079Y1720039D03*
Y1724763D03*
X337205Y1723976D03*
Y1728700D03*
X345079Y1734212D03*
X352953Y1672007D03*
Y1709803D03*
Y1714527D03*
Y1723976D03*
Y1728700D03*
X495078Y1705866D03*
Y1710590D03*
Y1720039D03*
Y1724763D03*
Y1734212D03*
X502952Y1672007D03*
X510826Y1705866D03*
Y1710590D03*
X502952Y1709803D03*
Y1714527D03*
X510826Y1720039D03*
Y1724763D03*
X502952Y1723976D03*
Y1728700D03*
X510826Y1734212D03*
X518700Y1672007D03*
Y1709803D03*
Y1714527D03*
X526574Y1705866D03*
Y1710590D03*
X518700Y1723976D03*
Y1728700D03*
X526574Y1720039D03*
Y1724763D03*
Y1734212D03*
X534448Y1672007D03*
X542322Y1705866D03*
Y1710590D03*
X534448Y1709803D03*
Y1714527D03*
X542322Y1720039D03*
Y1724763D03*
X534448Y1723976D03*
Y1728700D03*
X542322Y1734212D03*
X550196Y1672007D03*
Y1709803D03*
Y1714527D03*
Y1723976D03*
Y1728700D03*
X569882Y1672007D03*
X562008Y1705866D03*
X569882Y1709803D03*
X562008Y1710590D03*
X569882Y1714527D03*
X562008Y1720039D03*
X569882Y1723976D03*
X562008Y1724763D03*
X569882Y1728700D03*
X562008Y1734212D03*
X585630Y1672007D03*
X577756Y1705866D03*
X585630Y1709803D03*
X577756Y1710590D03*
X585630Y1714527D03*
X577756Y1720039D03*
X585630Y1723976D03*
X577756Y1724763D03*
X585630Y1728700D03*
X577756Y1734212D03*
X601378Y1672007D03*
X593504Y1705866D03*
X601378Y1709803D03*
X593504Y1710590D03*
X601378Y1714527D03*
X593504Y1720039D03*
X601378Y1723976D03*
X593504Y1724763D03*
X601378Y1728700D03*
X593504Y1734212D03*
X617126Y1672007D03*
X609252Y1705866D03*
X617126Y1709803D03*
X609252Y1710590D03*
X617126Y1714527D03*
X609252Y1720039D03*
X617126Y1723976D03*
X609252Y1724763D03*
X617126Y1728700D03*
X609252Y1734212D03*
X1238778Y1705866D03*
Y1710590D03*
Y1720039D03*
Y1724763D03*
Y1734212D03*
X1246652Y1672007D03*
X1254526Y1705866D03*
Y1710590D03*
X1246652Y1709803D03*
Y1714527D03*
X1254526Y1720039D03*
Y1724763D03*
X1246652Y1723976D03*
Y1728700D03*
X1254526Y1734212D03*
X1262400Y1672007D03*
Y1709803D03*
Y1714527D03*
X1270274Y1705866D03*
Y1710590D03*
X1262400Y1723976D03*
Y1728700D03*
X1270274Y1720039D03*
Y1724763D03*
Y1734212D03*
X1278148Y1672007D03*
X1286022Y1705866D03*
Y1710590D03*
X1278148Y1709803D03*
Y1714527D03*
X1286022Y1720039D03*
Y1724763D03*
X1278148Y1723976D03*
Y1728700D03*
X1286022Y1734212D03*
X1293896Y1672007D03*
Y1709803D03*
Y1714527D03*
Y1723976D03*
Y1728700D03*
X1313582Y1672007D03*
X1305708Y1705866D03*
X1313582Y1709803D03*
X1305708Y1710590D03*
X1313582Y1714527D03*
X1305708Y1720039D03*
X1313582Y1723976D03*
X1305708Y1724763D03*
X1313582Y1728700D03*
X1305708Y1734212D03*
X1329330Y1672007D03*
X1321456Y1705866D03*
X1329330Y1709803D03*
X1321456Y1710590D03*
X1329330Y1714527D03*
X1321456Y1720039D03*
X1329330Y1723976D03*
X1321456Y1724763D03*
X1329330Y1728700D03*
X1321456Y1734212D03*
X1345078Y1672007D03*
X1337204Y1705866D03*
X1345078Y1709803D03*
X1337204Y1710590D03*
X1345078Y1714527D03*
X1337204Y1720039D03*
X1345078Y1723976D03*
X1337204Y1724763D03*
X1345078Y1728700D03*
X1337204Y1734212D03*
X1360826Y1672007D03*
X1352952Y1705866D03*
X1360826Y1709803D03*
X1352952Y1710590D03*
X1360826Y1714527D03*
X1352952Y1720039D03*
X1360826Y1723976D03*
X1352952Y1724763D03*
X1360826Y1728700D03*
X1352952Y1734212D03*
X1510826Y1672007D03*
X1502952Y1705866D03*
X1510826Y1709803D03*
X1502952Y1710590D03*
X1510826Y1714527D03*
X1502952Y1720039D03*
X1510826Y1723976D03*
X1502952Y1724763D03*
X1510826Y1728700D03*
X1502952Y1734212D03*
X1526574Y1672007D03*
X1518700Y1705866D03*
X1526574Y1709803D03*
X1518700Y1710590D03*
X1526574Y1714527D03*
X1518700Y1720039D03*
X1526574Y1723976D03*
X1518700Y1724763D03*
X1526574Y1728700D03*
X1518700Y1734212D03*
X1542322Y1672007D03*
X1534448Y1705866D03*
X1542322Y1709803D03*
X1534448Y1710590D03*
X1542322Y1714527D03*
X1534448Y1720039D03*
X1542322Y1723976D03*
X1534448Y1724763D03*
X1542322Y1728700D03*
X1534448Y1734212D03*
X1558070Y1672007D03*
X1550196Y1705866D03*
X1558070Y1709803D03*
X1550196Y1710590D03*
X1558070Y1714527D03*
X1550196Y1720039D03*
X1558070Y1723976D03*
X1550196Y1724763D03*
X1558070Y1728700D03*
X1550196Y1734212D03*
X1569882Y1705866D03*
Y1710590D03*
Y1720039D03*
Y1724763D03*
Y1734212D03*
X1577756Y1672007D03*
X1585630Y1705866D03*
Y1710590D03*
X1577756Y1709803D03*
Y1714527D03*
X1585630Y1720039D03*
Y1724763D03*
X1577756Y1723976D03*
Y1728700D03*
X1585630Y1734212D03*
X1593504Y1672007D03*
Y1709803D03*
Y1714527D03*
X1601378Y1705866D03*
Y1710590D03*
X1593504Y1723976D03*
Y1728700D03*
X1601378Y1720039D03*
Y1724763D03*
Y1734212D03*
X1609252Y1672007D03*
X1617126Y1705866D03*
Y1710590D03*
X1609252Y1709803D03*
Y1714527D03*
X1617126Y1720039D03*
Y1724763D03*
X1609252Y1723976D03*
Y1728700D03*
X1617126Y1734212D03*
X1625000Y1672007D03*
Y1709803D03*
Y1714527D03*
Y1723976D03*
Y1728700D03*
G54D75*
X1859986Y1403418D03*
X1859706Y1709011D03*
X1871790Y476573D03*
X1861790D03*
X1870648Y783729D03*
X1860648D03*
X1862295Y850767D03*
X1872295D03*
X1871790Y1158071D03*
X1861790D03*
X1869986Y1403418D03*
X1869706Y1709011D03*
X1881862Y107291D03*
X1882340Y410829D03*
X1882711Y476864D03*
X1882240Y783474D03*
X1883273Y850816D03*
X1882579Y1158348D03*
X1881223Y1404467D03*
X1881177Y1709323D03*
X1891862Y107291D03*
X1892340Y410829D03*
X1892711Y476864D03*
X1892240Y783474D03*
X1893273Y850816D03*
X1892579Y1158348D03*
X1891223Y1404467D03*
X1891177Y1709323D03*
X2082012Y108312D03*
X2072012D03*
X2071128Y410829D03*
X2081128D03*
G54D13*
X27559Y87795D03*
X40708Y631889D03*
Y1368908D03*
X51180Y1714961D03*
X373622Y87795D03*
X395671Y1714960D03*
X661024Y631890D03*
X707677Y1714960D03*
X800787Y87795D03*
X931693Y757874D03*
X931692Y1072835D03*
X931693Y1387795D03*
X1045866Y87795D03*
X1155709Y1714961D03*
X1271260Y631890D03*
X1461806Y1714961D03*
X1499606Y87795D03*
X1806298Y1714961D03*
X1829921Y87795D03*
X1816772Y631889D03*
Y1368897D03*
G54D37*
X277098Y185236D03*
X395208D03*
G54D65*
X1183858Y217205D03*
X1173858D03*
X1193858D03*
G54D47*
X443467Y594259D03*
X1425533Y601230D03*
G54D16*
X27048Y1533228D03*
X79590Y1369350D03*
X137284Y1533228D03*
X215418Y658055D03*
X276440Y1357539D03*
X420125Y656008D03*
X443764Y1339823D03*
X523173Y578174D03*
X681440Y1385138D03*
X791678D03*
X873622Y1145275D03*
X983858D03*
X1052960Y1369350D03*
X1249812Y1357539D03*
X1370284Y582303D03*
X1417134Y1339823D03*
X1533552Y682342D03*
X1629732Y1383523D03*
X1664890Y642972D03*
X1714330Y1570984D03*
X1739968Y1383527D03*
X1761575Y159134D03*
X1824566Y1570988D03*
X1838150Y201929D03*
G54D52*
X757184Y1702772D03*
X1072863Y1409176D03*
X1080970Y1640958D03*
G54D66*
X1225530Y60384D03*
G54D69*
X1278148Y1719251D03*
G54D74*
X1835198Y1601502D03*
G54D78*
X1864986Y1390234D03*
X1886862Y94107D03*
X1887711Y463680D03*
X1888273Y837632D03*
G54D76*
X1866790Y463389D03*
X1867295Y837583D03*
X1886223Y1391283D03*
X2077012Y95128D03*
G54D39*
X303154Y879624D03*
Y886002D03*
X305004Y882813D03*
X303154Y892380D03*
Y898758D03*
X310555Y873246D03*
X317957Y879624D03*
X310555D03*
X319807Y876435D03*
X314256Y873246D03*
X310555Y886002D03*
X314256D03*
X316107Y882813D03*
Y889191D03*
X308705D03*
X319807Y882813D03*
X314256Y892380D03*
X308705Y895569D03*
Y882813D03*
X314256Y898758D03*
X316107Y901947D03*
X308705D03*
Y908325D03*
X314256Y911513D03*
X316107Y908325D03*
X314256Y917891D03*
X308705Y914702D03*
Y921080D03*
X316107D03*
Y940214D03*
X308705Y927458D03*
X316107D03*
X308705Y933836D03*
X314256Y930647D03*
Y937025D03*
X308705Y940214D03*
X314256Y949781D03*
X316107Y946592D03*
X308705D03*
Y952970D03*
X314256Y956159D03*
X316107Y959348D03*
X308705D03*
Y965726D03*
X316107D03*
X314256Y968915D03*
X317957Y981671D03*
X308705Y978482D03*
X316107D03*
X314256Y975293D03*
X308705Y972104D03*
X316107Y984860D03*
X308705D03*
X312406D03*
X319807D03*
X308705Y991238D03*
X310555Y988049D03*
X314256D03*
X316107Y997616D03*
X308705D03*
X314256Y994427D03*
X316107Y1003994D03*
X314256Y1007183D03*
X316107Y1010372D03*
X308705D03*
Y1003994D03*
X327209Y876435D03*
X332760Y879624D03*
X325358D03*
X334598Y872066D03*
X334610Y882813D03*
X321658Y886002D03*
X325358D03*
X330910Y882813D03*
X329059Y886002D03*
X334610Y889191D03*
X327209D03*
X334610Y895569D03*
X321658Y892380D03*
X327209Y895569D03*
X329059Y892380D03*
X334610Y901947D03*
X321658Y898758D03*
X327209Y901947D03*
X329059Y898758D03*
X321658Y905135D03*
Y911513D03*
X329059Y905135D03*
Y911513D03*
X327209Y908325D03*
X334610Y908324D03*
Y914702D03*
X321658Y917891D03*
X327209Y914702D03*
X329059Y917891D03*
X334610Y921080D03*
X321658Y924269D03*
X329059D03*
X327209Y921080D03*
X334610Y927458D03*
Y933836D03*
X321658Y930647D03*
X327209Y927458D03*
Y933836D03*
X329059Y930647D03*
X334610Y940214D03*
X321658Y937025D03*
X327209Y940214D03*
X329059Y937025D03*
Y956159D03*
X334610Y946592D03*
X321658Y943403D03*
Y949781D03*
X329059Y943403D03*
Y949781D03*
X327209Y946592D03*
X334610Y952970D03*
X321658Y956159D03*
X327209Y952970D03*
X334610Y959348D03*
Y965726D03*
X329059Y962537D03*
X327209Y965726D03*
X321658Y962537D03*
X327209Y959348D03*
X321658Y968915D03*
X329059D03*
X334610Y972104D03*
Y978482D03*
X321658Y975293D03*
Y981671D03*
X329059Y975293D03*
X327209Y972104D03*
X332760Y981671D03*
X329059D03*
X327209Y978482D03*
X334610Y984860D03*
X327209D03*
X330910D03*
X334610Y991238D03*
Y997616D03*
X321658Y988049D03*
Y994427D03*
X327209Y991238D03*
X329059Y988049D03*
Y994427D03*
X327209Y997616D03*
X321658Y1000805D03*
X329059D03*
X334610Y1003994D03*
Y1010372D03*
X321658Y1007183D03*
X327209Y1010372D03*
X329059Y1007183D03*
X327209Y1003994D03*
X343862Y879624D03*
X340162Y879568D03*
X345713Y882813D03*
X336461Y886002D03*
X340162D03*
X347563D03*
X342012Y882813D03*
X347563Y892380D03*
X342012Y889191D03*
X340162Y892380D03*
X347563Y898758D03*
Y905135D03*
Y911513D03*
X342012Y901947D03*
X340162Y898758D03*
Y911513D03*
X342012Y908325D03*
X347563Y917891D03*
Y924269D03*
X340162Y917891D03*
X342012Y921080D03*
X347563Y930647D03*
Y937025D03*
X342012Y927458D03*
X340162Y930647D03*
X342012Y940214D03*
X340162Y937025D03*
X347563Y943403D03*
Y949781D03*
Y956159D03*
X340162Y949781D03*
X342012Y946592D03*
X340162Y956159D03*
X347563Y962537D03*
Y968915D03*
X342012Y959348D03*
Y965726D03*
X340162Y968915D03*
X347563Y975293D03*
Y981671D03*
X345713Y984860D03*
X340162Y975293D03*
X343862Y981671D03*
X342012Y978482D03*
Y984860D03*
X347563Y988049D03*
Y994427D03*
Y1000805D03*
X340162Y988049D03*
X342012Y997616D03*
X340162Y994427D03*
X347563Y1007183D03*
X342012Y1010372D03*
X340162Y1007183D03*
X342012Y1003994D03*
X351265Y879568D03*
X360516Y876435D03*
X354965Y879624D03*
X356803Y872066D03*
X351264Y886002D03*
X362366D03*
X356815Y882813D03*
X360516D03*
X353114D03*
X354965Y886002D03*
Y892380D03*
X360516Y889191D03*
Y895569D03*
X353114Y889191D03*
Y895569D03*
X354965Y898758D03*
X360516Y901947D03*
X353114D03*
X354965Y911513D03*
Y905135D03*
X360516Y908325D03*
X353114Y908324D03*
X354965Y917891D03*
X360516Y914702D03*
X353114D03*
X354965Y924269D03*
X360516Y921080D03*
X353114D03*
X354965Y930647D03*
X360516Y927458D03*
Y933836D03*
X353114D03*
Y927458D03*
X354965Y937025D03*
X360516Y940214D03*
X353114D03*
X360516Y946592D03*
X353114D03*
X360516Y952970D03*
X353114D03*
X354965Y956159D03*
Y943403D03*
Y949781D03*
X360516Y959348D03*
Y965726D03*
X353114Y959348D03*
Y965726D03*
X354965Y962537D03*
Y968915D03*
Y975293D03*
Y981671D03*
X360516Y972104D03*
Y978482D03*
X358665Y981671D03*
X353114Y972104D03*
Y978482D03*
X360516Y984860D03*
X356815D03*
X353114D03*
X360516Y997616D03*
Y991238D03*
X353114D03*
Y997616D03*
X354965Y988049D03*
Y994427D03*
Y1000805D03*
Y1007183D03*
X360516Y1003994D03*
X353114D03*
X360516Y1010372D03*
X353114D03*
X369768Y879624D03*
X373469D03*
X375319Y876435D03*
X377169Y879624D03*
X366067Y886002D03*
Y892380D03*
X367917Y889191D03*
X373469Y892380D03*
X367917Y882813D03*
X373469Y886002D03*
X379020Y882813D03*
X377169Y886002D03*
X379020Y895569D03*
X366067Y898758D03*
Y911513D03*
X367917Y901947D03*
X373469Y898758D03*
X379020Y908325D03*
X373469Y911513D03*
Y905135D03*
X367917Y908324D03*
X366067Y917891D03*
X373469D03*
X367917Y921080D03*
X373469Y924269D03*
X379020Y921080D03*
X366067Y930647D03*
Y937025D03*
X367917Y927458D03*
X379020Y933836D03*
X373469Y930647D03*
X367917Y940214D03*
X373469Y937025D03*
X379020Y940214D03*
X366067Y949781D03*
Y956159D03*
X367917Y946592D03*
X373469Y943403D03*
Y949781D03*
Y956159D03*
X379020Y952970D03*
X366067Y968915D03*
X367917Y959348D03*
Y965726D03*
X373469Y962537D03*
Y968915D03*
X379020Y965726D03*
X366067Y975293D03*
X369768Y981671D03*
X367917Y978482D03*
X373469Y975293D03*
Y981671D03*
X367917Y984860D03*
X379020D03*
X371618D03*
X379020Y978482D03*
X366067Y994427D03*
Y988049D03*
X367917Y997616D03*
X379020Y991238D03*
X373469Y988049D03*
X379020Y997616D03*
X373469Y994427D03*
Y1000805D03*
X366067Y1007183D03*
X373469D03*
X367917Y1003994D03*
X379020D03*
X367917Y1010372D03*
X386421Y876435D03*
X388272Y879624D03*
X384571Y873246D03*
X382721Y882813D03*
Y889191D03*
X380870Y892380D03*
X384571Y886002D03*
X386421Y882813D03*
X393823D03*
X388272Y886002D03*
X390122Y882813D03*
X391973Y892380D03*
X390122Y895569D03*
X386421Y889191D03*
X393823D03*
X382721Y901947D03*
X380870Y898758D03*
Y911513D03*
Y905135D03*
X393823Y901947D03*
X391973Y898758D03*
X390122Y901947D03*
X386421D03*
X391973Y905135D03*
Y911513D03*
X390122Y908325D03*
X382721Y914702D03*
X380870Y917891D03*
Y924269D03*
X386421Y914702D03*
X391973Y917891D03*
X393823Y914702D03*
X390122D03*
Y921080D03*
X391973Y924269D03*
X382721Y927458D03*
Y933836D03*
X380870Y930647D03*
X386421Y927458D03*
Y933836D03*
X393823Y927458D03*
X390122D03*
X393823Y933836D03*
X391973Y930647D03*
X390122Y933836D03*
Y940214D03*
X382721Y946592D03*
X380870Y943403D03*
Y949781D03*
Y956159D03*
X386421Y946592D03*
X391973Y943403D03*
Y949781D03*
X393823Y946592D03*
X390122D03*
X391973Y956159D03*
X390122Y952970D03*
X382721Y959348D03*
X380870Y962537D03*
Y968915D03*
X393823Y959348D03*
X390122D03*
Y965726D03*
X386421Y959348D03*
X391973Y962537D03*
Y968915D03*
X386421Y984860D03*
X382721Y972104D03*
X380870Y975293D03*
X393823Y972104D03*
X390122D03*
Y978482D03*
X384571Y981671D03*
X391973D03*
Y975293D03*
X386421Y972104D03*
X393823Y984860D03*
X391973Y988049D03*
X384571Y994427D03*
Y988049D03*
X391973Y994427D03*
X393823Y991238D03*
X386421D03*
Y997616D03*
X391973Y1000805D03*
X384571D03*
X393823Y997616D03*
X386421Y1003994D03*
X382721Y1010372D03*
X390122D03*
X391973Y1007183D03*
X393823Y1003994D03*
X395673Y1007183D03*
X384571D03*
X410477Y873246D03*
X397524Y876435D03*
X399374Y873246D03*
Y879624D03*
X397524Y882813D03*
Y889191D03*
X401225Y882813D03*
X408626D03*
X404925D03*
X401225Y895569D03*
X408626Y889191D03*
X404925D03*
X403075Y892380D03*
X397524Y901947D03*
X401225D03*
X408626D03*
X404925D03*
X403075Y898758D03*
Y905135D03*
Y911513D03*
X401225Y908324D03*
X397524Y914702D03*
X401225D03*
X408626D03*
X403075Y917891D03*
X404925Y914702D03*
X401225Y921080D03*
X403075Y924269D03*
X401225Y933836D03*
X408626Y927458D03*
X404925D03*
X403075Y930647D03*
X401225Y940214D03*
X397524Y927458D03*
Y933836D03*
X401225Y927458D03*
X397524Y946592D03*
X401225D03*
X403075Y943403D03*
X408626Y946592D03*
X403075Y949781D03*
X404925Y946592D03*
X401225Y952970D03*
X403075Y956159D03*
X397524Y959348D03*
X401225Y965726D03*
Y959348D03*
X408626D03*
X404925D03*
X403075Y962537D03*
Y968915D03*
X397524Y972104D03*
X401225D03*
X408626D03*
X404925D03*
X399374Y981671D03*
X406776D03*
X401225Y978482D03*
X403075Y975293D03*
X401225Y984860D03*
X408626D03*
Y991238D03*
X399374Y988049D03*
Y994427D03*
X406776Y988049D03*
X401225Y991238D03*
Y997616D03*
X399374Y1000805D03*
X397524Y1010372D03*
X399374Y1007183D03*
X401225Y1003994D03*
X421579Y873246D03*
X412327Y882813D03*
Y895569D03*
X414177Y892380D03*
X419729Y882813D03*
X416028D03*
X423429Y895569D03*
X425280Y892380D03*
X416028Y889191D03*
X419729D03*
X412327Y901947D03*
X414177Y898758D03*
Y905135D03*
Y911513D03*
X412327Y908325D03*
X423429Y901947D03*
X425280Y898758D03*
X419729Y901947D03*
X416028D03*
X425280Y905135D03*
Y911513D03*
X423429Y908324D03*
X414177Y917891D03*
X412327Y914702D03*
X414177Y924269D03*
X412327Y921080D03*
X423429Y914702D03*
X419729D03*
X416028D03*
X425280Y917891D03*
Y924269D03*
X423429Y921080D03*
X412327Y927458D03*
Y933836D03*
X414177Y930647D03*
X412327Y940214D03*
X414177Y937025D03*
X423429Y927458D03*
X419729D03*
X423429Y933836D03*
X425280Y930647D03*
X419729Y933836D03*
X416028Y927458D03*
Y933836D03*
X425280Y937025D03*
X423429Y940214D03*
X414177Y949781D03*
X412327Y946592D03*
X414177Y943403D03*
X412327Y952970D03*
X414177Y956159D03*
X416028Y946592D03*
X425280Y943403D03*
Y949781D03*
X423429Y946592D03*
X419729D03*
X423429Y952970D03*
X425280Y956159D03*
X412327Y965726D03*
Y959348D03*
X414177Y962537D03*
Y968915D03*
X423429Y965726D03*
X416028Y959348D03*
X423429D03*
X419729D03*
X425280Y962537D03*
Y968915D03*
X416028Y972104D03*
X423429D03*
X419729D03*
X416028Y984860D03*
X423429D03*
X412327Y978482D03*
X414177Y981671D03*
Y975293D03*
X412327Y972104D03*
X423429Y978482D03*
X421579Y981671D03*
X425280Y975293D03*
X414177Y988049D03*
X421579D03*
X423429Y991238D03*
X416028D03*
X434532Y876435D03*
X432681Y879624D03*
X430831Y882813D03*
X427130D03*
X430831Y889191D03*
X427130D03*
X434532Y895569D03*
Y889191D03*
X428981Y905135D03*
X434532Y901947D03*
X432681Y905135D03*
X434532Y908325D03*
X428981Y917891D03*
X432681D03*
X434532Y914702D03*
Y921080D03*
X428981Y930647D03*
Y937025D03*
X432681Y930647D03*
X434532Y927458D03*
Y933836D03*
X432681Y937025D03*
X434532Y940214D03*
X428981Y949781D03*
X432681D03*
X434532Y946592D03*
Y952970D03*
X428981Y962537D03*
X432681D03*
X434532Y959348D03*
Y965726D03*
X428981Y981671D03*
Y975293D03*
X430831Y984860D03*
X434532Y972104D03*
X432681Y975293D03*
X434532Y978482D03*
X430831Y991238D03*
X428981Y988049D03*
X445609Y876435D03*
X447460Y879624D03*
X445609Y882813D03*
Y889191D03*
Y895569D03*
X453011Y882813D03*
X449310Y889191D03*
X453011D03*
X454861Y892380D03*
X445609Y901947D03*
Y908325D03*
X454861Y898758D03*
X451160Y905135D03*
X454861D03*
Y911513D03*
X447460Y905135D03*
X445609Y914702D03*
Y921080D03*
X447460Y917891D03*
X451160D03*
X454861D03*
Y924269D03*
Y930647D03*
X447460Y937025D03*
X451160D03*
X454861D03*
X445609Y927458D03*
Y933836D03*
Y940214D03*
X447460Y930647D03*
X451160D03*
X445609Y946592D03*
Y952970D03*
X447460Y949781D03*
X454861Y943403D03*
X451160Y949781D03*
X454861D03*
Y956159D03*
X445609Y959348D03*
Y965726D03*
X454861Y962537D03*
X451160D03*
X447460D03*
X454861Y968915D03*
X445609Y972104D03*
Y978482D03*
Y984860D03*
X447460Y981671D03*
X454861D03*
X451160Y975293D03*
X447460D03*
X454861D03*
X453011Y984860D03*
X445609Y991238D03*
X453011D03*
X454861Y988049D03*
X447460D03*
X460412Y876435D03*
X469664Y879624D03*
X460412Y889191D03*
X456712Y895569D03*
X467814Y882813D03*
X465964Y892380D03*
X467814Y895569D03*
X464113Y889191D03*
X456712Y908324D03*
X465964Y911513D03*
X456712Y901947D03*
X460412D03*
X465964Y898758D03*
X467814Y901947D03*
X464113D03*
X467814Y908325D03*
X465964Y905135D03*
X460412Y914702D03*
X456712D03*
Y921080D03*
X467814Y914702D03*
X464113D03*
X465964Y917891D03*
X467814Y921080D03*
X465964Y924269D03*
X460412Y927458D03*
X456712D03*
Y933836D03*
X460412D03*
X456712Y940214D03*
X467814Y927458D03*
Y933836D03*
X464113Y927458D03*
Y933836D03*
X467814Y940214D03*
X465964Y937025D03*
X460412Y946592D03*
X456712D03*
Y952970D03*
X467814Y946592D03*
X464113D03*
X465964Y943403D03*
Y949781D03*
X467814Y952970D03*
X465964Y956159D03*
X456712Y965726D03*
X460412Y959348D03*
X456712D03*
X467814Y965726D03*
Y959348D03*
X465964Y962537D03*
X464113Y959348D03*
X465964Y968915D03*
X456712Y972104D03*
Y978482D03*
X462263Y981671D03*
X460412Y972104D03*
Y984860D03*
X469664Y981671D03*
X467814Y978482D03*
Y972104D03*
X465964Y975293D03*
X464113Y972104D03*
X467814Y984860D03*
X460412Y991238D03*
X462263Y988049D03*
X469664D03*
X467814Y991238D03*
X471515Y876435D03*
X480767Y873246D03*
Y879624D03*
X482617Y876435D03*
X478916Y882813D03*
X475215D03*
X471515D03*
X478916Y895569D03*
X477066Y892380D03*
X475215Y889191D03*
X471515D03*
X482617Y882813D03*
Y889191D03*
X478916Y901947D03*
X471515D03*
X475215D03*
X477066Y898758D03*
X478916Y908325D03*
X477066Y905135D03*
Y911513D03*
X482617Y901947D03*
X478916Y914702D03*
X477066Y917891D03*
X475215Y914702D03*
X471515D03*
X478916Y921080D03*
X477066Y924269D03*
X482617Y914702D03*
X478916Y927458D03*
Y933836D03*
X475215Y927458D03*
X471515D03*
X477066Y930647D03*
X478916Y940214D03*
X482617Y927458D03*
Y933836D03*
X478916Y946592D03*
X477066Y943403D03*
X475215Y946592D03*
X471515D03*
X477066Y949781D03*
X478916Y952970D03*
X477066Y956159D03*
X482617Y946592D03*
X478916Y965726D03*
Y959348D03*
X475215D03*
X471515D03*
X477066Y962537D03*
Y968915D03*
X482617Y959348D03*
X478916Y978482D03*
Y972104D03*
X477066Y981671D03*
Y975293D03*
X475215Y972104D03*
X471515D03*
X475215Y984860D03*
X484467Y981671D03*
X482617Y972104D03*
Y984860D03*
X477066Y994427D03*
X475215Y991238D03*
X477066Y988049D03*
Y1000805D03*
X484467Y994427D03*
Y988049D03*
X482617Y991238D03*
Y997616D03*
X484467Y1000805D03*
X477066Y1007183D03*
X484467D03*
X482617Y1010372D03*
Y1003994D03*
X493719Y876435D03*
X491869Y879624D03*
X493719Y882813D03*
X490019D03*
X486318D03*
X493719Y889191D03*
X486318D03*
X490019Y895569D03*
X488168Y892380D03*
X497420Y889191D03*
X499271Y892380D03*
X493719Y901947D03*
X486318D03*
X490019D03*
X488168Y898758D03*
Y905135D03*
Y911513D03*
X497420Y901947D03*
X499271Y898758D03*
Y905135D03*
Y911513D03*
X490019Y908324D03*
X493719Y914702D03*
X488168Y917891D03*
X490019Y914702D03*
X486318D03*
X490019Y921080D03*
X488168Y924269D03*
X499271Y917891D03*
X497420Y914702D03*
X499271Y924269D03*
X493719Y927458D03*
X486318D03*
X490019D03*
X493719Y933836D03*
X490019D03*
X486318D03*
X488168Y930647D03*
X490019Y940214D03*
X497420Y927458D03*
Y933836D03*
X499271Y930647D03*
X488168Y943403D03*
X493719Y946592D03*
X490019D03*
X486318D03*
X488168Y949781D03*
X490019Y952970D03*
X488168Y956159D03*
X497420Y946592D03*
X499271Y943403D03*
Y949781D03*
Y956159D03*
X490019Y965726D03*
X493719Y959348D03*
X490019D03*
X486318D03*
X488168Y962537D03*
Y968915D03*
X499271Y962537D03*
X497420Y959348D03*
X499271Y968915D03*
X491869Y981671D03*
X490019Y978482D03*
X493719Y972104D03*
X488168Y975293D03*
X490019Y972104D03*
X486318D03*
X490019Y984860D03*
X497420Y972104D03*
X499271Y975293D03*
Y981671D03*
X497420Y984860D03*
X491869Y994427D03*
Y988049D03*
X490019Y997616D03*
Y991238D03*
X491869Y1000805D03*
X497420Y991238D03*
Y997616D03*
X499271Y988049D03*
Y994427D03*
Y1000805D03*
X491869Y1007183D03*
X490019Y1010372D03*
Y1003994D03*
X497420Y1010372D03*
Y1003994D03*
X499271Y1007183D03*
X502971Y879624D03*
X501133Y872118D03*
X508523Y882813D03*
X506672Y886002D03*
X502971D03*
X504822Y882813D03*
X506672Y892380D03*
X501121Y895569D03*
X512223Y882813D03*
X514074Y886002D03*
X512223Y889191D03*
X514074Y892380D03*
X506672Y898758D03*
Y905135D03*
Y911513D03*
X501121Y908325D03*
X512223Y901947D03*
X514074Y898758D03*
Y911513D03*
X512223Y908325D03*
X506672Y917891D03*
X501121Y921080D03*
X506672Y924269D03*
X514074Y917891D03*
X512223Y921080D03*
X506672Y930647D03*
X501121Y933836D03*
X506672Y937025D03*
X501121Y940214D03*
X512223Y927458D03*
X514074Y930647D03*
X512223Y940214D03*
X514074Y937025D03*
X506672Y943403D03*
Y949781D03*
X501121Y952970D03*
X506672Y956159D03*
X514074Y949781D03*
X512223Y946592D03*
X514074Y956159D03*
X506672Y962537D03*
X501121Y965726D03*
X506672Y968915D03*
X512223Y959348D03*
Y965726D03*
X514074Y968915D03*
X510373Y981671D03*
X506672Y975293D03*
Y981671D03*
X501121Y978482D03*
X508523Y984860D03*
X514074Y975293D03*
X512223Y978482D03*
Y984860D03*
X506672Y988049D03*
Y994427D03*
Y1000805D03*
X514074Y988049D03*
Y994427D03*
X512223Y997616D03*
X506672Y1007183D03*
X514074D03*
X512223Y1003994D03*
X525176Y879624D03*
X515924Y876435D03*
X525176Y873246D03*
Y886002D03*
X523326Y882813D03*
X517775Y886002D03*
X519625Y882813D03*
X527027Y895569D03*
Y889191D03*
X525176Y892380D03*
X519625Y889191D03*
Y895569D03*
X528877Y886002D03*
X527027Y901947D03*
X525176Y898758D03*
X519625Y901947D03*
X525176Y905135D03*
Y911513D03*
X519625Y908325D03*
X527027Y908324D03*
X525176Y917891D03*
X519625Y914702D03*
X527027D03*
Y921080D03*
X525176Y924269D03*
X519625Y921080D03*
X525176Y937025D03*
X527027Y927458D03*
Y933836D03*
X525176Y930647D03*
X519625Y927458D03*
Y933836D03*
X527027Y940214D03*
X519625D03*
X527027Y946592D03*
X519625D03*
X525176Y943403D03*
Y949781D03*
X527027Y952970D03*
X525176Y956159D03*
X519625Y952970D03*
X527027Y959348D03*
Y965726D03*
X525176Y962537D03*
X519625Y959348D03*
Y965726D03*
X525176Y968915D03*
X521475Y981671D03*
X519625Y978482D03*
X527027Y984860D03*
X523326D03*
X519625D03*
X527027Y972104D03*
Y978482D03*
X525176Y975293D03*
Y981671D03*
X519625Y972104D03*
X527027Y991238D03*
Y997616D03*
X525176Y988049D03*
Y994427D03*
X519625Y991238D03*
Y997616D03*
X525176Y1000805D03*
X527027Y1010372D03*
Y1003994D03*
X525176Y1007183D03*
X519625Y1010372D03*
Y1003994D03*
X534428Y876435D03*
X539979Y879624D03*
X532578D03*
X541830Y876435D03*
X543680Y879624D03*
X538129Y889191D03*
X539979Y892380D03*
X532578D03*
X543680Y886002D03*
X538129Y882813D03*
X532578Y886002D03*
X534428Y882813D03*
X538129Y901947D03*
X539979Y898758D03*
X532578D03*
X539979Y911513D03*
X538129Y908325D03*
X532578Y905135D03*
Y911513D03*
X539979Y917891D03*
X532578D03*
X538129Y921080D03*
X532578Y924269D03*
X538129Y927458D03*
X539979Y930647D03*
X532578D03*
X539979Y937025D03*
X538129Y940214D03*
X532578Y937025D03*
X539979Y949781D03*
X538129Y946592D03*
X532578Y943403D03*
Y949781D03*
X539979Y956159D03*
X532578D03*
X538129Y959348D03*
Y965726D03*
X532578Y962537D03*
X539979Y968915D03*
X532578D03*
X539979Y975293D03*
X532578D03*
X538129Y978482D03*
X536279Y981671D03*
X532578D03*
X538129Y984860D03*
X534428D03*
X532578Y994427D03*
X539979Y988049D03*
X532578D03*
X539979Y994427D03*
X538129Y997616D03*
X532578Y1000805D03*
X539978Y1007184D03*
X538129Y1003994D03*
X532578Y1007183D03*
X545531Y876435D03*
X552932D03*
X556633D03*
X551082Y879624D03*
X545543Y872085D03*
X554783Y886002D03*
X549231Y882813D03*
X558483Y892380D03*
X545531Y889191D03*
Y895569D03*
X552932Y889191D03*
X551082Y892380D03*
X552932Y895569D03*
X558483Y886002D03*
X545531Y882813D03*
X551082Y886002D03*
X558483Y898758D03*
X545531Y901947D03*
X552932D03*
X551082Y898758D03*
X558483Y905135D03*
Y911513D03*
X551082Y905135D03*
Y911513D03*
X552932Y908325D03*
X545531Y908324D03*
X558483Y917891D03*
X551082D03*
X552932Y914702D03*
X545531D03*
X558483Y924269D03*
X551082D03*
X552932Y921080D03*
X545531D03*
X558483Y930647D03*
X545531Y927458D03*
Y933836D03*
X552932Y927458D03*
Y933836D03*
X551082Y930647D03*
X558483Y937025D03*
X545531Y940214D03*
X551082Y937025D03*
X552932Y940214D03*
X558483Y943403D03*
Y949781D03*
X545531Y946592D03*
X551082Y943403D03*
Y949781D03*
X552932Y946592D03*
X558483Y956159D03*
X545531Y952970D03*
X552932D03*
X551082Y956159D03*
X558483Y962537D03*
X545531Y959348D03*
Y965726D03*
X552932Y959348D03*
X551082Y962537D03*
X552932Y965726D03*
X558483Y968915D03*
X551082D03*
X558483Y975293D03*
Y981671D03*
X545531Y972104D03*
Y978482D03*
X547381Y981671D03*
X551082Y975293D03*
X552932Y972104D03*
X551082Y981671D03*
X552932Y978482D03*
Y984860D03*
X549231D03*
X545531D03*
X558483Y988049D03*
Y994427D03*
X552932Y991238D03*
X551082Y994427D03*
X552932Y997616D03*
X545531Y991238D03*
Y997616D03*
X551082Y988049D03*
X558483Y1000805D03*
X551082D03*
X558483Y1007183D03*
X545531Y1010372D03*
Y1003994D03*
X552932Y1010372D03*
X551082Y1007183D03*
X552932Y1003994D03*
X562184Y879624D03*
X569586Y873246D03*
X560334Y882813D03*
X564034D03*
X569586Y886002D03*
X571436Y882813D03*
Y889191D03*
X564034D03*
X565885Y892380D03*
X571436Y895569D03*
X564034Y901947D03*
X571436D03*
X565885Y898758D03*
X564034Y908325D03*
X571436D03*
X565885Y911513D03*
Y917891D03*
X571436Y914702D03*
X564034Y921080D03*
X571436D03*
X564034Y927458D03*
X571436D03*
X565885Y930647D03*
X571436Y933836D03*
X565885Y937025D03*
X564034Y940214D03*
X571436D03*
X565885Y949781D03*
X564034Y946592D03*
X571436D03*
Y952970D03*
X565885Y956159D03*
X564034Y959348D03*
X571436D03*
X564034Y965726D03*
X571436D03*
X565885Y968915D03*
X562184Y981671D03*
X565885Y975293D03*
X571436Y972104D03*
X564034Y978482D03*
X571436D03*
X567735Y984860D03*
X560334D03*
X564034D03*
X571436D03*
X569586Y988049D03*
X571436Y991238D03*
X565885Y994427D03*
X564034Y997616D03*
X571436D03*
X565885Y988049D03*
X571436Y1010372D03*
X565885Y1007183D03*
X564034Y1003994D03*
X571436D03*
X576987Y879624D03*
X575137Y882813D03*
X576987Y886002D03*
Y892380D03*
Y898758D03*
X1286697Y873245D03*
Y879623D03*
X1279296D03*
X1284847Y895568D03*
Y882812D03*
X1286697Y886001D03*
X1281146Y882812D03*
X1279296Y886001D03*
X1284847Y889190D03*
X1279296Y892379D03*
X1284847Y901946D03*
X1279296Y898757D03*
X1284847Y908324D03*
Y914701D03*
Y921079D03*
Y927457D03*
Y933835D03*
Y940213D03*
Y946591D03*
Y952969D03*
Y959347D03*
Y965725D03*
Y972103D03*
Y978481D03*
Y984859D03*
X1288548D03*
X1284847Y991237D03*
X1286697Y988048D03*
X1284847Y997615D03*
Y1010371D03*
Y1003993D03*
X1290398Y873245D03*
X1301500Y879623D03*
X1303351Y876434D03*
X1294099Y879623D03*
X1295949Y876434D03*
X1303351Y895568D03*
X1290398Y886001D03*
Y892379D03*
X1292249Y882812D03*
X1297800Y886001D03*
X1301500D03*
X1295949Y882812D03*
X1292249Y889190D03*
X1303351D03*
X1297800Y892379D03*
X1290398Y898757D03*
Y911512D03*
X1292249Y901946D03*
X1297800Y898757D03*
X1303351Y901946D03*
X1292249Y908324D03*
X1297800Y905134D03*
Y911512D03*
X1303351Y908324D03*
X1290398Y917890D03*
X1297800D03*
X1303351Y914701D03*
Y921079D03*
X1297800Y924268D03*
X1292249Y921079D03*
X1297800Y930646D03*
X1303351Y927457D03*
Y933835D03*
X1292249Y927457D03*
X1303351Y940213D03*
X1297800Y937024D03*
X1292249Y940213D03*
X1290398Y930646D03*
Y937024D03*
Y949780D03*
Y956158D03*
X1297800Y949780D03*
X1303351Y946591D03*
X1292249D03*
X1297800Y943402D03*
X1303351Y952969D03*
X1297800Y956158D03*
X1290398Y968914D03*
X1297800Y962536D03*
X1303351Y959347D03*
Y965725D03*
X1292249Y959347D03*
Y965725D03*
X1297800Y968914D03*
X1290398Y975292D03*
X1297800Y981670D03*
Y975292D03*
X1303351Y972103D03*
Y978481D03*
X1294099Y981670D03*
X1292249Y978481D03*
X1303351Y984859D03*
X1295949D03*
X1292249D03*
X1290398Y988048D03*
Y994426D03*
X1297800D03*
Y988048D03*
X1303351Y991237D03*
Y997615D03*
X1292249D03*
X1297800Y1000804D03*
X1290398Y1007182D03*
X1292249Y1010371D03*
X1297800Y1007182D03*
X1303351Y1010371D03*
Y1003993D03*
X1292249D03*
X1314453Y876434D03*
X1308902Y873245D03*
Y879623D03*
X1310752Y895568D03*
X1307052Y882812D03*
X1305201Y886001D03*
Y892379D03*
X1310752Y882812D03*
X1312603Y886001D03*
X1316304D03*
X1318154Y882812D03*
X1310752Y889190D03*
X1318154D03*
X1316304Y892379D03*
X1305201Y898757D03*
Y905134D03*
Y911512D03*
X1310752Y901946D03*
X1318154D03*
X1316304Y898757D03*
Y911512D03*
X1318154Y908324D03*
X1310752Y908323D03*
X1305201Y917890D03*
Y924268D03*
X1310752Y914701D03*
X1316304Y917890D03*
X1318154Y921079D03*
X1310752D03*
X1305201Y930646D03*
Y937024D03*
X1310752Y927457D03*
Y933835D03*
X1318154Y927457D03*
X1316304Y930646D03*
Y937024D03*
X1310752Y940213D03*
X1318154D03*
X1305201Y943402D03*
Y949780D03*
Y956158D03*
X1310752Y946591D03*
X1316304Y949780D03*
X1318154Y946591D03*
X1310752Y952969D03*
X1316304Y956158D03*
X1318154Y959347D03*
Y965725D03*
X1316304Y968914D03*
X1305201Y962536D03*
Y968914D03*
X1310752Y959347D03*
Y965725D03*
X1305201Y975292D03*
Y981670D03*
X1307052Y984859D03*
X1310752Y972103D03*
Y978481D03*
X1316304Y975292D03*
X1318154Y978481D03*
X1308902Y981670D03*
X1310752Y984859D03*
X1318154D03*
X1305201Y988048D03*
Y994426D03*
Y1000804D03*
X1310752Y991237D03*
Y997615D03*
X1316304Y988048D03*
X1318154Y997615D03*
X1316304Y994426D03*
X1305201Y1007182D03*
X1310752Y1003993D03*
Y1010371D03*
X1318154D03*
X1316304Y1007182D03*
X1318154Y1003993D03*
X1320004Y879623D03*
X1331107Y873245D03*
X1325556Y876434D03*
X1331107Y879623D03*
X1321855Y882812D03*
X1323705Y886001D03*
X1329256Y882812D03*
X1332957D03*
X1331107Y886001D03*
X1327406D03*
X1323705Y892379D03*
X1329256Y889190D03*
X1331107Y892379D03*
X1329256Y895568D03*
X1323705Y898757D03*
X1331107D03*
X1329256Y901946D03*
X1331107Y911512D03*
X1323705D03*
Y905134D03*
X1331107D03*
X1329256Y908323D03*
Y914701D03*
X1323705Y917890D03*
X1331107D03*
X1323705Y924268D03*
X1329256Y921079D03*
X1331107Y924268D03*
Y930646D03*
X1329256Y933835D03*
X1323705Y930646D03*
X1329256Y927457D03*
X1331107Y937024D03*
X1329256Y940213D03*
X1323705Y937024D03*
X1331107Y943402D03*
X1329256Y946591D03*
X1331107Y949780D03*
X1323705Y943402D03*
Y949780D03*
X1329256Y952969D03*
X1331107Y956158D03*
X1323705D03*
X1329256Y959347D03*
X1331107Y962536D03*
X1329256Y965725D03*
X1323705Y962536D03*
X1331107Y968914D03*
X1323705D03*
X1320004Y981670D03*
X1321855Y984859D03*
X1323705Y975292D03*
Y981670D03*
X1329256Y972103D03*
X1331107Y975292D03*
X1329256Y978481D03*
X1331107Y981670D03*
X1334807D03*
X1329256Y984859D03*
X1332957D03*
X1323705Y1000804D03*
Y988048D03*
Y994426D03*
X1329256Y997615D03*
X1331107Y988048D03*
X1329256Y991237D03*
X1331107Y994426D03*
Y1000804D03*
X1323705Y1007182D03*
X1329256Y1003993D03*
X1331107Y1007182D03*
X1329256Y1010371D03*
X1336658Y876434D03*
X1345910Y879623D03*
X1349611D03*
X1338508Y886001D03*
X1336658Y882812D03*
Y889190D03*
Y895568D03*
X1342209Y886001D03*
X1349611D03*
X1344059Y882812D03*
Y889190D03*
X1342209Y892379D03*
X1349611D03*
X1336658Y901946D03*
Y908324D03*
X1342209Y898757D03*
X1349611D03*
X1344059Y901946D03*
X1349611Y905134D03*
X1342209Y911512D03*
X1349611D03*
X1344059Y908323D03*
X1336658Y914701D03*
Y921079D03*
X1342209Y917890D03*
X1349611D03*
X1344059Y921079D03*
X1349611Y924268D03*
X1336658Y933835D03*
Y927457D03*
Y940213D03*
X1344059Y927457D03*
X1342209Y930646D03*
X1349611D03*
X1344059Y940213D03*
X1342209Y937024D03*
X1349611D03*
Y943402D03*
X1344059Y946591D03*
X1349611Y949780D03*
X1342209D03*
X1349611Y956158D03*
X1342209D03*
X1336658Y946591D03*
Y952969D03*
Y965725D03*
Y959347D03*
X1344059D03*
X1349611Y962536D03*
X1344059Y965725D03*
X1349611Y968914D03*
X1342209D03*
X1336658Y972103D03*
Y978481D03*
Y984859D03*
X1349611Y975292D03*
X1342209D03*
X1344059Y978481D03*
X1349611Y981670D03*
X1345910D03*
X1344059Y984859D03*
X1347760D03*
X1336658Y997615D03*
Y991237D03*
X1349611Y988048D03*
Y994426D03*
X1342209D03*
X1344059Y997615D03*
X1342209Y988048D03*
X1349611Y1000804D03*
X1336658Y1010371D03*
X1344059D03*
X1336658Y1003993D03*
X1344059D03*
X1342209Y1007182D03*
X1349611D03*
X1351461Y876434D03*
X1353311Y879623D03*
X1364414D03*
X1360713Y873245D03*
X1362563Y876434D03*
X1353311Y886001D03*
X1362563Y882812D03*
X1358863D03*
X1364414Y886001D03*
X1360713D03*
X1355162Y882812D03*
X1357012Y892379D03*
X1355162Y895568D03*
X1362563Y889190D03*
X1358863D03*
X1357012Y898757D03*
X1362563Y901946D03*
X1358863D03*
X1357012Y905134D03*
Y911512D03*
X1355162Y908324D03*
X1358863Y914701D03*
X1362563D03*
X1357012Y917890D03*
X1355162Y921079D03*
X1357012Y924268D03*
X1362563Y933835D03*
X1358863D03*
X1355162D03*
X1362563Y927457D03*
X1358863D03*
X1357012Y930646D03*
X1355162Y940213D03*
X1357012Y943402D03*
X1358863Y946591D03*
X1362563D03*
X1357012Y949780D03*
Y956158D03*
X1355162Y952969D03*
X1358863Y959347D03*
X1362563D03*
X1357012Y962536D03*
X1355162Y965725D03*
X1357012Y968914D03*
X1358863Y972103D03*
X1362563D03*
X1357012Y975292D03*
X1360713Y981670D03*
X1355162Y978481D03*
X1362563Y984859D03*
X1355162D03*
Y991237D03*
Y997615D03*
X1362563Y991237D03*
Y997615D03*
X1360713Y994426D03*
Y988048D03*
Y1000804D03*
X1358863Y1010371D03*
X1360713Y1007182D03*
X1362563Y1003993D03*
X1355162D03*
X1373666Y876434D03*
X1375516Y873245D03*
Y879623D03*
X1369965Y882812D03*
X1366264D03*
X1369965Y889190D03*
X1368115Y892379D03*
X1366264Y895568D03*
X1373666Y882812D03*
X1377367D03*
X1379217Y892379D03*
X1377367Y895568D03*
X1373666Y889190D03*
X1368115Y898757D03*
X1369965Y901946D03*
X1366264D03*
X1368115Y905134D03*
Y911512D03*
X1366264Y908324D03*
X1379217Y898757D03*
X1377367Y901946D03*
X1373666D03*
X1379217Y905134D03*
X1377367Y908324D03*
X1379217Y911512D03*
X1369965Y914701D03*
X1368115Y917890D03*
X1366264Y914701D03*
X1368115Y924268D03*
X1366264Y921079D03*
X1377367Y914701D03*
X1373666D03*
X1379217Y917890D03*
X1377367Y921079D03*
X1379217Y924268D03*
X1366264Y933835D03*
X1369965Y927457D03*
X1368115Y930646D03*
X1369965Y933835D03*
X1366264Y927457D03*
Y940213D03*
X1377367Y927457D03*
X1373666D03*
X1379217Y930646D03*
X1377367Y933835D03*
X1373666D03*
X1377367Y940213D03*
X1368115Y943402D03*
X1369965Y946591D03*
X1368115Y949780D03*
X1366264Y946591D03*
X1368115Y956158D03*
X1366264Y952969D03*
X1379217Y943402D03*
X1373666Y946591D03*
X1377367D03*
X1379217Y949780D03*
X1377367Y952969D03*
X1379217Y956158D03*
X1366264Y959347D03*
X1369965D03*
X1368115Y962536D03*
X1366264Y965725D03*
X1368115Y968914D03*
X1373666Y959347D03*
X1377367Y965725D03*
Y959347D03*
X1379217Y962536D03*
Y968914D03*
X1369965Y972103D03*
X1368115Y975292D03*
Y981670D03*
X1366264Y972103D03*
Y978481D03*
X1369965Y984859D03*
X1373666Y972103D03*
X1377367D03*
X1379217Y975292D03*
X1375516Y981670D03*
X1377367Y978481D03*
Y984859D03*
X1369965Y991237D03*
Y997615D03*
X1368115Y994426D03*
Y988048D03*
Y1000804D03*
X1375516Y994426D03*
X1377367Y991237D03*
Y997615D03*
X1375516Y988048D03*
Y1000804D03*
X1369965Y1003993D03*
X1368115Y1007182D03*
X1366264Y1010371D03*
X1373666D03*
X1375516Y1007182D03*
X1371815D03*
X1377367Y1003993D03*
X1386619Y879623D03*
X1382918Y873245D03*
X1384768Y876434D03*
X1394020Y873245D03*
X1384768Y882812D03*
X1381067D03*
Y889190D03*
X1384768D03*
X1392170Y882812D03*
X1388469D03*
Y895568D03*
X1392170Y889190D03*
X1390319Y892379D03*
X1381067Y901946D03*
X1384768D03*
X1388469D03*
X1390319Y898757D03*
X1392170Y901946D03*
X1388469Y908324D03*
X1390319Y911512D03*
Y905134D03*
X1381067Y914701D03*
X1384768D03*
X1390319Y917890D03*
X1388469Y914701D03*
X1392170D03*
X1388469Y921079D03*
X1390319Y924268D03*
X1381067Y927457D03*
X1384768D03*
X1388469D03*
Y933835D03*
X1392170Y927457D03*
X1390319Y930646D03*
X1392170Y933835D03*
X1388469Y940213D03*
X1390319Y937024D03*
X1381067Y946591D03*
X1384768D03*
X1388469D03*
X1390319Y943402D03*
X1392170Y946591D03*
X1390319Y949780D03*
X1388469Y952969D03*
X1390319Y956158D03*
X1381067Y959347D03*
X1384768D03*
X1388469Y965725D03*
Y959347D03*
X1392170D03*
X1390319Y962536D03*
Y968914D03*
X1388469Y978481D03*
X1381067Y972103D03*
X1384768D03*
X1382918Y981670D03*
X1384768Y984859D03*
X1388469Y972103D03*
X1392170D03*
X1390319Y981670D03*
Y975292D03*
X1392170Y984859D03*
X1384768Y991237D03*
X1382918Y988048D03*
X1392170Y991237D03*
X1390319Y988048D03*
X1397721Y873245D03*
Y879623D03*
X1395871Y876434D03*
X1408823Y879623D03*
X1399571Y882812D03*
X1395871D03*
X1401422Y892379D03*
X1399571Y895568D03*
X1395871Y889190D03*
X1403272Y882812D03*
X1406973D03*
X1403272Y889190D03*
X1406973D03*
X1399571Y901946D03*
X1395871D03*
X1401422Y905134D03*
Y911512D03*
X1405123Y905134D03*
X1408823D03*
X1401422Y898757D03*
X1399571Y908323D03*
Y914701D03*
X1401422Y917890D03*
X1395871Y914701D03*
X1399571Y921079D03*
X1401422Y924268D03*
X1405123Y917890D03*
X1408823D03*
X1395871Y927457D03*
Y933835D03*
X1399571Y927457D03*
X1401422Y930646D03*
X1399571Y933835D03*
Y940213D03*
X1401422Y937024D03*
X1405123Y930646D03*
X1408823D03*
X1405123Y937024D03*
X1408823D03*
X1401422Y943402D03*
X1399571Y946591D03*
X1401422Y949780D03*
X1399571Y952969D03*
X1401422Y956158D03*
X1408823Y949780D03*
X1405123D03*
X1395871Y946591D03*
X1399571Y965725D03*
X1395871Y959347D03*
X1399571D03*
X1401422Y962536D03*
Y968914D03*
X1408823Y962536D03*
X1405123D03*
X1397721Y981670D03*
X1399571Y978481D03*
X1395871Y972103D03*
X1399571D03*
X1401422Y975292D03*
X1399571Y984859D03*
X1405123Y981670D03*
X1408823Y975292D03*
X1405123D03*
X1406973Y984859D03*
X1399571Y991237D03*
X1397721Y988048D03*
X1406973Y991237D03*
X1405123Y988048D03*
X1410674Y876434D03*
X1423602Y879623D03*
X1421751Y876434D03*
X1410674Y882812D03*
Y889190D03*
Y895568D03*
X1421751Y882812D03*
Y895568D03*
Y889190D03*
X1410674Y901946D03*
Y908324D03*
X1421751Y901946D03*
X1423602Y905134D03*
X1421751Y908324D03*
X1410674Y914701D03*
Y921079D03*
X1423602Y917890D03*
X1421751Y914701D03*
Y921079D03*
Y940213D03*
X1410674Y927457D03*
Y933835D03*
Y940213D03*
X1423602Y930646D03*
X1421751Y927457D03*
Y933835D03*
X1423602Y937024D03*
X1410674Y946591D03*
Y952969D03*
X1423602Y949780D03*
X1421751Y946591D03*
Y952969D03*
X1410674Y959347D03*
Y965725D03*
X1423602Y962536D03*
X1421751Y959347D03*
Y965725D03*
X1410674Y972103D03*
Y978481D03*
X1423602Y981670D03*
Y975292D03*
X1421751Y972103D03*
Y978481D03*
Y984859D03*
X1423602Y988048D03*
X1421751Y991237D03*
X1436554Y876434D03*
X1429153Y882812D03*
X1425452Y889190D03*
X1429153D03*
X1431003Y892379D03*
X1432854Y895568D03*
X1436554Y889190D03*
X1432854Y901946D03*
X1431003Y898757D03*
Y911512D03*
Y905134D03*
X1427302D03*
X1436554Y901946D03*
X1432854Y908323D03*
Y914701D03*
X1431003Y917890D03*
X1427302D03*
X1432854Y921079D03*
X1431003Y924268D03*
X1436554Y914701D03*
X1432854Y927457D03*
X1431003Y930646D03*
X1427302D03*
X1432854Y933835D03*
Y940213D03*
X1431003Y937024D03*
X1427302D03*
X1436554Y927457D03*
Y933835D03*
X1431003Y943402D03*
Y949780D03*
X1427302D03*
X1432854Y946591D03*
Y952969D03*
X1431003Y956158D03*
X1436554Y946591D03*
X1432854Y959347D03*
X1427302Y962536D03*
X1431003D03*
X1432854Y965725D03*
X1431003Y968914D03*
X1436554Y959347D03*
X1432854Y978481D03*
X1431003Y981670D03*
X1432854Y972103D03*
X1431003Y975292D03*
X1427302D03*
X1429153Y984859D03*
X1438405Y981670D03*
X1436554Y972103D03*
Y984859D03*
X1431003Y988048D03*
X1429153Y991237D03*
X1436554D03*
X1438405Y988048D03*
X1447657Y876434D03*
X1445806Y879623D03*
X1443956Y882812D03*
X1447657D03*
X1440255Y889190D03*
X1447657D03*
X1442106Y892379D03*
X1443956Y895568D03*
X1451357Y882812D03*
X1451358Y889190D03*
X1453208Y892379D03*
X1442106Y898757D03*
X1440255Y901946D03*
X1447657D03*
X1443956D03*
X1442106Y905134D03*
X1443956Y908324D03*
X1442106Y911512D03*
X1451358Y901946D03*
X1453208Y898757D03*
Y905134D03*
Y911512D03*
X1440255Y914701D03*
X1443956D03*
X1447657D03*
X1442106Y917890D03*
X1443956Y921079D03*
X1442106Y924268D03*
X1451357Y914701D03*
X1453208Y917890D03*
Y924268D03*
X1440255Y927457D03*
X1443956D03*
X1447657D03*
X1440255Y933835D03*
X1443956D03*
X1442106Y937024D03*
X1443956Y940213D03*
X1453208Y930646D03*
X1451357Y927457D03*
X1447657Y946591D03*
X1442106Y943402D03*
X1440255Y946591D03*
X1442106Y949780D03*
X1443956Y946591D03*
Y952969D03*
X1442106Y956158D03*
X1451357Y946591D03*
X1453208Y943402D03*
Y949780D03*
Y956158D03*
X1440255Y959347D03*
X1443956D03*
X1447657D03*
X1443956Y965725D03*
X1442106Y962536D03*
Y968914D03*
X1451357Y959347D03*
X1453208Y962536D03*
Y968914D03*
X1445806Y981670D03*
X1443956Y978481D03*
Y972103D03*
X1447657D03*
X1442106Y975292D03*
X1440255Y972103D03*
X1443956Y984859D03*
X1453208Y981670D03*
X1451357Y972103D03*
X1453208Y975292D03*
X1451357Y984859D03*
X1445806Y988048D03*
X1443956Y991237D03*
X1453208Y988048D03*
Y994426D03*
X1451357Y991237D03*
X1453208Y1000804D03*
Y1007182D03*
X1456909Y873245D03*
Y879623D03*
X1458759Y876434D03*
X1468011Y879623D03*
X1455058Y882812D03*
X1462460D03*
X1466161D03*
X1458759D03*
Y889190D03*
X1455058Y895568D03*
X1464310Y892379D03*
X1466161Y895568D03*
X1462460Y889190D03*
X1464310Y898757D03*
X1455058Y901946D03*
X1458759D03*
X1466161D03*
X1462460D03*
X1464310Y905134D03*
X1455058Y908324D03*
X1464310Y911512D03*
X1466161Y908323D03*
X1458759Y914701D03*
X1464310Y917890D03*
Y924268D03*
X1455058Y921079D03*
X1466161D03*
X1455058Y914701D03*
X1462460D03*
X1466161D03*
X1455058Y927457D03*
X1458759D03*
X1466161D03*
X1462460D03*
X1455058Y933835D03*
X1464310Y930646D03*
X1462460Y933835D03*
X1466161D03*
X1458759D03*
X1455058Y940213D03*
X1466161D03*
X1462460Y946591D03*
X1466161D03*
X1458759D03*
X1466161Y952969D03*
X1464310Y956158D03*
X1455058Y952969D03*
X1464310Y943402D03*
X1455058Y946591D03*
X1464310Y949780D03*
X1455058Y965725D03*
X1466161D03*
X1455058Y959347D03*
X1462460D03*
X1466161D03*
X1458759D03*
X1464310Y962536D03*
Y968914D03*
X1460609Y981670D03*
X1455058Y978481D03*
X1466161D03*
X1455058Y972103D03*
X1462460D03*
X1466161D03*
X1458759D03*
X1464310Y975292D03*
X1458759Y984859D03*
X1466161D03*
X1468011Y981670D03*
X1458759Y997615D03*
X1466161D03*
X1460609Y988048D03*
Y994426D03*
X1458759Y991237D03*
X1466161D03*
X1460609Y1000804D03*
X1468011Y988048D03*
Y994426D03*
Y1000804D03*
X1458759Y1003993D03*
X1466161D03*
Y1010371D03*
X1458759D03*
X1460609Y1007182D03*
X1468011D03*
X1479113Y873245D03*
X1469861Y876434D03*
X1479113Y879623D03*
X1482814Y886001D03*
X1480964Y882812D03*
X1469861D03*
X1479113Y886001D03*
X1482814Y892379D03*
X1469861Y889190D03*
X1473562D03*
X1475413Y892379D03*
X1477263Y895568D03*
X1482814Y898757D03*
X1469861Y901946D03*
X1475413Y898757D03*
X1473562Y901946D03*
X1482814Y905134D03*
Y911512D03*
X1477263Y908324D03*
X1475413Y911512D03*
Y905134D03*
X1482814Y917890D03*
X1469861Y914701D03*
X1473562D03*
X1475413Y917890D03*
Y924268D03*
X1482814D03*
X1477263Y921079D03*
X1469861Y933835D03*
X1473562D03*
X1482814Y930646D03*
X1475413D03*
X1477263Y933835D03*
X1473562Y927457D03*
X1469861D03*
X1482814Y937024D03*
X1477263Y940213D03*
X1482814Y943402D03*
Y949780D03*
X1475413Y943402D03*
X1469861Y946591D03*
X1473562D03*
X1475413Y949780D03*
X1482814Y956158D03*
X1477263Y952969D03*
X1475413Y956158D03*
X1482814Y962536D03*
X1469861Y959347D03*
X1473562D03*
X1475413Y962536D03*
X1477263Y965725D03*
X1482814Y968914D03*
X1475413D03*
X1482814Y975292D03*
Y981670D03*
X1469861Y972103D03*
X1473562D03*
X1475413Y975292D03*
X1477263Y978481D03*
X1475413Y981670D03*
X1473562Y984859D03*
X1475413Y1000804D03*
X1482814Y988048D03*
Y994426D03*
X1473562Y991237D03*
Y997615D03*
X1475413Y988048D03*
Y994426D03*
X1482814Y1000804D03*
Y1007182D03*
X1473562Y1003993D03*
Y1010371D03*
X1475413Y1007182D03*
X1492066Y876434D03*
X1490216Y886001D03*
X1484665Y882812D03*
X1488365D03*
X1495767D03*
X1493917Y886001D03*
X1488365Y889190D03*
X1495767D03*
X1490216Y892379D03*
X1495767Y895568D03*
X1490216Y898757D03*
X1488365Y901946D03*
X1495767D03*
X1488365Y908324D03*
X1490216Y911512D03*
X1495767Y908324D03*
Y914701D03*
X1490216Y917890D03*
X1488365Y921079D03*
X1495767D03*
X1490216Y930646D03*
X1495767Y933835D03*
X1488365Y927457D03*
X1495767D03*
X1488365Y940213D03*
X1495767D03*
X1490216Y937024D03*
X1488365Y946591D03*
X1490216Y949780D03*
X1495767Y946591D03*
Y952969D03*
X1490216Y956158D03*
X1488365Y965725D03*
X1495767Y959347D03*
Y965725D03*
X1488365Y959347D03*
X1490216Y968914D03*
X1495767Y972103D03*
X1490216Y975292D03*
X1486515Y981670D03*
X1488365Y978481D03*
X1495767D03*
X1497617Y981670D03*
X1484665Y984859D03*
X1488365D03*
X1495767D03*
X1490216Y988048D03*
X1488365Y997615D03*
X1490216Y994426D03*
X1495767Y991237D03*
Y997615D03*
X1488365Y1003993D03*
X1490216Y1007182D03*
X1495767Y1003993D03*
Y1010371D03*
X1501318Y873245D03*
Y879623D03*
X1510570Y876434D03*
X1508720Y879623D03*
X1501318Y886001D03*
X1510570Y882812D03*
X1508720Y886001D03*
X1503169Y889190D03*
Y895568D03*
X1501318Y892379D03*
X1508720D03*
X1499468Y882812D03*
X1505019Y886001D03*
X1501318Y898757D03*
X1508720D03*
X1503169Y901946D03*
X1501318Y905134D03*
X1508720D03*
X1501318Y911512D03*
X1508720D03*
X1503169Y908323D03*
Y914701D03*
X1501318Y917890D03*
X1508720D03*
X1503169Y921079D03*
X1501318Y924268D03*
X1508720D03*
X1503169Y927457D03*
X1501318Y930646D03*
X1503169Y933835D03*
X1508720Y930646D03*
Y937024D03*
X1503169Y940213D03*
X1501318Y937024D03*
Y943402D03*
X1508720D03*
X1503169Y946591D03*
X1501318Y949780D03*
X1508720D03*
X1503169Y952969D03*
X1501318Y956158D03*
X1508720D03*
X1503169Y959347D03*
Y965725D03*
X1501318Y962536D03*
X1508720D03*
X1501318Y968914D03*
X1508720D03*
X1510570Y984859D03*
X1512421Y981670D03*
X1503169Y972103D03*
X1501318Y975292D03*
X1503169Y978481D03*
X1501318Y981670D03*
X1508720Y975292D03*
Y981670D03*
X1499468Y984859D03*
X1503169D03*
Y991237D03*
X1501318Y988048D03*
X1503169Y997615D03*
X1501318Y994426D03*
X1508720Y988048D03*
Y994426D03*
X1501318Y1000804D03*
X1508720D03*
X1501318Y1007182D03*
X1503169Y1010371D03*
X1508720Y1007182D03*
X1503169Y1003993D03*
X1521673Y876434D03*
X1517972D03*
X1519822Y879623D03*
X1527224D03*
X1516121D03*
X1523523Y873245D03*
X1514271Y882812D03*
Y889190D03*
X1521673Y882812D03*
X1519822Y886001D03*
X1525373Y882812D03*
X1527224Y886001D03*
X1521673Y889190D03*
Y895568D03*
X1527224Y892379D03*
X1516121D03*
X1514271Y901946D03*
Y908324D03*
X1521673Y901946D03*
X1527224Y898757D03*
X1516121D03*
X1527224Y911512D03*
Y905134D03*
X1516121Y911512D03*
X1521673Y908323D03*
X1514271Y921079D03*
X1521673Y914701D03*
X1527224Y917890D03*
X1516121D03*
X1521673Y921079D03*
X1527224Y924268D03*
X1514271Y927457D03*
Y940213D03*
X1516121Y930646D03*
X1521673Y927457D03*
Y933835D03*
X1527224Y930646D03*
X1516121Y937024D03*
X1527224D03*
X1521673Y940213D03*
X1514271Y946591D03*
X1516121Y949780D03*
X1521673Y946591D03*
X1527224Y943402D03*
Y949780D03*
X1521673Y952969D03*
X1527224Y956158D03*
X1516121D03*
X1514271Y959347D03*
Y965725D03*
X1521673Y959347D03*
Y965725D03*
X1527224Y962536D03*
Y968914D03*
X1516121D03*
X1514271Y978481D03*
Y984859D03*
X1521673Y972103D03*
X1523523Y981670D03*
X1521673Y978481D03*
X1527224Y975292D03*
Y981670D03*
X1516121Y975292D03*
X1521673Y984859D03*
X1525373D03*
X1514271Y997615D03*
X1521673Y991237D03*
Y997615D03*
X1527224Y988048D03*
Y994426D03*
X1516121Y988048D03*
Y994426D03*
X1527224Y1000804D03*
X1514271Y1003993D03*
X1516121Y1007182D03*
X1521673Y1003993D03*
Y1010371D03*
X1527224Y1007182D03*
X1529074Y876434D03*
X1538326Y879623D03*
X1530925Y886001D03*
X1529074Y889190D03*
Y895568D03*
X1540176Y882812D03*
X1536476D03*
X1534625Y886001D03*
X1540176Y889190D03*
X1542027Y892379D03*
X1534625D03*
X1529074Y901946D03*
Y908324D03*
X1542027Y898757D03*
X1540176Y901946D03*
X1534625Y898757D03*
X1540176Y908324D03*
X1542027Y911512D03*
X1534625Y905134D03*
Y911512D03*
X1529074Y914701D03*
Y921079D03*
X1542027Y917890D03*
X1534625D03*
X1540176Y921079D03*
X1534625Y924268D03*
X1529074Y927457D03*
Y933835D03*
Y940213D03*
X1540176Y927457D03*
X1542027Y930646D03*
X1534625D03*
X1542027Y937024D03*
X1540176Y940213D03*
X1534625Y937024D03*
X1529074Y946591D03*
Y952969D03*
X1540176Y946591D03*
X1542027Y949780D03*
X1534625Y943402D03*
Y949780D03*
Y956158D03*
X1542027D03*
X1529074Y959347D03*
Y965725D03*
X1540176Y959347D03*
Y965725D03*
X1534625Y962536D03*
X1542027Y968914D03*
X1534625D03*
X1538326Y981670D03*
X1542027Y975292D03*
X1540176Y978481D03*
X1534625Y975292D03*
Y981670D03*
X1536476Y984859D03*
X1540176D03*
X1529074Y972103D03*
Y978481D03*
Y984859D03*
Y991237D03*
Y997615D03*
X1542027Y988048D03*
X1540176Y997615D03*
X1542027Y994426D03*
X1534625Y988048D03*
Y994426D03*
Y1000804D03*
X1542027Y1007182D03*
X1534625D03*
X1529074Y1003993D03*
Y1010371D03*
X1540176Y1003993D03*
X1545728Y873245D03*
X1553129Y879623D03*
X1545728Y886001D03*
X1547578Y882812D03*
X1553129Y886001D03*
X1551279Y882812D03*
X1547578Y889190D03*
Y895568D03*
X1553129Y892379D03*
X1547578Y901946D03*
X1553129Y898757D03*
X1547578Y908324D03*
Y914701D03*
Y921079D03*
Y927457D03*
Y933835D03*
Y940213D03*
Y946591D03*
Y952969D03*
Y959347D03*
Y965725D03*
X1543877Y984859D03*
X1547578Y972103D03*
Y978481D03*
Y984859D03*
X1545728Y988048D03*
X1547578Y991237D03*
Y997615D03*
Y1003993D03*
Y1010371D03*
G54D60*
X928740Y321654D03*
G54D36*
X250326Y185236D03*
X368437D03*
G54D61*
X916546Y309460D03*
X911495Y321654D03*
X916546Y333848D03*
X928740Y304409D03*
Y338899D03*
X940934Y309460D03*
X945985Y321654D03*
X940934Y333848D03*
G54D73*
X1766929Y1714960D03*
G54D11*
X19685Y-29134D03*
Y1803261D03*
X2081889Y-29134D03*
Y1803261D03*
G54D27*
X117933Y605376D03*
X763602Y605413D03*
X1094076Y605378D03*
X1739745Y605411D03*
G54D18*
X44000Y154200D03*
X31818Y1424257D03*
X441043Y1672205D03*
Y1718465D03*
X1416437Y1672205D03*
Y1718465D03*
X1800449Y126194D03*
X1804650Y1667292D03*
G54D53*
X791280Y1704890D03*
X1066280D03*
G54D33*
X230905Y1644448D03*
Y1658621D03*
Y1672795D03*
Y1686968D03*
Y1701141D03*
Y1715314D03*
Y1729488D03*
X246653Y1644448D03*
X238779Y1648385D03*
X246653Y1658621D03*
X238779Y1662558D03*
X246653Y1672795D03*
X238779Y1676732D03*
X246653Y1686968D03*
X238779Y1690905D03*
X246653Y1701141D03*
X238779Y1705078D03*
X246653Y1715314D03*
X238779Y1719251D03*
X246653Y1729488D03*
X238779Y1733425D03*
X254527Y1648385D03*
Y1662558D03*
Y1676732D03*
Y1690905D03*
Y1705078D03*
Y1719251D03*
Y1733425D03*
X262401Y1644448D03*
X270275Y1648385D03*
X262401Y1658621D03*
X270275Y1662558D03*
X262401Y1672795D03*
X270275Y1676732D03*
X262401Y1686968D03*
X270275Y1690905D03*
X262401Y1701141D03*
X270275Y1705078D03*
X262401Y1715314D03*
X270275Y1719251D03*
X262401Y1729488D03*
X270275Y1733425D03*
X278149Y1644448D03*
X286023Y1648385D03*
X278149Y1658621D03*
X286023Y1662558D03*
X278149Y1672795D03*
X286023Y1676732D03*
X278149Y1686968D03*
X286023Y1690905D03*
X278149Y1701141D03*
X286023Y1705078D03*
X278149Y1715314D03*
X286023Y1719251D03*
X278149Y1729488D03*
X286023Y1733425D03*
X297835Y1672795D03*
X305709Y1676732D03*
X297835Y1686968D03*
X305709Y1690905D03*
X297835Y1701141D03*
X305709Y1705078D03*
X297835Y1715314D03*
X305709Y1719251D03*
X297835Y1729488D03*
X305709Y1733425D03*
X313583Y1672795D03*
X321457Y1676732D03*
X313583Y1686968D03*
X321457Y1690905D03*
X313583Y1701141D03*
X321457Y1705078D03*
X313583Y1715314D03*
X321457Y1719251D03*
X313583Y1729488D03*
X321457Y1733425D03*
X329331Y1672795D03*
Y1686968D03*
Y1701141D03*
Y1715314D03*
Y1729488D03*
X345079Y1672795D03*
X337205Y1676732D03*
X345079Y1686968D03*
X337205Y1690905D03*
X345079Y1701141D03*
X337205Y1705078D03*
X345079Y1715314D03*
X337205Y1719251D03*
X345079Y1729488D03*
X337205Y1733425D03*
X352953Y1676732D03*
Y1690905D03*
Y1705078D03*
Y1719251D03*
Y1733425D03*
X495078Y1672795D03*
Y1686968D03*
Y1701141D03*
Y1715314D03*
Y1729488D03*
X510826Y1672795D03*
X502952Y1676732D03*
X510826Y1686968D03*
X502952Y1690905D03*
X510826Y1701141D03*
X502952Y1705078D03*
X510826Y1715314D03*
X502952Y1719251D03*
X510826Y1729488D03*
X502952Y1733425D03*
X526574Y1672795D03*
X518700Y1676732D03*
X526574Y1686968D03*
X518700Y1690905D03*
X526574Y1701141D03*
X518700Y1705078D03*
X526574Y1715314D03*
X518700Y1719251D03*
X526574Y1729488D03*
X518700Y1733425D03*
X542322Y1672795D03*
X534448Y1676732D03*
X542322Y1686968D03*
X534448Y1690905D03*
X542322Y1701141D03*
X534448Y1705078D03*
X542322Y1715314D03*
X534448Y1719251D03*
X542322Y1729488D03*
X534448Y1733425D03*
X550196Y1676732D03*
Y1690905D03*
Y1705078D03*
Y1719251D03*
Y1733425D03*
X562008Y1672795D03*
X569882Y1676732D03*
X562008Y1686968D03*
X569882Y1690905D03*
X562008Y1701141D03*
X569882Y1705078D03*
X562008Y1715314D03*
X569882Y1719251D03*
X562008Y1729488D03*
X569882Y1733425D03*
X577756Y1672795D03*
X585630Y1676732D03*
X577756Y1686968D03*
X585630Y1690905D03*
X577756Y1701141D03*
X585630Y1705078D03*
X577756Y1715314D03*
X585630Y1719251D03*
X577756Y1729488D03*
X585630Y1733425D03*
X593504Y1672795D03*
X601378Y1676732D03*
X593504Y1686968D03*
X601378Y1690905D03*
X593504Y1701141D03*
X601378Y1705078D03*
X593504Y1715314D03*
X601378Y1719251D03*
X593504Y1729488D03*
X601378Y1733425D03*
X609252Y1672795D03*
X617126Y1676732D03*
X609252Y1686968D03*
X617126Y1690905D03*
X609252Y1701141D03*
X617126Y1705078D03*
X609252Y1715314D03*
X617126Y1719251D03*
X609252Y1729488D03*
X617126Y1733425D03*
X1238778Y1672795D03*
Y1686968D03*
Y1701141D03*
Y1715314D03*
Y1729488D03*
X1254526Y1672795D03*
X1246652Y1676732D03*
X1254526Y1686968D03*
X1246652Y1690905D03*
X1254526Y1701141D03*
X1246652Y1705078D03*
X1254526Y1715314D03*
X1246652Y1719251D03*
X1254526Y1729488D03*
X1246652Y1733425D03*
X1270274Y1672795D03*
X1262400Y1676732D03*
X1270274Y1686968D03*
X1262400Y1690905D03*
X1270274Y1701141D03*
X1262400Y1705078D03*
X1270274Y1715314D03*
X1262400Y1719251D03*
X1270274Y1729488D03*
X1262400Y1733425D03*
X1286022Y1672795D03*
X1278148Y1676732D03*
X1286022Y1686968D03*
X1278148Y1690905D03*
X1286022Y1701141D03*
X1278148Y1705078D03*
X1286022Y1715314D03*
Y1729488D03*
X1278148Y1733425D03*
X1305708Y1672795D03*
Y1686968D03*
X1293896Y1676732D03*
X1305708Y1701141D03*
X1293896Y1690905D03*
X1305708Y1715314D03*
X1293896Y1705078D03*
X1305708Y1729488D03*
X1293896Y1719251D03*
Y1733425D03*
X1313582Y1676732D03*
Y1690905D03*
Y1705078D03*
Y1719251D03*
Y1733425D03*
X1321456Y1672795D03*
X1329330Y1676732D03*
X1321456Y1686968D03*
X1329330Y1690905D03*
X1321456Y1701141D03*
X1329330Y1705078D03*
X1321456Y1715314D03*
X1329330Y1719251D03*
X1321456Y1729488D03*
X1329330Y1733425D03*
X1337204Y1672795D03*
X1345078Y1676732D03*
X1337204Y1686968D03*
X1345078Y1690905D03*
X1337204Y1701141D03*
X1345078Y1705078D03*
X1337204Y1715314D03*
X1345078Y1719251D03*
X1337204Y1729488D03*
X1345078Y1733425D03*
X1352952Y1672795D03*
X1360826Y1676732D03*
X1352952Y1686968D03*
X1360826Y1690905D03*
X1352952Y1701141D03*
X1360826Y1705078D03*
X1352952Y1715314D03*
X1360826Y1719251D03*
X1352952Y1729488D03*
X1360826Y1733425D03*
X1502952Y1672795D03*
X1510826Y1676732D03*
X1502952Y1686968D03*
X1510826Y1690905D03*
X1502952Y1701141D03*
X1510826Y1705078D03*
X1502952Y1715314D03*
X1510826Y1719251D03*
X1502952Y1729488D03*
X1510826Y1733425D03*
X1518700Y1672795D03*
X1526574Y1676732D03*
X1518700Y1686968D03*
X1526574Y1690905D03*
X1518700Y1701141D03*
X1526574Y1705078D03*
X1518700Y1715314D03*
X1526574Y1719251D03*
X1518700Y1729488D03*
X1526574Y1733425D03*
X1534448Y1672795D03*
X1542322Y1676732D03*
X1534448Y1686968D03*
X1542322Y1690905D03*
X1534448Y1701141D03*
X1542322Y1705078D03*
X1534448Y1715314D03*
X1542322Y1719251D03*
X1534448Y1729488D03*
X1542322Y1733425D03*
X1550196Y1672795D03*
X1558070Y1676732D03*
X1550196Y1686968D03*
X1558070Y1690905D03*
X1550196Y1701141D03*
X1558070Y1705078D03*
X1550196Y1715314D03*
X1558070Y1719251D03*
X1550196Y1729488D03*
X1558070Y1733425D03*
X1569882Y1672795D03*
Y1686968D03*
Y1701141D03*
Y1715314D03*
Y1729488D03*
X1585630Y1672795D03*
X1577756Y1676732D03*
X1585630Y1686968D03*
X1577756Y1690905D03*
X1585630Y1701141D03*
X1577756Y1705078D03*
X1585630Y1715314D03*
X1577756Y1719251D03*
X1585630Y1729488D03*
X1577756Y1733425D03*
X1601378Y1672795D03*
X1593504Y1676732D03*
X1601378Y1686968D03*
X1593504Y1690905D03*
X1601378Y1701141D03*
X1593504Y1705078D03*
X1601378Y1715314D03*
X1593504Y1719251D03*
X1601378Y1729488D03*
X1593504Y1733425D03*
X1617126Y1672795D03*
X1609252Y1676732D03*
X1617126Y1686968D03*
X1609252Y1690905D03*
X1617126Y1701141D03*
X1609252Y1705078D03*
X1617126Y1715314D03*
X1609252Y1719251D03*
X1617126Y1729488D03*
X1609252Y1733425D03*
X1625000Y1676732D03*
Y1690905D03*
Y1705078D03*
Y1719251D03*
Y1733425D03*
G54D46*
X441043Y1698268D03*
X1416437D03*
G54D55*
X805690Y204724D03*
X1057659D03*
G54D15*
X17292Y290137D03*
X35689Y301357D03*
X33822Y1462075D03*
Y1459075D03*
Y1456075D03*
X36822D03*
Y1459075D03*
Y1462075D03*
X33822Y1465075D03*
X36822D03*
X37671Y1515214D03*
X34704Y1515235D03*
X47892Y290137D03*
X49400Y384392D03*
X49250Y396332D03*
X47618Y412613D03*
X47619Y421655D03*
X42822Y1462075D03*
Y1459075D03*
Y1456075D03*
Y1465075D03*
X47138Y1513072D03*
X47089Y1510268D03*
X50642Y1557451D03*
X45633Y1592481D03*
X50133D03*
X38426Y1654079D03*
X41427Y1668587D03*
X38426Y1659059D03*
X44583Y1672433D03*
Y1677613D03*
X66289Y301357D03*
X61340Y384362D03*
X61250Y396142D03*
X56542Y589521D03*
X66822Y1462075D03*
Y1459075D03*
Y1456075D03*
X57822Y1462075D03*
Y1459075D03*
Y1456075D03*
X66822Y1465075D03*
X57822D03*
X63990Y1562177D03*
Y1567627D03*
Y1564727D03*
X63915Y1558805D03*
Y1556254D03*
X63990Y1570427D03*
X61225Y1570283D03*
X58564Y1570209D03*
X65767Y1609405D03*
X59767D03*
X53767D03*
X65767Y1615405D03*
X65943Y1621405D03*
X59767D03*
X53767Y1615405D03*
Y1621405D03*
X59427Y1644410D03*
X53648Y1653088D03*
X77790Y520108D03*
X77733Y526764D03*
X77790Y537808D03*
X77733Y544464D03*
X81822Y1462075D03*
Y1456075D03*
Y1465075D03*
X68427Y1644410D03*
X73427D03*
X80000Y1702450D03*
X79500Y1720450D03*
X88722Y1462075D03*
X85722D03*
X88722Y1456075D03*
X85722D03*
X88722Y1465075D03*
X85722D03*
X85621Y1551969D03*
X82974Y1552051D03*
X83340Y1654353D03*
X89466Y1663138D03*
Y1667127D03*
X83340Y1659333D03*
X85395Y1670331D03*
Y1675311D03*
X102096Y1555442D03*
X100439Y1667361D03*
X106573Y1660235D03*
X100915Y1679564D03*
X105069Y1685763D03*
X102243Y1682263D03*
Y1689263D03*
X120016Y300654D03*
Y320631D03*
X114973Y1660235D03*
X113469Y1685763D03*
X133120Y1454751D03*
X137120D03*
X141028Y1454705D03*
X140775Y1638035D03*
X146982Y526997D03*
X145028Y1454705D03*
X152449Y1623572D03*
Y1628528D03*
X151611Y1663933D03*
X159427Y1687843D03*
X151510Y1676811D03*
X163113Y1477590D03*
Y1499490D03*
X164730Y1521561D03*
X161239Y1636147D03*
Y1631191D03*
X162995Y1661377D03*
X160011Y1663933D03*
X163003Y1666462D03*
X159910Y1676811D03*
X162848Y1679357D03*
X162840Y1674272D03*
X187250Y129674D03*
X189410Y388180D03*
X200754Y595174D03*
Y603274D03*
X192951Y1560498D03*
X196081Y1639349D03*
X195504Y1645359D03*
X203754Y595174D03*
Y603274D03*
X207968Y1653130D03*
X203800Y1646832D03*
X272242Y523076D03*
X276085Y1509654D03*
X270720Y1531073D03*
X273220D03*
X275720D03*
X281147Y521803D03*
X280621Y1478082D03*
X291175Y1477590D03*
X283221Y1484772D03*
Y1479992D03*
X278021Y1484772D03*
Y1479992D03*
X283221Y1493392D03*
X280621Y1491482D03*
X278021Y1493392D03*
X291175Y1499490D03*
X283221Y1498172D03*
X278021D03*
X291619Y1536606D03*
X291593Y1529402D03*
Y1531902D03*
X284800Y1526750D03*
X277572Y1536763D03*
X280072D03*
X291619Y1539106D03*
X292792Y1521561D03*
X297323Y1651172D03*
X318660Y24989D03*
X307255Y1641150D03*
X339914Y165170D03*
X384668Y471926D03*
X410701Y99148D03*
X396977Y216685D03*
X399625Y479119D03*
X408683Y1478082D03*
Y1491482D03*
X406083Y1479992D03*
Y1484772D03*
Y1493392D03*
Y1498172D03*
X404147Y1509654D03*
X398782Y1531073D03*
X401282D03*
X403782D03*
X411800Y220200D03*
X413425Y479042D03*
X411283Y1479992D03*
Y1484772D03*
Y1493392D03*
Y1498172D03*
X412862Y1526750D03*
X436090Y120007D03*
X429997Y166400D03*
X441997D03*
X439299Y220046D03*
X427225Y478965D03*
X440159Y966741D03*
Y981741D03*
Y974241D03*
X427286Y1477590D03*
Y1499490D03*
X428746Y1521727D03*
X427730Y1536606D03*
X427704Y1531902D03*
Y1529402D03*
X427730Y1539106D03*
X428500Y1650000D03*
X465997Y166400D03*
X457997D03*
X466041Y1664913D03*
X483467Y209755D03*
X514418Y145171D03*
Y149171D03*
Y153171D03*
X513360Y169190D03*
X511771Y199576D03*
X506261Y865338D03*
X522418Y153171D03*
X516572Y865327D03*
X530418Y145171D03*
Y149171D03*
Y153171D03*
X531280Y210922D03*
X544794Y1478082D03*
Y1491482D03*
X542194Y1479992D03*
Y1484772D03*
Y1493392D03*
X537694Y1504872D03*
X542194Y1498172D03*
X543759Y1536882D03*
X540193Y1531073D03*
X537693D03*
X535193D03*
X541259Y1536882D03*
X555348Y1477590D03*
X547394Y1479992D03*
Y1484772D03*
Y1493392D03*
X555348Y1499490D03*
X547394Y1498172D03*
X556965Y1521561D03*
X556642Y1529389D03*
X554715Y1531564D03*
X550540Y1526910D03*
X556197Y1536687D03*
Y1539187D03*
X561248Y106985D03*
Y100399D03*
X562208Y387227D03*
Y376427D03*
Y401158D03*
X568433Y415846D03*
X581985Y379577D03*
Y390377D03*
Y404308D03*
X588723Y423949D03*
X593975Y164440D03*
X598208Y387227D03*
Y376427D03*
X599164Y432209D03*
X604718Y257562D03*
X617985Y379577D03*
Y398578D03*
Y390377D03*
X610935Y409996D03*
X615075Y443000D03*
X633882Y587488D03*
X646285Y297171D03*
X640317Y391085D03*
X634566Y407848D03*
X639482Y587488D03*
X645446Y587300D03*
X653821Y90326D03*
X653013Y443200D03*
X664170Y445711D03*
X651046Y587300D03*
X672856Y1478082D03*
Y1491482D03*
X675112Y1479602D03*
X675456Y1484772D03*
Y1493392D03*
X670256Y1479992D03*
Y1484772D03*
Y1493392D03*
X665756Y1504872D03*
X675456Y1498172D03*
X670256D03*
X680710Y1520284D03*
X683674Y1522287D03*
X695796Y418358D03*
X708395Y430957D03*
X702095Y421508D03*
X698946Y437256D03*
X702095Y449854D03*
X708395Y474971D03*
X698946Y468672D03*
X695796Y487570D03*
X706172Y1552082D03*
X698003Y1684692D03*
X711544Y421508D03*
X720993Y443555D03*
Y446705D03*
X717843D03*
Y440405D03*
X720993Y449854D03*
Y462373D03*
Y459223D03*
Y456074D03*
X717843Y459223D03*
Y465523D03*
X711544Y484420D03*
X722141Y1405912D03*
X721916Y1414339D03*
Y1416939D03*
X722141Y1408412D03*
X721916Y1428989D03*
Y1431589D03*
X733512Y427807D03*
X727292Y421508D03*
X736661Y443555D03*
X733512Y446705D03*
Y443555D03*
X727292Y446705D03*
Y443555D03*
X724143D03*
Y462373D03*
X727292D03*
X733512Y459223D03*
X727292D03*
X733512Y462373D03*
X736661D03*
X727292Y474971D03*
X736661Y484420D03*
X724143D03*
X752409Y421508D03*
X739811Y443555D03*
Y446705D03*
X742961Y440405D03*
X739811Y449854D03*
Y456074D03*
Y459223D03*
Y462373D03*
X742961Y465523D03*
X752409Y484420D03*
X746082Y1506931D03*
X751030Y1668583D03*
X765008Y418358D03*
X758709Y437256D03*
X755559Y456074D03*
X758709Y468672D03*
X765008Y487570D03*
X758179Y1482049D03*
X758163Y1526223D03*
X758179Y1534963D03*
X779014Y1343262D03*
Y1340062D03*
X782014D03*
Y1337062D03*
Y1343262D03*
X780000Y1353500D03*
X779014Y1346462D03*
Y1349862D03*
X782014Y1346462D03*
Y1349862D03*
X780000Y1357500D03*
Y1363500D03*
Y1360500D03*
X780111Y1405366D03*
X782758Y1405249D03*
X795421Y1331257D03*
X785014Y1350862D03*
X804099Y1333835D03*
X801171Y1343278D03*
X810986Y1361684D03*
X819115Y115223D03*
X824499Y145198D03*
X820405Y311830D03*
X831115Y115223D03*
X829115Y150273D03*
X838670Y1518558D03*
X841310Y1518608D03*
X838630Y1521538D03*
X841270Y1521588D03*
X854578Y99651D03*
X856397Y339751D03*
X847007Y1521458D03*
X844367Y1521408D03*
Y1518784D03*
X847007Y1518834D03*
X855853Y1521308D03*
X853213Y1521258D03*
X850146Y1521261D03*
Y1518637D03*
X853213Y1518634D03*
X855853Y1518684D03*
X860152Y328399D03*
X865132D03*
X861377Y339751D03*
X872986Y753451D03*
X858581Y1518568D03*
X858567Y1521416D03*
X876133Y73580D03*
Y95580D03*
Y117580D03*
X919272Y989932D03*
X921289Y1663187D03*
X942779Y277731D03*
X936693Y1462328D03*
X939507Y1462497D03*
X945195Y1459453D03*
X942056Y1459650D03*
X939416Y1459600D03*
Y1456976D03*
X942056Y1457026D03*
X945195Y1456829D03*
X951099Y632206D03*
X956693Y1459805D03*
X953630Y1456760D03*
X958383Y1462447D03*
X950902Y1459500D03*
X948262Y1459450D03*
X953616Y1459608D03*
X948262Y1456826D03*
X950902Y1456876D03*
X955350Y1532760D03*
X961350D03*
X958350D03*
X953520Y1567570D03*
X950520D03*
X959520D03*
X956520D03*
X953520Y1582570D03*
X950520D03*
Y1579570D03*
X953520D03*
Y1576570D03*
X950520D03*
X953520Y1573570D03*
X950520D03*
Y1570570D03*
X953520D03*
X959520Y1582570D03*
X956520D03*
Y1579570D03*
X959520D03*
Y1576570D03*
X956520D03*
X959520Y1573570D03*
X956520D03*
Y1570570D03*
X959520D03*
X953520Y1588570D03*
X950520D03*
Y1585570D03*
X953520D03*
X959520Y1588570D03*
X956520D03*
Y1585570D03*
X959520D03*
X977150Y1052684D03*
X966000Y1300000D03*
X968500D03*
X971000D03*
X967350Y1532760D03*
X964350D03*
X991280D03*
X988280D03*
X988160Y1567710D03*
X991160D03*
X985160D03*
X988160Y1582710D03*
X991160D03*
X985160D03*
Y1579710D03*
X991160D03*
X988160D03*
X991160Y1570710D03*
X988160D03*
Y1573710D03*
X991160D03*
X988160Y1576710D03*
X991160D03*
X985160Y1570710D03*
Y1573710D03*
Y1576710D03*
X988160Y1588710D03*
X991160D03*
X985160D03*
Y1585710D03*
X991160D03*
X988160D03*
X994280Y1532760D03*
X997280D03*
X1000280D03*
X1014206Y510304D03*
X1013306Y526146D03*
X1019440Y1532930D03*
X1016750Y1567710D03*
X1019750D03*
X1016750Y1576710D03*
Y1573710D03*
Y1570710D03*
X1019750Y1576710D03*
Y1573710D03*
Y1570710D03*
Y1579710D03*
X1016750D03*
Y1582710D03*
X1019750D03*
Y1585710D03*
X1016750D03*
Y1588710D03*
X1019750D03*
X1025440Y1532930D03*
X1022440D03*
X1031440D03*
X1028440D03*
X1022750Y1567710D03*
Y1576710D03*
Y1573710D03*
Y1570710D03*
Y1579710D03*
Y1582710D03*
Y1585710D03*
Y1588710D03*
X1045254Y521074D03*
X1037212Y510940D03*
X1051110Y1532850D03*
X1048219Y1567883D03*
X1051219D03*
X1048219Y1576883D03*
Y1573883D03*
Y1570883D03*
X1051219Y1576883D03*
Y1573883D03*
Y1570883D03*
Y1579883D03*
X1048219D03*
Y1582883D03*
X1051219D03*
Y1585883D03*
X1048219D03*
Y1588883D03*
X1051219D03*
X1055934Y385488D03*
X1057110Y1532850D03*
X1054110D03*
X1063110D03*
X1060110D03*
X1054219Y1567883D03*
Y1576883D03*
Y1573883D03*
Y1570883D03*
Y1579883D03*
Y1582883D03*
Y1585883D03*
Y1588883D03*
X1068143Y383688D03*
X1073204Y383417D03*
X1083819Y353094D03*
X1090300Y1532660D03*
X1087300D03*
X1096300D03*
X1093300D03*
X1119067Y1551457D03*
X1133765Y1572102D03*
X1170986Y1510590D03*
Y1532490D03*
X1183354Y77685D03*
X1176972Y86788D03*
X1200824Y1593498D03*
X1192612Y1680410D03*
X1207954Y1680419D03*
X1209879Y1700359D03*
X1230094Y314216D03*
X1226094Y305216D03*
X1216875Y1705826D03*
X1216738Y1720861D03*
X1277732Y236594D03*
Y246594D03*
Y241594D03*
Y251594D03*
X1288494Y1511082D03*
X1285894Y1512992D03*
Y1517772D03*
X1288494Y1524482D03*
X1285894Y1531172D03*
Y1526392D03*
X1283958Y1542654D03*
X1278593Y1564073D03*
X1281093D03*
X1283593D03*
X1287945Y1569763D03*
X1285445D03*
X1302365Y1418702D03*
X1292522Y1421596D03*
X1303943Y1430729D03*
X1299048Y1510590D03*
X1291094Y1512992D03*
Y1517772D03*
X1299048Y1532490D03*
X1291094Y1531172D03*
Y1526392D03*
X1299466Y1562402D03*
Y1564902D03*
X1292673Y1559750D03*
X1299492Y1572106D03*
Y1569606D03*
X1307766Y563013D03*
X1308700Y590300D03*
X1317266Y592522D03*
X1308700Y587800D03*
X1313109Y1195398D03*
Y1200898D03*
X1325366Y592522D03*
X1339488Y1202295D03*
X1340483Y1209006D03*
X1336861Y1222119D03*
X1350809Y1202323D03*
X1368137Y1222298D03*
Y1227798D03*
X1383800Y1685398D03*
X1406655Y1564073D03*
X1409155D03*
X1399940Y1637127D03*
X1414619Y244450D03*
X1416301Y966740D03*
Y981740D03*
Y974240D03*
X1416556Y1511082D03*
X1419156Y1512992D03*
Y1517772D03*
X1413956Y1512992D03*
Y1517772D03*
X1416556Y1524482D03*
X1419156Y1531172D03*
Y1526392D03*
X1413956Y1531172D03*
Y1526392D03*
X1412020Y1542654D03*
X1420735Y1559750D03*
X1411655Y1564073D03*
X1435160Y1510590D03*
Y1532490D03*
X1435578Y1564902D03*
Y1562402D03*
X1436940Y1554277D03*
X1435604Y1572106D03*
Y1569606D03*
X1445985Y116953D03*
X1441390Y163944D03*
X1442993Y176204D03*
X1462405Y61563D03*
X1461242Y128242D03*
X1463017Y136368D03*
X1465832Y535330D03*
X1542767Y1564073D03*
X1552668Y1511082D03*
X1555268Y1512992D03*
Y1517772D03*
X1550068Y1512992D03*
Y1517772D03*
X1552668Y1524482D03*
X1555268Y1531172D03*
Y1526392D03*
X1550068Y1531172D03*
Y1526392D03*
X1548132Y1542654D03*
X1556847Y1559750D03*
X1545267Y1564073D03*
X1547767D03*
X1552118Y1569763D03*
X1549618D03*
X1563222Y1510590D03*
Y1532490D03*
X1564581Y1562316D03*
X1562613Y1564816D03*
X1564128Y1572225D03*
X1562621Y1569761D03*
X1602270Y229530D03*
X1629597Y221842D03*
X1619909Y306746D03*
X1643283Y1425541D03*
X1648337Y1451313D03*
X1654419Y233062D03*
X1655383Y1425541D03*
X1656997Y1708609D03*
Y1723759D03*
X1665100Y156762D03*
Y166762D03*
X1673223Y220857D03*
X1673630Y1533092D03*
Y1537872D03*
X1684925Y118762D03*
Y149762D03*
Y161762D03*
Y153762D03*
X1684942Y234000D03*
X1683587Y1433425D03*
X1680430Y1511198D03*
X1682760Y1512169D03*
X1683330Y1517772D03*
X1678130Y1512992D03*
Y1517772D03*
X1680730Y1524482D03*
X1683330Y1531172D03*
Y1526392D03*
X1678130Y1531172D03*
Y1526392D03*
X1688584Y1553284D03*
X1691548Y1555287D03*
X1686857Y1683918D03*
X1684733Y1698952D03*
X1695102Y1698947D03*
X1691357Y1688418D03*
X1691997Y1708609D03*
X1733083Y654034D03*
X1737606Y1539807D03*
X1736579Y1587480D03*
X1723929Y1654456D03*
X1723963Y1658965D03*
Y1663465D03*
Y1667965D03*
X1731117Y1705115D03*
Y1720265D03*
X1741329Y1482405D03*
Y1485405D03*
Y1491405D03*
Y1488405D03*
X1740058Y1537419D03*
X1744866Y1539589D03*
X1742165Y1539620D03*
X1740979Y1577905D03*
X1743681Y1626750D03*
X1750681D03*
X1747181D03*
X1743481Y1616550D03*
X1750481D03*
X1746981D03*
X1747963Y1641965D03*
X1764029Y1485405D03*
Y1482405D03*
Y1491405D03*
Y1488405D03*
X1756329Y1485405D03*
Y1482405D03*
Y1491405D03*
Y1488405D03*
X1769054Y1585705D03*
X1753079Y1596650D03*
Y1606550D03*
Y1603050D03*
Y1600150D03*
X1761839Y1634223D03*
X1757763Y1643365D03*
X1761494Y1661947D03*
X1779029Y1482405D03*
Y1485405D03*
Y1491405D03*
Y1488405D03*
X1772904Y1585005D03*
X1773863Y1661465D03*
X1774940Y1669037D03*
X1773738Y1672965D03*
X1773963Y1680965D03*
X1793070Y25001D03*
X1788029Y1485405D03*
Y1482405D03*
Y1491405D03*
Y1488405D03*
X1789379Y1588478D03*
X1805525Y146716D03*
X1812029Y1485405D03*
Y1482405D03*
X1803029D03*
Y1485405D03*
X1812029Y1491405D03*
Y1488405D03*
X1803029Y1491405D03*
Y1488405D03*
X1801789Y1536742D03*
X1807408Y1539223D03*
X1810408D03*
X1812078Y1596725D03*
X1812003Y1607375D03*
Y1603875D03*
X1812078Y1600225D03*
X1809179Y1616550D03*
X1809254Y1613775D03*
X1812570Y159275D03*
X1827029Y1488405D03*
Y1491405D03*
Y1485405D03*
Y1482405D03*
X1815344Y1539373D03*
X1818344D03*
X1823112Y1538659D03*
X1812679Y1616550D03*
X1816179D03*
X1812754Y1613775D03*
X1816254D03*
X1837641Y159275D03*
X1840700Y326201D03*
Y348201D03*
Y370201D03*
Y392201D03*
Y414201D03*
Y436201D03*
Y458201D03*
Y480201D03*
Y502201D03*
Y524201D03*
Y546201D03*
Y568201D03*
Y590201D03*
Y656201D03*
Y678201D03*
Y700201D03*
Y722201D03*
Y744201D03*
Y766201D03*
Y788201D03*
Y810201D03*
Y832201D03*
Y854201D03*
Y876201D03*
Y898201D03*
Y920201D03*
Y942201D03*
Y964201D03*
Y986201D03*
Y1008201D03*
Y1030201D03*
Y1052201D03*
Y1074201D03*
Y1096201D03*
Y1118201D03*
Y1140201D03*
Y1162201D03*
Y1184201D03*
Y1206201D03*
Y1228201D03*
Y1250201D03*
Y1272201D03*
Y1294201D03*
Y1316201D03*
Y1338201D03*
Y1404201D03*
Y1448201D03*
Y1470201D03*
Y1492201D03*
Y1514201D03*
Y1536201D03*
Y1558201D03*
Y1580201D03*
X1828889Y1622578D03*
Y1644578D03*
Y1666578D03*
Y1688578D03*
X1854479Y66461D03*
Y110461D03*
Y132461D03*
Y154461D03*
X1847866Y159124D03*
X1854479Y176461D03*
Y198461D03*
Y220461D03*
Y242461D03*
Y264461D03*
Y286461D03*
G54D59*
X922441Y154311D03*
Y243799D03*
G54D12*
X21569Y49379D03*
X21345Y387760D03*
X21309Y395712D03*
X36500Y323500D03*
X33686Y383944D03*
X27309Y383926D03*
X29962Y401000D03*
X36524Y398013D03*
X26771Y398811D03*
X30680Y438142D03*
X35852Y664480D03*
Y686410D03*
Y683910D03*
X43569Y49379D03*
X45423Y197224D03*
Y212224D03*
Y202224D03*
Y207224D03*
X40000Y323500D03*
X55190Y360862D03*
X42809D03*
X46834D03*
X39410Y384582D03*
X39226Y395346D03*
X53825Y421746D03*
X49848Y524210D03*
X49889Y531149D03*
X50880Y1421963D03*
X52405Y1514835D03*
X49405D03*
X52405Y1511986D03*
X49405D03*
X52330Y1509137D03*
X49330D03*
X52796Y1526469D03*
X52905Y1523335D03*
X47760Y1529506D03*
X65347Y66847D03*
X60367D03*
X65347Y71839D03*
X60367D03*
X58457Y69340D03*
X67575Y287500D03*
X56620Y303500D03*
X64150Y434972D03*
X53800Y435451D03*
X54762Y444993D03*
X56800Y524220D03*
X56719Y531120D03*
X64923Y795316D03*
Y832127D03*
Y868938D03*
Y905750D03*
Y942561D03*
Y1089805D03*
Y1126616D03*
Y1163427D03*
Y1200238D03*
Y1237049D03*
X58349Y1412731D03*
X55755Y1511885D03*
X55905Y1514835D03*
X57281Y1523287D03*
X66081D03*
X59881D03*
X63481D03*
X55789Y1509224D03*
X57281Y1526394D03*
X66081D03*
X65281Y1529501D03*
X59881Y1526394D03*
X63481D03*
X62681Y1529501D03*
X64235Y1533150D03*
X61755D03*
X59275D03*
X67196Y1552869D03*
X64235Y1538750D03*
X61755D03*
X59275D03*
X63802Y1579997D03*
X58602D03*
X61302D03*
X75928Y3001D03*
X81159Y17045D03*
X72087Y25977D03*
X74087Y23981D03*
X79043D03*
X81043Y25977D03*
X79192Y19541D03*
X81159Y22037D03*
X73025Y37106D03*
X80111D03*
X73025Y48720D03*
X80111D03*
X69453Y75343D03*
X82367Y71839D03*
X80457Y69340D03*
X82367Y66847D03*
X76347Y72850D03*
X71367D03*
X76347Y77842D03*
X71367D03*
X71779Y157194D03*
Y161194D03*
X71772Y421746D03*
X68365Y443677D03*
X80915Y756766D03*
X73873D03*
Y760266D03*
X69323Y776911D03*
X80915Y763766D03*
X80015Y786950D03*
X69323Y783604D03*
X81065Y791970D03*
X80015Y796989D03*
X69323Y807029D03*
Y813722D03*
Y820415D03*
X80015Y823761D03*
Y833800D03*
X81065Y828781D03*
X69323Y843840D03*
Y850533D03*
X80015Y860572D03*
X81065Y865592D03*
X69323Y857226D03*
X80015Y870611D03*
X69323Y880651D03*
Y887344D03*
Y894037D03*
X80015Y907423D03*
Y897383D03*
X81065Y902403D03*
X69323Y924155D03*
Y917462D03*
X81065Y939214D03*
X80015Y934194D03*
X69323Y930848D03*
X80015Y944234D03*
X69323Y954273D03*
Y960966D03*
Y967659D03*
Y974352D03*
Y981045D03*
Y987737D03*
Y994430D03*
Y1004470D03*
Y1034588D03*
Y1041281D03*
Y1047974D03*
Y1054667D03*
Y1071399D03*
Y1061360D03*
X80015Y1081438D03*
X81065Y1086458D03*
X69323Y1078092D03*
X80015Y1091478D03*
X69323Y1101517D03*
X80015Y1118249D03*
X69323Y1114903D03*
Y1108210D03*
X80015Y1128289D03*
X81065Y1123269D03*
X69323Y1145021D03*
Y1138328D03*
X80015Y1165100D03*
X81065Y1160080D03*
X80015Y1155060D03*
X69323Y1151714D03*
Y1175139D03*
Y1181832D03*
X80015Y1191871D03*
X69323Y1188525D03*
X81065Y1196891D03*
X80015Y1201911D03*
X69323Y1211950D03*
Y1218643D03*
X80015Y1238722D03*
Y1228682D03*
X81065Y1233702D03*
X69323Y1225336D03*
Y1248761D03*
Y1255454D03*
X76378Y1406622D03*
X74325Y1523303D03*
X68870Y1523147D03*
X71359Y1523186D03*
X81868Y1511285D03*
X81405Y1516835D03*
X81905Y1513835D03*
X81405Y1519835D03*
Y1522835D03*
X78808Y1522839D03*
X81905Y1508698D03*
X74440Y1526385D03*
X74462Y1529665D03*
X82696Y1529095D03*
X76806Y1593265D03*
X80400Y1602225D03*
X86139Y17045D03*
X95333D03*
X88148Y19541D03*
X95216Y25977D03*
X86260D03*
X93216Y23981D03*
X88260D03*
X86139Y22037D03*
X95333D03*
X93365Y19541D03*
X94284Y37106D03*
X87198D03*
Y48720D03*
X94284D03*
X87347Y71839D03*
Y66847D03*
X91457Y75340D03*
X93367Y72847D03*
Y77839D03*
X89150Y154494D03*
X93717Y159053D03*
X87654Y376026D03*
X87520Y386502D03*
X85465Y773564D03*
Y780257D03*
Y803682D03*
X94624Y795316D03*
X85465Y810375D03*
Y817068D03*
X94624Y832127D03*
X85465Y840493D03*
Y847186D03*
Y853879D03*
Y877304D03*
X94624Y868938D03*
X85465Y890690D03*
Y883997D03*
X94624Y905750D03*
X85465Y920808D03*
Y914115D03*
Y927501D03*
Y950926D03*
X94624Y942561D03*
X85465Y957619D03*
Y971005D03*
Y964312D03*
Y984391D03*
Y977698D03*
Y991084D03*
Y997777D03*
Y1004470D03*
Y1044627D03*
Y1031241D03*
Y1037934D03*
Y1051320D03*
Y1058013D03*
Y1068052D03*
Y1074745D03*
X94624Y1089805D03*
X85465Y1098171D03*
Y1104863D03*
Y1111556D03*
X94624Y1126616D03*
X85465Y1134982D03*
Y1148367D03*
Y1141675D03*
X94624Y1163427D03*
X85465Y1178486D03*
Y1171793D03*
Y1185178D03*
Y1208604D03*
X94624Y1200238D03*
X85465Y1215297D03*
Y1221989D03*
X94624Y1237049D03*
X85465Y1252108D03*
Y1245415D03*
X90501Y1338952D03*
X92791Y1341302D03*
X96191Y1337721D03*
X92941Y1346172D03*
X91000Y1350300D03*
X88500D03*
X84000Y1408000D03*
Y1412500D03*
Y1417000D03*
X97530Y1410247D03*
X93000Y1430500D03*
X84000Y1421500D03*
Y1426000D03*
X93000Y1435500D03*
Y1440000D03*
X84500D03*
X95624Y1523287D03*
X85368Y1511285D03*
X85405Y1513835D03*
X88868Y1511285D03*
X88905Y1513835D03*
X93024Y1523287D03*
X85405Y1508698D03*
X88905D03*
X97498Y1533150D03*
X95624Y1526394D03*
X95018Y1533150D03*
X88696Y1526769D03*
X93024Y1526394D03*
X88696Y1523769D03*
X97498Y1538750D03*
X95018D03*
X93029Y1705225D03*
X97683Y1722477D03*
X97928Y3001D03*
X100313Y17045D03*
X109506D03*
X109389Y25977D03*
X100433D03*
X107389Y23981D03*
X102433D03*
X100313Y22037D03*
X102321Y19541D03*
X109506Y22037D03*
X107538Y19541D03*
X108458Y37106D03*
X101371D03*
Y48720D03*
X108458D03*
X98347Y72847D03*
X104367Y71839D03*
X109347D03*
X102457Y69340D03*
X104367Y66847D03*
X109347D03*
X98347Y77839D03*
X104829Y151191D03*
X107931Y158767D03*
X99754Y155807D03*
X110616Y756766D03*
X103574D03*
Y760266D03*
X99024Y776911D03*
X110616Y763766D03*
X103574Y767266D03*
X99024Y783604D03*
X109716Y786950D03*
X110766Y791970D03*
X99024Y807029D03*
X109716Y796989D03*
X99024Y813722D03*
Y820415D03*
X109716Y823761D03*
Y833800D03*
X110766Y828781D03*
X99024Y843840D03*
Y850533D03*
Y857226D03*
X109716Y860572D03*
X110766Y865592D03*
X99024Y880651D03*
X109716Y870611D03*
X99024Y887344D03*
Y894037D03*
X109716Y897383D03*
X110766Y902403D03*
X109716Y907423D03*
X99024Y924155D03*
Y917462D03*
Y930848D03*
X110766Y939214D03*
X109716Y934194D03*
X99024Y954273D03*
X109716Y944234D03*
X99024Y960966D03*
Y967659D03*
Y974352D03*
Y981045D03*
Y987737D03*
Y994430D03*
Y1004470D03*
Y1034588D03*
Y1041281D03*
Y1047974D03*
Y1054667D03*
Y1071399D03*
Y1061360D03*
Y1078092D03*
X109716Y1081438D03*
X110766Y1086458D03*
X99024Y1101517D03*
X109716Y1091478D03*
X99024Y1114903D03*
Y1108210D03*
X109716Y1118249D03*
Y1128289D03*
X110766Y1123269D03*
X99024Y1145021D03*
Y1138328D03*
Y1151714D03*
X109716Y1165100D03*
X110766Y1160080D03*
X109716Y1155060D03*
X99024Y1175139D03*
Y1181832D03*
Y1188525D03*
X109716Y1191871D03*
X110766Y1196891D03*
X109716Y1201911D03*
X99024Y1211950D03*
Y1218643D03*
Y1225336D03*
X109716Y1228682D03*
Y1238722D03*
X110766Y1233702D03*
X99024Y1248761D03*
Y1255454D03*
X99211Y1337771D03*
X112677Y1357409D03*
X110077D03*
X107477D03*
X104877D03*
X111581Y1372872D03*
X106721Y1367272D03*
Y1372872D03*
X109151D03*
X112677Y1363473D03*
X110077D03*
X112677Y1360516D03*
X110077D03*
X107477D03*
X104877D03*
X100347Y1361417D03*
X109151Y1367272D03*
X111581D03*
X111630Y1385287D03*
X101995Y1388247D03*
X98492Y1523287D03*
X100922D03*
X109635Y1523158D03*
X106713Y1523098D03*
X103513D03*
X99978Y1533150D03*
X98492Y1526394D03*
X98424Y1529501D03*
X100922Y1526394D03*
X101024Y1529501D03*
X108861Y1528840D03*
Y1526410D03*
X101396Y1552769D03*
X99978Y1538750D03*
X106448Y1696436D03*
X119928Y3001D03*
X114486Y17045D03*
X123683D03*
X123563Y25977D03*
X114607D03*
X116607Y23981D03*
X121563D03*
X114486Y22037D03*
X116494Y19541D03*
X121712D03*
X123683Y22037D03*
X122631Y37106D03*
X115544D03*
Y48720D03*
X122631D03*
X113457Y75340D03*
X115367Y72847D03*
X120347D03*
X126367Y71842D03*
X124457Y69343D03*
X126367Y66850D03*
X115367Y77839D03*
X120347D03*
X115166Y773564D03*
Y780257D03*
X124324Y795316D03*
X115166Y803682D03*
Y810375D03*
Y817068D03*
X124324Y832127D03*
X115166Y840493D03*
Y847186D03*
Y853879D03*
Y877304D03*
X124324Y868938D03*
X115166Y890690D03*
Y883997D03*
X124324Y905750D03*
X115166Y920808D03*
Y914115D03*
Y927501D03*
Y950926D03*
X124324Y942561D03*
X115166Y957619D03*
Y971005D03*
Y964312D03*
Y984391D03*
Y977698D03*
Y991084D03*
Y997777D03*
Y1004470D03*
Y1031241D03*
Y1037934D03*
Y1044627D03*
Y1051320D03*
Y1058013D03*
Y1068052D03*
Y1074745D03*
X124324Y1089805D03*
X115166Y1098171D03*
Y1104863D03*
Y1111556D03*
X124324Y1126616D03*
X115166Y1134982D03*
Y1148367D03*
Y1141675D03*
X124324Y1163427D03*
X115166Y1178486D03*
Y1171793D03*
Y1185178D03*
Y1208604D03*
X124324Y1200238D03*
X115166Y1215297D03*
Y1221989D03*
X124324Y1237049D03*
X115166Y1252108D03*
Y1245415D03*
X124071Y1337843D03*
X126671D03*
X115277Y1357409D03*
X126491Y1354871D03*
X125241Y1357371D03*
X126491Y1352271D03*
X123891Y1354871D03*
Y1352271D03*
X120221Y1357425D03*
X126491Y1349671D03*
X123891D03*
X117777Y1357409D03*
X121207Y1360686D03*
X114405Y1509335D03*
Y1516335D03*
Y1512835D03*
Y1519835D03*
Y1522835D03*
X116905D03*
Y1519835D03*
Y1512835D03*
Y1516335D03*
Y1509335D03*
Y1526335D03*
X120052Y1712450D03*
X141928Y3001D03*
X128663Y17045D03*
X130668Y19541D03*
X128663Y22037D03*
X129718Y37106D03*
Y48720D03*
X135457Y75340D03*
X137367Y72847D03*
X142347D03*
X131347Y71842D03*
Y66850D03*
X137367Y77839D03*
X142347D03*
X128367Y202241D03*
Y207241D03*
Y197241D03*
Y212241D03*
X139440Y439000D03*
X138090Y441900D03*
X140800Y441920D03*
X134812Y530955D03*
X131861Y664958D03*
X139869Y686582D03*
X140316Y756766D03*
X133124D03*
Y760266D03*
X128724Y776911D03*
X140316Y763766D03*
X133124Y767266D03*
X139416Y786950D03*
X128724Y783604D03*
X140466Y791970D03*
X128724Y807029D03*
X139416Y796989D03*
X128724Y813722D03*
Y820415D03*
X139416Y823761D03*
Y833800D03*
X140466Y828781D03*
X128724Y843840D03*
Y850533D03*
Y857226D03*
X139416Y860572D03*
X140466Y865592D03*
X128724Y880651D03*
X139416Y870611D03*
X128724Y887344D03*
Y894037D03*
X139416Y897383D03*
X140466Y902403D03*
X139416Y907423D03*
X128724Y924155D03*
Y917462D03*
X140466Y939214D03*
X139416Y934194D03*
X128724Y930848D03*
Y954273D03*
X139416Y944234D03*
X128724Y960966D03*
Y967659D03*
Y974352D03*
Y981045D03*
Y987737D03*
Y994430D03*
Y1004470D03*
Y1034588D03*
Y1041281D03*
Y1047974D03*
Y1054667D03*
Y1071399D03*
Y1061360D03*
X139416Y1081438D03*
X140466Y1086458D03*
X128724Y1078092D03*
Y1101517D03*
X139416Y1091478D03*
X128724Y1114903D03*
X139416Y1118249D03*
X128724Y1108210D03*
X139416Y1128289D03*
X140466Y1123269D03*
X128724Y1145021D03*
Y1138328D03*
X139416Y1165100D03*
X140466Y1160080D03*
X139416Y1155060D03*
X128724Y1151714D03*
Y1175139D03*
Y1181832D03*
X139416Y1191871D03*
X128724Y1188525D03*
X140466Y1196891D03*
X139416Y1201911D03*
X128724Y1211950D03*
Y1218643D03*
Y1225336D03*
X139416Y1228682D03*
X140466Y1233702D03*
X139416Y1238722D03*
X128724Y1248761D03*
Y1255454D03*
X137551Y1337771D03*
X131791Y1337811D03*
X140077Y1357409D03*
X137477D03*
X139321Y1367272D03*
Y1372872D03*
X141751D03*
X140077Y1360516D03*
X137477D03*
X132947Y1361417D03*
X141751Y1367272D03*
X130492Y1384789D03*
X132150Y1386740D03*
X132643Y1711846D03*
X150473Y25977D03*
X157429Y23981D03*
X152473D03*
X151410Y37106D03*
Y48720D03*
X153347Y71842D03*
X148367D03*
X153347Y66850D03*
X148367D03*
X146453Y69343D03*
X150318Y233536D03*
X142660Y438930D03*
X143720Y441960D03*
X145960Y438800D03*
X146930Y441870D03*
X149210Y438640D03*
X149830Y441920D03*
X149672Y665500D03*
X152705Y683218D03*
X144866Y773564D03*
Y780257D03*
X154025Y795316D03*
X144866Y803682D03*
Y810375D03*
Y817068D03*
X154025Y832127D03*
X144866Y840493D03*
Y847186D03*
Y853879D03*
Y877304D03*
X154025Y868938D03*
X144866Y890690D03*
Y883997D03*
X154025Y905750D03*
X144866Y920808D03*
Y914115D03*
Y927501D03*
X154025Y942561D03*
X144866Y950926D03*
Y957619D03*
Y971005D03*
Y964312D03*
Y984391D03*
Y977698D03*
Y991084D03*
Y997777D03*
Y1004470D03*
Y1031241D03*
Y1037934D03*
Y1044627D03*
Y1051320D03*
Y1058013D03*
Y1068052D03*
Y1074745D03*
X154025Y1089805D03*
X144866Y1098171D03*
Y1104863D03*
Y1111556D03*
X154025Y1126616D03*
X144866Y1134982D03*
Y1148367D03*
Y1141675D03*
X154025Y1163427D03*
X144866Y1178486D03*
Y1171793D03*
Y1185178D03*
Y1208604D03*
X154025Y1200238D03*
X144866Y1215297D03*
Y1221989D03*
X154025Y1237049D03*
X144866Y1252108D03*
Y1245415D03*
X156491Y1354871D03*
Y1352271D03*
X152821Y1357425D03*
X156491Y1349671D03*
X145277Y1357409D03*
X147877D03*
X142677D03*
X150377D03*
X144181Y1367272D03*
X153767Y1360456D03*
Y1363413D03*
X144181Y1372872D03*
X142677Y1360516D03*
X145277Y1363473D03*
X142677D03*
X145277Y1360516D03*
X144230Y1385287D03*
X150900Y1433500D03*
Y1429500D03*
X143478Y1440000D03*
X151082Y1436653D03*
X146978Y1440000D03*
X147277Y1712791D03*
X152815Y1705500D03*
X155740Y1729726D03*
X163928Y3001D03*
X164525Y17045D03*
X159545D03*
X159429Y25977D03*
X164646D03*
X171602Y23981D03*
X166646D03*
X157578Y19541D03*
X166534D03*
X171751D03*
X164525Y22037D03*
X159545D03*
X158497Y37106D03*
X165584D03*
X158497Y48720D03*
X165584D03*
X158661Y75340D03*
X160571Y72847D03*
X165551D03*
X171571Y71839D03*
X169661Y69340D03*
X171571Y66847D03*
X160571Y77839D03*
X165551D03*
X172120Y416600D03*
X168950Y412950D03*
X168910Y415930D03*
X170500Y441420D03*
X167580Y441380D03*
X164870Y441360D03*
X169440Y438390D03*
X166220Y438460D03*
X162975Y760266D03*
Y756766D03*
X170017D03*
X158425Y776911D03*
X170017Y763766D03*
X162975Y767266D03*
X158425Y783604D03*
X169117Y786950D03*
X170167Y791970D03*
X158425Y807029D03*
X169117Y796989D03*
X158425Y813722D03*
Y820415D03*
X169117Y823761D03*
Y833800D03*
X170167Y828781D03*
X158425Y843840D03*
Y850533D03*
Y857226D03*
X169117Y860572D03*
X170167Y865592D03*
X158425Y880651D03*
X169117Y870611D03*
X158425Y887344D03*
Y894037D03*
X169117Y897383D03*
X170167Y902403D03*
X169117Y907423D03*
X158425Y924155D03*
Y917462D03*
Y930848D03*
X170167Y939214D03*
X169117Y934194D03*
X158425Y954273D03*
X169117Y944234D03*
X158425Y960966D03*
Y967659D03*
Y974352D03*
Y981045D03*
Y987737D03*
Y994430D03*
Y1004470D03*
Y1034588D03*
Y1041281D03*
Y1047974D03*
Y1054667D03*
Y1071399D03*
Y1061360D03*
Y1078092D03*
X169117Y1081438D03*
X170167Y1086458D03*
X158425Y1101517D03*
X169117Y1091478D03*
X158425Y1114903D03*
Y1108210D03*
X169117Y1118249D03*
Y1128289D03*
X170167Y1123269D03*
X158425Y1145021D03*
Y1138328D03*
X169117Y1165100D03*
X170167Y1160080D03*
X169117Y1155060D03*
X158425Y1151714D03*
Y1175139D03*
Y1181832D03*
Y1188525D03*
X169117Y1191871D03*
X170167Y1196891D03*
X169117Y1201911D03*
X158425Y1211950D03*
Y1218643D03*
Y1225336D03*
X169117Y1238722D03*
Y1228682D03*
X170167Y1233702D03*
X158425Y1248761D03*
Y1255454D03*
X171481Y1337853D03*
X164481Y1337813D03*
X161881D03*
X170177Y1357409D03*
X159091Y1354871D03*
X157841Y1357371D03*
X159091Y1352271D03*
Y1349671D03*
X172021Y1367272D03*
Y1372872D03*
X170177Y1360516D03*
X165647Y1361417D03*
X163192Y1384789D03*
X164850Y1386740D03*
X168661Y1459995D03*
X166751Y1462595D03*
X168661Y1465195D03*
X164650Y1529350D03*
Y1540250D03*
X171925Y1708428D03*
X167500Y1712864D03*
X171925Y1727581D03*
X157860Y1718500D03*
X185928Y3001D03*
X173719Y17045D03*
X178699D03*
X173602Y25977D03*
X173719Y22037D03*
X178699D03*
X180707Y19541D03*
X172670Y37106D03*
X179757D03*
X172670Y48720D03*
X179757D03*
X176551Y71839D03*
Y66847D03*
X180657Y75343D03*
X182571Y72850D03*
Y77842D03*
X182548Y147260D03*
X176610Y441380D03*
X175990Y438100D03*
X173710Y441330D03*
X172740Y438260D03*
X173299Y664958D03*
X172802Y682036D03*
X174567Y773564D03*
Y780257D03*
Y803682D03*
X183726Y795316D03*
X174567Y810375D03*
Y817068D03*
X183726Y832127D03*
X174567Y840493D03*
Y847186D03*
Y853879D03*
Y877304D03*
X183726Y868938D03*
X174567Y890690D03*
Y883997D03*
X183726Y905750D03*
X174567Y920808D03*
Y914115D03*
Y927501D03*
Y950926D03*
X183726Y942561D03*
X174567Y957619D03*
Y971005D03*
Y964312D03*
Y984391D03*
Y977698D03*
Y991084D03*
Y997777D03*
Y1004470D03*
Y1031241D03*
Y1037934D03*
Y1044627D03*
Y1051320D03*
Y1058013D03*
Y1068052D03*
Y1074745D03*
X183726Y1089805D03*
X174567Y1098171D03*
Y1104863D03*
Y1111556D03*
Y1134982D03*
X183726Y1126616D03*
X174567Y1148367D03*
Y1141675D03*
X183726Y1163427D03*
X174567Y1178486D03*
Y1171793D03*
Y1185178D03*
Y1208604D03*
X183726Y1200238D03*
X174567Y1215297D03*
Y1221989D03*
X183726Y1237049D03*
X174567Y1252108D03*
Y1245415D03*
X185701Y1337853D03*
X183101D03*
X174081D03*
X172777Y1357409D03*
X183077D03*
X185521Y1357425D03*
X175377Y1357409D03*
X177977D03*
X180577D03*
X176881Y1367272D03*
X174451D03*
X186467Y1360456D03*
Y1363413D03*
X172777Y1360516D03*
X176881Y1372872D03*
X174451D03*
X177977Y1363473D03*
X175377D03*
Y1360516D03*
X177977D03*
X176930Y1385287D03*
X173441Y1459995D03*
X173451Y1452895D03*
X180141Y1450295D03*
X175361D03*
X180141Y1455495D03*
X175361D03*
X173441Y1465195D03*
X186851Y1472295D03*
X177322Y1498320D03*
X173980Y1528731D03*
X185254Y1686870D03*
X179444Y1708810D03*
X184340Y1718000D03*
X194607Y25977D03*
X196607Y23981D03*
X201563D03*
X201712Y19541D03*
X195544Y37106D03*
Y48720D03*
X193571Y71839D03*
X198551D03*
X191661Y69340D03*
X193571Y66847D03*
X198551D03*
X187656Y72850D03*
Y77842D03*
X195979Y109462D03*
X203061Y131158D03*
X195690Y415390D03*
X195730Y412410D03*
X200405Y622385D03*
Y632385D03*
X192676Y760266D03*
Y756766D03*
X199718D03*
X192676Y767266D03*
X199718Y763766D03*
X188126Y776911D03*
X199868Y791970D03*
X198818Y786950D03*
X188126Y783604D03*
X198818Y796989D03*
X188126Y807029D03*
Y813722D03*
Y820415D03*
X199868Y828781D03*
X198818Y823761D03*
Y833800D03*
X188126Y843840D03*
Y850533D03*
X199868Y865592D03*
X198818Y860572D03*
X188126Y857226D03*
X198818Y870611D03*
X188126Y880651D03*
Y887344D03*
Y894037D03*
X199868Y902403D03*
X198818Y897383D03*
Y907423D03*
X188126Y917462D03*
Y924155D03*
X199868Y939214D03*
X198818Y934194D03*
X188126Y930848D03*
X198818Y944234D03*
X188126Y954273D03*
Y960966D03*
Y967659D03*
Y974352D03*
Y981045D03*
Y987737D03*
Y994430D03*
Y1004470D03*
Y1034588D03*
Y1041281D03*
Y1047974D03*
Y1054667D03*
Y1061360D03*
Y1071399D03*
X199868Y1086458D03*
X198818Y1081438D03*
X188126Y1078092D03*
X198818Y1091478D03*
X188126Y1101517D03*
X198818Y1118249D03*
X188126Y1108210D03*
Y1114903D03*
X199868Y1123269D03*
X198818Y1128289D03*
X188126Y1138328D03*
Y1145021D03*
X199868Y1160080D03*
X198818Y1155060D03*
Y1165100D03*
X188126Y1151714D03*
Y1175139D03*
X198818Y1191871D03*
X188126Y1181832D03*
Y1188525D03*
X199868Y1196891D03*
X198818Y1201911D03*
X188126Y1211950D03*
Y1218643D03*
X199868Y1233702D03*
X198818Y1228682D03*
Y1238722D03*
X188126Y1225336D03*
Y1248761D03*
Y1255454D03*
X195771Y1337903D03*
X193171D03*
X190541Y1357371D03*
X189191Y1354871D03*
Y1352271D03*
X191791Y1354871D03*
Y1352271D03*
X189191Y1349671D03*
X191791D03*
X198547Y1361417D03*
X196092Y1384789D03*
X197750Y1386740D03*
X193551Y1462595D03*
X200241Y1459995D03*
X195461D03*
X202161Y1450295D03*
X200251Y1452895D03*
X202161Y1455495D03*
X193541Y1469695D03*
X188761D03*
X193541Y1474895D03*
X188761D03*
X200241Y1465195D03*
X195461D03*
X197703Y1550897D03*
X192978Y1550797D03*
X188254D03*
X187388Y1594876D03*
X192344D03*
X199448D03*
X187388Y1589884D03*
X199448D03*
X192344D03*
X193418Y1604876D03*
Y1599884D03*
X198374D03*
Y1604876D03*
Y1611796D03*
X193418D03*
X198374Y1616788D03*
X193418D03*
X192344Y1626788D03*
X199448D03*
X192344Y1621796D03*
X199448D03*
X187388D03*
Y1626788D03*
X200848Y1655656D03*
X190242Y1656635D03*
X201120Y1668603D03*
X199040Y1666925D03*
X196366Y1664821D03*
X190271Y1671753D03*
X195153Y1679774D03*
X190391Y1701988D03*
X195300Y1694898D03*
X194000Y1712362D03*
X201531Y1715000D03*
X192745Y1707106D03*
X199547Y1704605D03*
X195150Y1723000D03*
X207928Y3001D03*
X208659Y17045D03*
X203679D03*
X208780Y25977D03*
X203563D03*
X210780Y23981D03*
X215736D03*
X210668Y19541D03*
X215885D03*
X208659Y22037D03*
X203679D03*
X202631Y37106D03*
X216804D03*
X209718D03*
X202631Y48720D03*
X209718D03*
X216804D03*
X202795Y75340D03*
X204705Y72847D03*
X209685D03*
X213791Y69343D03*
X215705Y66850D03*
Y71842D03*
X204705Y77839D03*
X209685D03*
X214107Y113022D03*
X205489Y142790D03*
X206760Y148760D03*
X206805Y622385D03*
X203605D03*
X206805Y632385D03*
X203605D03*
X204268Y773564D03*
Y780257D03*
X213427Y795316D03*
X204268Y803682D03*
Y810375D03*
Y817068D03*
X213427Y832127D03*
X204268Y840493D03*
Y847186D03*
Y853879D03*
X213427Y868938D03*
X204268Y877304D03*
Y883997D03*
Y890690D03*
X213427Y905750D03*
X204268Y914115D03*
Y920808D03*
Y927501D03*
X213427Y942561D03*
X204268Y950926D03*
Y957619D03*
Y964312D03*
Y971005D03*
Y977698D03*
Y984391D03*
Y991084D03*
Y997777D03*
Y1004470D03*
Y1031241D03*
Y1037934D03*
Y1044627D03*
Y1051320D03*
Y1058013D03*
Y1068052D03*
Y1074745D03*
X213427Y1089805D03*
X204268Y1098171D03*
Y1104863D03*
Y1111556D03*
X213427Y1126616D03*
X204268Y1134982D03*
Y1141675D03*
Y1148367D03*
X213427Y1163427D03*
X204268Y1171793D03*
Y1178486D03*
Y1185178D03*
X213427Y1200238D03*
X204268Y1208604D03*
Y1215297D03*
Y1221989D03*
X213427Y1237049D03*
X204268Y1245415D03*
Y1252108D03*
X215977Y1357409D03*
X210877D03*
X208277D03*
X213477D03*
X205677D03*
X203077D03*
X207351Y1367272D03*
X209781Y1372872D03*
X204921Y1367272D03*
Y1372872D03*
X207351D03*
X210877Y1363473D03*
X208277D03*
Y1360516D03*
X210877D03*
X205677D03*
X203077D03*
X209781Y1367272D03*
X209830Y1385287D03*
X213648Y1416262D03*
X206941Y1450295D03*
Y1455495D03*
X213651Y1472295D03*
X215561Y1469695D03*
Y1474895D03*
X216601Y1550697D03*
X202427D03*
X211876Y1550897D03*
X207152D03*
X211508Y1594876D03*
X204404D03*
X216464D03*
X211508Y1589884D03*
X204404D03*
X216464D03*
X210434Y1604876D03*
X205478D03*
X210434Y1599884D03*
X205478D03*
Y1611796D03*
X210434D03*
Y1616788D03*
X205478D03*
X211508Y1626788D03*
X216464D03*
X211508Y1621796D03*
X216464D03*
X204404Y1626788D03*
Y1621796D03*
X203807Y1681173D03*
Y1696366D03*
X211103Y1708988D03*
X229928Y3001D03*
X217853Y17045D03*
X222833D03*
X217736Y25977D03*
X217853Y22037D03*
X222833D03*
X224841Y19541D03*
X223891Y37106D03*
X230977D03*
X223891Y48720D03*
X230977D03*
X224795Y75340D03*
X226705Y72847D03*
X231685D03*
X220685Y66850D03*
Y71842D03*
X231685Y77839D03*
X226705D03*
X233653Y162074D03*
X222000Y160000D03*
X220687Y522453D03*
X226687D03*
X233493Y676906D03*
X227493D03*
X224493D03*
X230493D03*
X221493D03*
X222377Y760266D03*
Y756766D03*
X229419D03*
X222377Y767266D03*
X229419Y763119D03*
X217827Y776911D03*
X229569Y791970D03*
X228519Y786950D03*
X217827Y783604D03*
X228519Y796989D03*
X217827Y807029D03*
Y813722D03*
Y820415D03*
X229569Y828781D03*
X228519Y823761D03*
Y833800D03*
X217827Y843840D03*
Y850533D03*
X229569Y865592D03*
X228519Y860572D03*
X217827Y857226D03*
X228519Y870611D03*
X217827Y880651D03*
Y887344D03*
Y894037D03*
X229569Y902403D03*
X228519Y897383D03*
Y907423D03*
X217827Y917462D03*
Y924155D03*
X229569Y939214D03*
X228519Y934194D03*
X217827Y930848D03*
X228519Y944234D03*
X217827Y954273D03*
Y960966D03*
Y967659D03*
Y974352D03*
Y981045D03*
Y987737D03*
Y994430D03*
Y1004470D03*
Y1034588D03*
Y1041281D03*
Y1047974D03*
Y1054667D03*
Y1061360D03*
Y1071399D03*
X229569Y1086458D03*
X228519Y1081438D03*
X217827Y1078092D03*
Y1101517D03*
X228519Y1091478D03*
Y1118249D03*
X217827Y1108210D03*
Y1114903D03*
X229569Y1123269D03*
X228519Y1128289D03*
X217827Y1138328D03*
Y1145021D03*
X229569Y1160080D03*
X228519Y1155060D03*
Y1165100D03*
X217827Y1151714D03*
Y1175139D03*
X228519Y1191871D03*
X217827Y1181832D03*
Y1188525D03*
X229569Y1196891D03*
X228519Y1201911D03*
X217827Y1211950D03*
Y1218643D03*
X229569Y1233702D03*
X228519Y1228682D03*
Y1238722D03*
X217827Y1225336D03*
Y1248761D03*
Y1255454D03*
X224481Y1326418D03*
X221881D03*
X224481Y1323918D03*
X221881Y1321418D03*
X224481D03*
X221881Y1323918D03*
X230171Y1323904D03*
Y1321404D03*
X227871Y1338124D03*
X223941Y1338068D03*
X221341D03*
X230661Y1338124D03*
X224691Y1354871D03*
Y1352271D03*
X223441Y1357371D03*
X222091Y1354871D03*
Y1352271D03*
X218421Y1357425D03*
X224691Y1349671D03*
X222091D03*
X219367Y1360456D03*
Y1363413D03*
X231347Y1361417D03*
X228892Y1384789D03*
X230550Y1386740D03*
X228693Y1408885D03*
X224881Y1410685D03*
X220803Y1412115D03*
X217097Y1413863D03*
X227051Y1452895D03*
X220351Y1462595D03*
X228961Y1450295D03*
Y1455495D03*
X227041Y1459995D03*
X222261D03*
X220341Y1469695D03*
Y1474895D03*
X227041Y1465195D03*
X222261D03*
X226050Y1550897D03*
X221325Y1550797D03*
X230774Y1550897D03*
X228524Y1594876D03*
X223568D03*
Y1589884D03*
X228524D03*
X222494Y1604876D03*
X217538D03*
X222494Y1599884D03*
X217538D03*
X229598Y1604876D03*
Y1599884D03*
Y1611796D03*
X217538D03*
X222494D03*
X229598Y1616788D03*
X217538D03*
X222494D03*
X223568Y1626788D03*
X228524D03*
X223568Y1621796D03*
X228524D03*
X243486Y23005D03*
X244296Y59765D03*
X242251Y162515D03*
X246250Y204360D03*
X233438Y593556D03*
X236638D03*
X233456Y601598D03*
X236656D03*
X236674Y609640D03*
X233474D03*
X233969Y773564D03*
Y780257D03*
Y803682D03*
Y810375D03*
Y817068D03*
Y840493D03*
Y847186D03*
Y853879D03*
Y877304D03*
Y883997D03*
Y890690D03*
Y914115D03*
Y920808D03*
Y927501D03*
Y950926D03*
Y957619D03*
Y964312D03*
Y971005D03*
Y977698D03*
Y984391D03*
Y991084D03*
Y997777D03*
Y1004470D03*
Y1031241D03*
Y1037934D03*
Y1044627D03*
Y1051320D03*
Y1058013D03*
Y1068052D03*
Y1074745D03*
Y1098171D03*
Y1104863D03*
Y1111556D03*
Y1134982D03*
Y1141675D03*
Y1148367D03*
Y1171793D03*
Y1178486D03*
Y1185178D03*
Y1208604D03*
Y1215297D03*
Y1221989D03*
Y1245415D03*
Y1252108D03*
X232961Y1323904D03*
Y1321404D03*
X239561Y1338124D03*
X243677Y1357409D03*
X241077D03*
X238477D03*
X235877D03*
X246277D03*
X242581Y1367272D03*
X240151D03*
X243677Y1363473D03*
X241077D03*
Y1360516D03*
X243677D03*
X242581Y1372872D03*
X240151D03*
X237721D03*
Y1367272D03*
X238477Y1360516D03*
X235877D03*
X242630Y1385287D03*
X233194Y1407349D03*
X233741Y1450295D03*
Y1455495D03*
X240451Y1472295D03*
X242361Y1469695D03*
Y1474895D03*
X235499Y1550897D03*
X240223D03*
X244947Y1550697D03*
X240584Y1594876D03*
X235628D03*
Y1589884D03*
X240584D03*
X246614Y1604876D03*
Y1599884D03*
X234554Y1604876D03*
Y1599884D03*
X241658Y1604876D03*
Y1599884D03*
X246614Y1611796D03*
X241658D03*
X234554D03*
X246614Y1616788D03*
X241658D03*
X234554D03*
X235628Y1626788D03*
X240584D03*
X235628Y1621796D03*
X240584D03*
X251928Y3001D03*
X247716Y75865D03*
Y71865D03*
X251793Y100846D03*
X261383Y133786D03*
X258253D03*
X249735Y152694D03*
X254095Y209235D03*
X254671Y642138D03*
X258470Y775410D03*
X260671Y1338124D03*
X258071D03*
X247725Y1338141D03*
X257491Y1352271D03*
X256241Y1357371D03*
X257491Y1354871D03*
X254891Y1352271D03*
Y1354871D03*
X251221Y1357425D03*
X248777Y1357409D03*
X257491Y1349671D03*
X254891D03*
X252167Y1363413D03*
Y1360456D03*
X253851Y1452895D03*
X247151Y1462595D03*
X260541Y1450295D03*
X255761D03*
X260541Y1455495D03*
X255761D03*
X253841Y1459995D03*
X249061D03*
X253841Y1465195D03*
X249061D03*
X247141Y1469695D03*
Y1474895D03*
X259120Y1550797D03*
X254396Y1550897D03*
X249671D03*
X259748Y1594876D03*
X247688D03*
X252644D03*
X247688Y1589884D03*
X259748D03*
X252644D03*
X253718Y1604876D03*
X258674D03*
X253718Y1599884D03*
X258674D03*
Y1611796D03*
X253718D03*
X258674Y1616788D03*
X253718D03*
X252644Y1626788D03*
X259748D03*
X252644Y1621796D03*
X259748D03*
X247688Y1626788D03*
Y1621796D03*
X273928Y3001D03*
X272596Y27185D03*
X263276Y34625D03*
X271596Y40165D03*
X270364Y118415D03*
X272361Y120243D03*
X264574Y159206D03*
Y155206D03*
X267500Y220441D03*
X265100Y595078D03*
X270905Y608485D03*
X273905D03*
Y611485D03*
X272603Y692910D03*
Y695510D03*
X271491Y1291740D03*
X274091D03*
X272077Y1314370D03*
X269477D03*
X274677D03*
X272077Y1311263D03*
X269477D03*
X274677D03*
X271321Y1326726D03*
Y1321126D03*
X276181Y1326726D03*
X273751D03*
X274677Y1317327D03*
X264947Y1315271D03*
X276181Y1321126D03*
X273751D03*
X276230Y1339141D03*
X264085Y1339175D03*
X267251Y1452895D03*
X273941Y1450295D03*
X269161D03*
X273941Y1455495D03*
X269161D03*
X276637Y1523953D03*
X270139Y1548563D03*
X271808Y1594876D03*
X264704D03*
X271808Y1589884D03*
X264704D03*
X265778Y1604876D03*
X270734D03*
X265778Y1599790D03*
X270734D03*
Y1611796D03*
X265778D03*
X270734Y1616788D03*
X265778D03*
X271808Y1626788D03*
Y1621796D03*
X264704Y1626788D03*
Y1621796D03*
X291000Y14820D03*
X285896Y23965D03*
X291156Y21395D03*
X286716Y40020D03*
X285499Y53191D03*
X278989Y48720D03*
X286076D03*
X283949Y152506D03*
X288516Y157065D03*
X285260Y234000D03*
X279500Y234075D03*
X290865Y609470D03*
X277105Y608485D03*
X280305D03*
X277105Y611485D03*
X280305D03*
X286665Y609470D03*
X283705Y608485D03*
X284705Y605485D03*
X283705Y611485D03*
X287832Y674150D03*
X283921Y1291740D03*
X281321D03*
X284821Y1311279D03*
X282377Y1311263D03*
X279877D03*
X277277Y1314370D03*
Y1311263D03*
X288491Y1306125D03*
Y1308725D03*
X291091Y1306125D03*
Y1308725D03*
X288491Y1303525D03*
X291091D03*
X289841Y1311225D03*
X285767Y1314310D03*
Y1317267D03*
X277277Y1317327D03*
X283946Y1530595D03*
X286446D03*
X288824Y1594876D03*
X276764D03*
X283868D03*
Y1589884D03*
X276764D03*
X288824D03*
X277838Y1604876D03*
X282794D03*
X277838Y1599884D03*
X282794D03*
X289898Y1604876D03*
Y1599884D03*
Y1611796D03*
X282794D03*
X277838D03*
X289898Y1616788D03*
X282794D03*
X277838D03*
X283868Y1626788D03*
X288824D03*
X283868Y1621796D03*
X288824D03*
X276764Y1626788D03*
Y1621796D03*
X295928Y3001D03*
X296272Y69128D03*
X293443Y78576D03*
X293448Y82486D03*
Y85986D03*
X303043Y79376D03*
X299943Y79276D03*
X299653Y92506D03*
X299628Y149203D03*
X299624Y158706D03*
X294553Y153819D03*
X293000Y216500D03*
X294165Y609570D03*
X297838Y609585D03*
X300965Y609570D03*
X304449D03*
X305121Y726348D03*
X298991D03*
X294541Y1291378D03*
X291941D03*
X302373Y1314342D03*
X304973D03*
X302373Y1311235D03*
X304973D03*
X304217Y1326698D03*
Y1321098D03*
X297843Y1315243D03*
X295388Y1338615D03*
X297046Y1340566D03*
X305199Y1398269D03*
Y1400769D03*
X295116Y1398132D03*
Y1400632D03*
X292516D03*
Y1398132D03*
X301513Y1452895D03*
X294813Y1462595D03*
X303423Y1450295D03*
Y1455495D03*
X301503Y1459995D03*
X296723D03*
X301503Y1465195D03*
X296723D03*
X299950Y1499500D03*
X301550Y1518040D03*
Y1514420D03*
Y1510800D03*
X302042Y1528731D03*
X300884Y1594876D03*
X295928D03*
Y1589884D03*
X300884D03*
X294854Y1604876D03*
Y1599884D03*
X301958Y1604876D03*
Y1599884D03*
Y1611796D03*
X294854D03*
X301958Y1616788D03*
X294854D03*
X295928Y1626788D03*
X300884D03*
X295928Y1621796D03*
X300884D03*
X317928Y3001D03*
X306716Y39985D03*
X320053Y85806D03*
Y88806D03*
X310425Y243925D03*
X317240Y252970D03*
X308925Y260075D03*
X307865Y609570D03*
X311349Y609632D03*
X313961Y607088D03*
Y604588D03*
X319657Y696415D03*
X319621Y1291740D03*
X321387Y1306097D03*
Y1308697D03*
Y1303497D03*
X317717Y1311251D03*
X315273Y1311235D03*
X312773D03*
X307573Y1314342D03*
Y1311235D03*
X310173Y1314342D03*
Y1311235D03*
X318663Y1314282D03*
X309077Y1321098D03*
X306647D03*
X318663Y1317239D03*
X309077Y1326698D03*
X306647D03*
X307573Y1317299D03*
X310173D03*
X309126Y1339113D03*
X307799Y1400769D03*
Y1398269D03*
X318199Y1400549D03*
X314199D03*
X310399D03*
X308203Y1450295D03*
Y1455495D03*
X314913Y1472295D03*
X316823Y1469695D03*
Y1474895D03*
X321040Y1550797D03*
X316316D03*
X320048Y1594876D03*
X307988D03*
X312944D03*
X307988Y1589884D03*
X320048D03*
X312944D03*
X306914Y1604876D03*
Y1599884D03*
X314018Y1604876D03*
X318974D03*
X314018Y1599884D03*
X318974D03*
Y1611796D03*
X314018D03*
X306914D03*
X318974Y1616788D03*
X314018D03*
X306914D03*
X320048Y1626788D03*
X312944D03*
X320048Y1621796D03*
X312944D03*
X307988Y1626788D03*
Y1621796D03*
X329535Y49379D03*
X331000Y270260D03*
X328966Y543012D03*
X334744Y566086D03*
X333500Y582500D03*
Y578500D03*
X333988Y590633D03*
X329471Y1291778D03*
X322221Y1291740D03*
X326761Y1291778D03*
X335277Y1314285D03*
Y1311178D03*
X323987Y1303497D03*
Y1306097D03*
Y1308697D03*
X322737Y1311197D03*
X330747Y1315186D03*
X328292Y1338558D03*
X329950Y1340509D03*
X333830Y1396299D03*
Y1398899D03*
Y1401499D03*
Y1393799D03*
X324309Y1396599D03*
Y1399199D03*
Y1401799D03*
Y1394099D03*
X321999Y1400549D03*
X321613Y1462595D03*
X323523Y1459995D03*
X328303D03*
X328313Y1452895D03*
X335003Y1450295D03*
X330223D03*
X335003Y1455495D03*
X330223D03*
X328313Y1472295D03*
X323523Y1465195D03*
X328303D03*
X321603Y1469695D03*
Y1474895D03*
X325765Y1550897D03*
X330489Y1550697D03*
X335214Y1550897D03*
X332108Y1594876D03*
X325004D03*
X332108Y1589884D03*
X325004D03*
X326078Y1604876D03*
X331034D03*
X326078Y1599884D03*
X331034D03*
Y1611796D03*
X326078D03*
X331034Y1616788D03*
X326078D03*
X332108Y1626788D03*
X325004D03*
X332108Y1621796D03*
X325004D03*
X343036Y122525D03*
X342075Y287925D03*
X351157Y562415D03*
X345500Y574415D03*
X351157D03*
X338664Y699660D03*
X337030Y697750D03*
X340477Y1314285D03*
X337877D03*
Y1311178D03*
X340477D03*
X350621Y1311194D03*
X348177Y1311178D03*
X343077Y1314285D03*
X345677Y1311178D03*
X343077D03*
X341981Y1321041D03*
X339551D03*
X341981Y1326641D03*
X337121Y1321041D03*
X339551Y1326641D03*
X337121D03*
X340477Y1317242D03*
X343077D03*
X342030Y1339056D03*
X347110Y1398312D03*
X351110D03*
X341760Y1401449D03*
X337760D03*
X349760D03*
X345760D03*
X348413Y1462595D03*
X350323Y1459995D03*
X341713Y1472295D03*
X350323Y1465195D03*
X348403Y1469695D03*
X343623D03*
X348403Y1474895D03*
X343623D03*
X339938Y1550897D03*
X349387Y1550797D03*
X344663Y1550697D03*
X349124Y1594876D03*
X337064D03*
X344168D03*
Y1589884D03*
X337064D03*
X349124D03*
X338138Y1604876D03*
X343094D03*
X338138Y1599884D03*
X343094D03*
X350198Y1604876D03*
Y1599884D03*
Y1611796D03*
X343094D03*
X338138D03*
X350198Y1616788D03*
X343094D03*
X338138D03*
X344168Y1626788D03*
X349124D03*
X344168Y1621796D03*
X349124D03*
X337064Y1626788D03*
Y1621796D03*
X351535Y49379D03*
X366874Y135157D03*
X366771Y127665D03*
X359734Y288768D03*
X360433Y294030D03*
X355832Y297855D03*
X353700Y547893D03*
X356850D03*
X365593Y621622D03*
X364788Y1193918D03*
X364457Y1188109D03*
X359541Y1291918D03*
X362311Y1291968D03*
X356551Y1291880D03*
X353951D03*
X356891Y1306040D03*
Y1308640D03*
Y1303440D03*
X354291Y1306040D03*
Y1308640D03*
Y1303440D03*
X355641Y1311140D03*
X351567Y1314225D03*
Y1317182D03*
X363547Y1315386D03*
X361092Y1338758D03*
X362750Y1340709D03*
X355110Y1398312D03*
X359110D03*
X363110D03*
X357760Y1401449D03*
X353760D03*
X355113Y1452895D03*
X361803Y1450295D03*
X357023D03*
X361803Y1455495D03*
X357023D03*
X355103Y1459995D03*
Y1465195D03*
X354112Y1550897D03*
X358836D03*
X363561D03*
X361184Y1594876D03*
X356228D03*
Y1589884D03*
X361184D03*
X355154Y1604876D03*
Y1599884D03*
X362258Y1604876D03*
Y1599790D03*
Y1611796D03*
X355154D03*
X362258Y1616788D03*
X355154D03*
X356228Y1626788D03*
X361184D03*
X356228Y1621796D03*
X361184D03*
X373535Y49379D03*
X375920Y146577D03*
X380012Y243615D03*
X379200Y298772D03*
X367902Y303760D03*
X380771Y524903D03*
X375943D03*
X371724Y699450D03*
X370090Y697482D03*
X372000Y816862D03*
Y826362D03*
Y828862D03*
Y837862D03*
Y840362D03*
Y849362D03*
X378083Y1184949D03*
X367782Y1199648D03*
X380977Y1311378D03*
X375877Y1314485D03*
X378477Y1311378D03*
X375877D03*
X370677Y1314485D03*
X368077D03*
X373277D03*
X368077Y1311378D03*
X370677D03*
X373277D03*
X375877Y1317442D03*
X372351Y1326841D03*
X369921D03*
Y1321241D03*
X374781Y1326841D03*
X373277Y1317442D03*
X374781Y1321241D03*
X372351D03*
X374830Y1339256D03*
X379610Y1391781D03*
X375056Y1393741D03*
X375213Y1462595D03*
X377123Y1459995D03*
X368513Y1472295D03*
X377123Y1465195D03*
X375203Y1469695D03*
X370423D03*
X375203Y1474895D03*
X370423D03*
X368285Y1550897D03*
X373009Y1550697D03*
X377733Y1550897D03*
X368288Y1594876D03*
X373244D03*
X368288Y1589884D03*
X373244D03*
X367214Y1604876D03*
Y1599790D03*
X374318Y1604876D03*
X379274D03*
X374318Y1599884D03*
X379274D03*
Y1611796D03*
X374318D03*
X367214D03*
X379274Y1616788D03*
X374318D03*
X367214D03*
X373244Y1626788D03*
Y1621796D03*
X368288Y1626788D03*
Y1621796D03*
X372313Y1641759D03*
X379895Y1670046D03*
X372350Y1683284D03*
X385024Y-17575D03*
X381771Y-17589D03*
X388049Y-18895D03*
X381756Y-20104D03*
X385009Y-20090D03*
X381725Y-14717D03*
X385008Y-9673D03*
X385023Y-7158D03*
X381755Y-9687D03*
X388048Y-8478D03*
X381770Y-7172D03*
X381740Y-12202D03*
X395535Y49379D03*
X391600Y121178D03*
X387712Y147441D03*
X384600Y221800D03*
X386563Y280370D03*
X387184Y470495D03*
X387440Y525154D03*
X395657Y546894D03*
X391657Y546816D03*
X387657Y546876D03*
X384500Y810862D03*
X384499Y819862D03*
X388361Y1293713D03*
X385701Y1291828D03*
X392176Y1309859D03*
X394951Y1311259D03*
X389691Y1306240D03*
Y1308840D03*
X387091Y1306240D03*
Y1308840D03*
X389691Y1303640D03*
X387091D03*
X383421Y1311394D03*
X388441Y1311340D03*
X384367Y1314425D03*
Y1317382D03*
X392950Y1315280D03*
X392910Y1317880D03*
X395267Y1358621D03*
X393321Y1385630D03*
X388718Y1387386D03*
X384270Y1389875D03*
X395313Y1452895D03*
X381913D03*
X383823Y1450295D03*
X388603D03*
X383823Y1455495D03*
X388603D03*
X381903Y1459995D03*
Y1465195D03*
X382458Y1550897D03*
X387182Y1550797D03*
X393322Y1573347D03*
X394915Y1590018D03*
X387805Y1607802D03*
Y1604802D03*
Y1610802D03*
X387325Y1627212D03*
X385502Y1667154D03*
X394824Y1667120D03*
X389824D03*
X403734Y110326D03*
Y118976D03*
X397426Y112815D03*
Y116215D03*
X402606Y129465D03*
Y126065D03*
X403141Y144300D03*
X396237Y315507D03*
X399657Y546915D03*
X401880Y696220D03*
X404771Y698670D03*
X396129Y1334717D03*
X408459Y1330709D03*
X405859D03*
X400659D03*
X403259D03*
X408459Y1333816D03*
X405859D03*
X403259D03*
X400659D03*
X408459Y1336773D03*
X405859D03*
X402503Y1340572D03*
X407363D03*
X404933D03*
X407412Y1358587D03*
X407363Y1346172D03*
X404933D03*
X402503D03*
X410002Y1375093D03*
X405978Y1377794D03*
X401953Y1380494D03*
X397187Y1383354D03*
X397223Y1450295D03*
X402003D03*
X397223Y1455495D03*
X402003D03*
X401583Y1504872D03*
X404699Y1523953D03*
X398201Y1548563D03*
X410672Y1561170D03*
X400905Y1596091D03*
X403417Y1606224D03*
X403848Y1615354D03*
X400623Y1629772D03*
X406075Y1641000D03*
X399824Y1667120D03*
X409000Y1667025D03*
X405000Y1683500D03*
X401666Y1677925D03*
X417535Y49379D03*
X413949Y69270D03*
X414486Y127579D03*
Y124179D03*
X423521Y1311969D03*
X421091Y1311219D03*
X419673Y1325571D03*
Y1322971D03*
Y1328171D03*
X422273Y1322971D03*
Y1325571D03*
Y1328171D03*
X416949Y1336713D03*
Y1333756D03*
X424333Y1331447D03*
X411059Y1330709D03*
X416003Y1330725D03*
X413559Y1330709D03*
X421023Y1330671D03*
X414132Y1372234D03*
X415862Y1503715D03*
X422557Y1530595D03*
X420057D03*
X421059Y1569168D03*
X416163Y1594450D03*
X422007Y1592330D03*
X413100Y1607600D03*
X418293Y1607495D03*
X423379Y1607675D03*
X413200Y1612700D03*
X423439Y1612407D03*
X411515Y1599649D03*
X413100Y1617900D03*
X418500Y1618000D03*
X423349Y1617857D03*
X416962Y1634123D03*
X415437Y1636382D03*
X417365Y1630495D03*
X420765D03*
X421347Y1636668D03*
X411500Y1653500D03*
X417441Y1643946D03*
X420000Y1668075D03*
X417000Y1683500D03*
X439535Y49379D03*
X430564Y56348D03*
X430500Y72900D03*
X436090Y128007D03*
X440090Y132007D03*
X433124Y222253D03*
Y225205D03*
X439500Y484000D03*
X439284Y1038766D03*
Y1042766D03*
X431830Y1311240D03*
X438561Y1321622D03*
X432561D03*
X435561D03*
X437624Y1452895D03*
X430924Y1462595D03*
X439534Y1450295D03*
Y1455495D03*
X437614Y1459995D03*
X432834D03*
X437614Y1465195D03*
X432834D03*
X436140Y1499320D03*
X437661Y1518040D03*
Y1514420D03*
Y1510800D03*
X438153Y1528731D03*
X430239Y1581726D03*
X426688Y1598003D03*
X439283Y1608704D03*
X432559Y1627500D03*
X439404Y1615146D03*
X428000Y1640500D03*
X450102Y87011D03*
X450414Y92384D03*
X443014D03*
X452090Y116007D03*
Y124007D03*
Y132007D03*
Y128007D03*
X445997Y170701D03*
X453783Y217646D03*
X441320Y304170D03*
Y310170D03*
X449760Y497240D03*
X448688Y1305947D03*
X449440Y1308386D03*
X450220Y1310834D03*
X451083Y1313347D03*
X441561Y1321622D03*
X444561D03*
X452089Y1316074D03*
X452936Y1318775D03*
X453823Y1321436D03*
X454603Y1324033D03*
X454909Y1326721D03*
X444314Y1450295D03*
Y1455495D03*
X451024Y1472295D03*
X452934Y1469695D03*
Y1474895D03*
X452427Y1550797D03*
X440846Y1576526D03*
X451561Y1589884D03*
Y1594876D03*
X444128Y1604200D03*
Y1600200D03*
X451561Y1621796D03*
Y1626788D03*
X448776Y1622266D03*
Y1617166D03*
Y1619766D03*
X452500Y1637559D03*
X447387Y1641441D03*
X454099Y1649575D03*
X461535Y49379D03*
X457502Y87011D03*
X464456Y93101D03*
X457056D03*
X464051Y224799D03*
X460624Y244103D03*
X465925Y489925D03*
X457724Y1462595D03*
X459634Y1459995D03*
X464414D03*
X466334Y1450295D03*
X464424Y1452895D03*
X466334Y1455495D03*
X459634Y1465195D03*
X464414D03*
X457714Y1469695D03*
Y1474895D03*
X461876Y1550897D03*
X457151Y1550797D03*
X466600Y1550697D03*
X468577Y1589884D03*
Y1594876D03*
X456517Y1589884D03*
X463621D03*
Y1594876D03*
X456517D03*
X457591Y1599884D03*
X462547D03*
Y1604876D03*
X457591D03*
X462547Y1611796D03*
X457591D03*
X469651D03*
Y1599884D03*
Y1604876D03*
X462547Y1616788D03*
X457591D03*
X469651D03*
X468577Y1621796D03*
Y1626788D03*
X463621Y1621796D03*
Y1626788D03*
X456517Y1621796D03*
Y1626788D03*
X457240Y1629500D03*
X462500Y1655500D03*
X468350Y1645351D03*
X461000Y1650000D03*
X470309Y1689000D03*
X470500Y1674075D03*
X462500Y1701000D03*
X468500Y1708500D03*
X467416Y1724808D03*
X469975D03*
X464734Y1730518D03*
X483535Y49379D03*
X478949Y60029D03*
Y55135D03*
Y64975D03*
X470895Y128020D03*
X478295D03*
X482255Y127322D03*
Y135722D03*
X479630Y141942D03*
X471371Y231764D03*
X477203Y1015474D03*
X484784D03*
X477203Y1019017D03*
X484784D03*
X477203Y1022560D03*
X484784D03*
X484524Y1462595D03*
X471114Y1450295D03*
Y1455495D03*
X477824Y1472295D03*
X484514Y1469695D03*
X479734D03*
X484514Y1474895D03*
X479734D03*
X480774Y1550697D03*
X476049Y1550897D03*
X471325D03*
X480637Y1589884D03*
Y1594876D03*
X475681D03*
Y1589884D03*
X481711Y1611796D03*
Y1599884D03*
Y1604876D03*
X474607Y1611796D03*
Y1599884D03*
Y1604876D03*
X481711Y1616788D03*
X474607D03*
X475681Y1621796D03*
X480637D03*
X475681Y1626788D03*
X480637D03*
X478500Y1655500D03*
X476000Y1680000D03*
X478500Y1701000D03*
Y1714500D03*
X487590Y105969D03*
X494810D03*
X492300Y121389D03*
X487880Y131442D03*
X496280D03*
X492300Y124389D03*
X488580Y141942D03*
X494200Y158800D03*
X488260Y418980D03*
X488405Y578572D03*
X492284Y1015474D03*
Y1019017D03*
Y1022560D03*
X491224Y1452895D03*
X497914Y1450295D03*
X493134D03*
X497914Y1455495D03*
X493134D03*
X486434Y1459995D03*
X491214D03*
X486434Y1465195D03*
X491214D03*
X485498Y1550797D03*
X490223Y1550897D03*
X494947D03*
X499672D03*
X499801Y1594876D03*
X492697Y1589884D03*
X487741Y1594876D03*
X492697D03*
X499801Y1589884D03*
X487741D03*
X498727Y1611796D03*
Y1599884D03*
Y1604876D03*
X486667Y1611796D03*
X493771D03*
Y1599884D03*
Y1604876D03*
X486667Y1599884D03*
Y1604876D03*
X498727Y1616788D03*
X499801Y1621796D03*
Y1626788D03*
X486667Y1616788D03*
X493771D03*
X492697Y1621796D03*
X487741D03*
X492697Y1626788D03*
X487741D03*
X510815Y69562D03*
X502815Y106984D03*
X512654Y94967D03*
X500836Y119092D03*
X511140Y109829D03*
X511170Y224930D03*
Y227882D03*
X501500Y433000D03*
X511324Y1462595D03*
X513234Y1459995D03*
X504624Y1472295D03*
X513234Y1465195D03*
X511314Y1469695D03*
X506534D03*
X511314Y1474895D03*
X506534D03*
X513844Y1550897D03*
X509120Y1550697D03*
X504396Y1550897D03*
X511861Y1594876D03*
X504757Y1589884D03*
Y1594876D03*
X511861Y1589884D03*
X505831Y1611796D03*
X510787D03*
X505831Y1599884D03*
Y1604876D03*
X510787Y1599884D03*
Y1604876D03*
X511861Y1621796D03*
Y1626788D03*
X505831Y1616788D03*
X510787D03*
X504757Y1621796D03*
Y1626788D03*
X518843Y23788D03*
X517907Y69507D03*
X524993D03*
X516020Y102870D03*
X519240Y94967D03*
X521420Y109829D03*
X516020Y111770D03*
X518418Y137171D03*
X522831Y443712D03*
X518024Y1452895D03*
X519934Y1450295D03*
X524714D03*
X519934Y1455495D03*
X524714D03*
X518014Y1459995D03*
Y1465195D03*
X523293Y1550797D03*
X518569Y1550897D03*
X528940Y1548260D03*
X528877Y1589884D03*
Y1594876D03*
X516817Y1589884D03*
Y1594876D03*
X523921D03*
Y1589884D03*
X529951Y1611796D03*
Y1599790D03*
Y1604876D03*
X517891Y1611796D03*
X522847D03*
Y1599884D03*
X517891D03*
X522847Y1604876D03*
X517891D03*
X529951Y1616788D03*
X528877Y1621796D03*
Y1626788D03*
X517891Y1616788D03*
X522847D03*
X523921Y1621796D03*
X516817D03*
X523921Y1626788D03*
X516817D03*
X540843Y23788D03*
X542723Y39562D03*
X532080Y69507D03*
X539166D03*
X535170Y108730D03*
Y117630D03*
X533097Y246780D03*
X532000Y426500D03*
X544844Y439701D03*
X543500Y463500D03*
X540106Y657325D03*
X531424Y1452895D03*
X533334Y1450295D03*
X538114D03*
X533334Y1455495D03*
X538114D03*
X544814Y1459995D03*
X540810Y1523953D03*
X540937Y1589884D03*
Y1594876D03*
X535981D03*
Y1589884D03*
X542011Y1611796D03*
Y1599884D03*
Y1604876D03*
X534907Y1611796D03*
Y1599790D03*
Y1604876D03*
X542011Y1616788D03*
X540937Y1621796D03*
Y1626788D03*
X534907Y1616788D03*
X535981Y1621796D03*
Y1626788D03*
X548610Y57990D03*
X546253Y69507D03*
X553340D03*
X545935Y77516D03*
X553821D03*
X546400Y120700D03*
X553780Y118740D03*
Y127140D03*
X547196Y195256D03*
X546800Y262800D03*
X548856Y440452D03*
X556993Y616406D03*
X550993D03*
X553993D03*
X547993D03*
X558986Y1462595D03*
X545931Y1451344D03*
X559090Y1452185D03*
X548119Y1530595D03*
X550619D03*
X552997Y1589884D03*
X548041Y1594876D03*
X552997D03*
X548041Y1589884D03*
X559027Y1611796D03*
Y1599884D03*
Y1604876D03*
X546967Y1611796D03*
X554071D03*
Y1599884D03*
Y1604876D03*
X546967Y1599884D03*
Y1604876D03*
X559027Y1616788D03*
X546967D03*
X554071D03*
X552997Y1621796D03*
Y1626788D03*
X548041D03*
Y1621796D03*
X562843Y23788D03*
X560426Y69507D03*
X570860Y118310D03*
X565210Y125819D03*
X570860Y127510D03*
X564603Y197778D03*
Y200304D03*
X573911Y212196D03*
X569004Y228571D03*
X563230Y426508D03*
X563575Y448425D03*
X569464Y462140D03*
X559993Y616406D03*
X561580Y1242740D03*
X565686Y1452895D03*
X567596Y1450295D03*
X572376D03*
X567596Y1455495D03*
X572376D03*
X565676Y1459995D03*
X560896D03*
X565676Y1465195D03*
X560896D03*
X562860Y1499360D03*
X565723Y1510800D03*
Y1514420D03*
Y1518040D03*
X566215Y1528731D03*
X572161Y1594876D03*
X565057Y1589884D03*
X560101Y1594876D03*
X565057D03*
X572161Y1589884D03*
X560101D03*
X571087Y1611796D03*
Y1599884D03*
Y1604876D03*
X566131Y1611796D03*
Y1599884D03*
Y1604876D03*
X571087Y1616788D03*
X572161Y1621796D03*
Y1626788D03*
X566131Y1616788D03*
X565057Y1621796D03*
X560101D03*
X565057Y1626788D03*
X560101D03*
X584843Y23788D03*
X580098Y96439D03*
X576510Y125819D03*
X588554Y221277D03*
X577859Y212196D03*
X588554Y229277D03*
X575917Y421390D03*
X583505Y457925D03*
X587812Y474353D03*
X577801Y466000D03*
X578830Y1238075D03*
X578071Y1244425D03*
X588630Y1255075D03*
X583630D03*
X585786Y1462595D03*
X587696Y1459995D03*
X579086Y1472295D03*
X587696Y1465195D03*
X580996Y1469695D03*
X585776D03*
X580996Y1474895D03*
X585776D03*
X585213Y1550797D03*
X580489D03*
X589177Y1589884D03*
Y1594876D03*
X577117Y1589884D03*
Y1594876D03*
X584221D03*
Y1589884D03*
X578191Y1611796D03*
X583147D03*
Y1599884D03*
X578191D03*
X583147Y1604876D03*
X578191D03*
X589177Y1621796D03*
Y1626788D03*
X578191Y1616788D03*
X583147D03*
X584221Y1621796D03*
X577117D03*
X584221Y1626788D03*
X577117D03*
X603379Y70512D03*
X594430Y463600D03*
X592612Y805986D03*
X594330Y1238075D03*
X595671Y1245688D03*
X595598Y1251075D03*
X599659Y1241734D03*
X603947Y1258575D03*
X595947D03*
X592476Y1459995D03*
X594396Y1450295D03*
X599176D03*
X592486Y1452895D03*
X594396Y1455495D03*
X599176D03*
X592476Y1465195D03*
X599387Y1550897D03*
X604111D03*
X589938D03*
X594662Y1550697D03*
X601237Y1589884D03*
Y1594876D03*
X596281D03*
Y1589884D03*
X602311Y1611796D03*
Y1599884D03*
Y1604876D03*
X590251Y1611796D03*
X595207D03*
Y1599884D03*
X590251D03*
X595207Y1604876D03*
X590251D03*
X602311Y1616788D03*
X601237Y1621796D03*
Y1626788D03*
X590251Y1616788D03*
X595207D03*
X596281Y1621796D03*
Y1626788D03*
X606843Y23788D03*
X615190Y70533D03*
X607834Y222611D03*
X612414Y227041D03*
X605796Y425585D03*
X612969Y447260D03*
X616171Y780364D03*
X606559Y796116D03*
X612871Y1248488D03*
X612947Y1252075D03*
X609159Y1240234D03*
X612447Y1258575D03*
X616527Y1390732D03*
X619286Y1452895D03*
X612586Y1462595D03*
X614496Y1459995D03*
X619276D03*
X605886Y1472295D03*
X614496Y1465195D03*
X619276D03*
X612576Y1469695D03*
X607796D03*
X612576Y1474895D03*
X607796D03*
X613560Y1550797D03*
X618285Y1550897D03*
X608836Y1550697D03*
X613297Y1589884D03*
X608341Y1594876D03*
X613297D03*
X608341Y1589884D03*
X619327Y1611796D03*
Y1599884D03*
Y1604876D03*
X607267Y1611796D03*
X614371D03*
Y1599884D03*
Y1604876D03*
X607267Y1599884D03*
Y1604876D03*
X619327Y1616788D03*
X607267D03*
X614371D03*
X613297Y1621796D03*
X608341D03*
X613297Y1626788D03*
X608341D03*
X628843Y23788D03*
X625574Y150177D03*
X623605Y219277D03*
Y228777D03*
X624760Y424569D03*
X621916Y465088D03*
X632996Y478309D03*
X621309Y483346D03*
X634288Y766646D03*
X625976Y1450295D03*
X621196D03*
X625976Y1455495D03*
X621196D03*
X632686Y1472295D03*
X632458Y1550897D03*
X623009D03*
X627734D03*
X632461Y1594876D03*
X625357Y1589884D03*
X620401Y1594876D03*
X625357D03*
X632461Y1589884D03*
X620401D03*
X631387Y1611796D03*
Y1599790D03*
Y1604876D03*
X626431Y1611796D03*
Y1599790D03*
Y1604876D03*
X631387Y1616788D03*
X632461Y1626788D03*
Y1621796D03*
X626431Y1616788D03*
X620401Y1621796D03*
X625357D03*
X620401Y1626788D03*
X625357D03*
X627958Y1654114D03*
X645151Y69507D03*
X642394Y131172D03*
X642481Y184862D03*
X643012Y201913D03*
Y199313D03*
X635200Y415425D03*
X644673Y425816D03*
X637504Y454352D03*
X636614Y512597D03*
X647354Y776911D03*
Y783604D03*
Y807029D03*
Y813722D03*
Y820415D03*
Y843840D03*
Y850533D03*
Y857226D03*
Y880651D03*
Y887344D03*
Y894037D03*
Y917462D03*
Y924155D03*
Y930848D03*
Y954273D03*
Y960966D03*
Y967659D03*
Y974352D03*
Y981045D03*
Y987737D03*
Y994430D03*
Y1004470D03*
Y1034588D03*
Y1041281D03*
Y1047974D03*
Y1054667D03*
Y1061360D03*
Y1071399D03*
Y1078092D03*
Y1101517D03*
Y1108210D03*
Y1114903D03*
Y1138328D03*
Y1145021D03*
Y1151714D03*
Y1175139D03*
Y1181832D03*
Y1188525D03*
Y1211950D03*
Y1218643D03*
Y1225336D03*
Y1248761D03*
Y1255454D03*
X642436Y1350877D03*
X646236D03*
X638436D03*
X643563Y1392581D03*
X647445Y1392605D03*
X646086Y1452895D03*
X639386Y1462595D03*
X647996Y1450295D03*
Y1455495D03*
X641296Y1459995D03*
X646076D03*
X641296Y1465195D03*
X646076D03*
X639376Y1469695D03*
X634596D03*
X639376Y1474895D03*
X634596D03*
X646631Y1550897D03*
X637182Y1550697D03*
X641906Y1550897D03*
X637417Y1589884D03*
Y1594876D03*
X643447Y1599884D03*
X638491D03*
X643447Y1604876D03*
X638491D03*
X643447Y1611796D03*
X638491D03*
X643447Y1616788D03*
X637417Y1626788D03*
X638491Y1616788D03*
X637417Y1621796D03*
X640520Y1635483D03*
X649266Y1650126D03*
X642151Y1649961D03*
X639284Y1683049D03*
X647500Y1682850D03*
X635210Y1721545D03*
X650843Y23788D03*
X649585Y29298D03*
X663703Y32574D03*
X653570Y58363D03*
X660775Y78330D03*
X649441Y177003D03*
X662740Y375240D03*
X649500Y382500D03*
X660885Y412588D03*
X650268Y479141D03*
X649771Y505736D03*
X659398Y516260D03*
X658946Y756766D03*
X651904D03*
Y760266D03*
X663496Y773564D03*
X658946Y763766D03*
X651904Y767266D03*
X658046Y786950D03*
X663496Y780257D03*
X651754Y795316D03*
X658046Y796989D03*
X663496Y803682D03*
Y810375D03*
Y817068D03*
X651754Y832127D03*
X658046Y833800D03*
Y823761D03*
X663496Y840493D03*
Y847186D03*
X658046Y860572D03*
X663496Y853879D03*
X651754Y868938D03*
X658046Y870611D03*
X663496Y877304D03*
Y883997D03*
Y890690D03*
X651754Y905750D03*
X658046Y897383D03*
Y907423D03*
X663496Y914115D03*
Y920808D03*
X658046Y934194D03*
X663496Y927501D03*
X651754Y942561D03*
X658046Y944234D03*
X663496Y950926D03*
Y957619D03*
Y964312D03*
Y971005D03*
Y977698D03*
Y984391D03*
Y991084D03*
Y997777D03*
Y1004470D03*
Y1031241D03*
Y1037934D03*
Y1044627D03*
Y1051320D03*
Y1058013D03*
Y1068052D03*
Y1074745D03*
X651754Y1089805D03*
X658046Y1081438D03*
Y1091478D03*
X663496Y1098171D03*
Y1104863D03*
X658046Y1118249D03*
X663496Y1111556D03*
X651754Y1126616D03*
X658046Y1128289D03*
X663496Y1134982D03*
Y1141675D03*
Y1148367D03*
X651754Y1163427D03*
X658046Y1155060D03*
Y1165100D03*
X663496Y1171793D03*
Y1178486D03*
X658046Y1191871D03*
X663496Y1185178D03*
X651754Y1200238D03*
X658046Y1201911D03*
X663496Y1208604D03*
Y1215297D03*
Y1221989D03*
X651754Y1237049D03*
X658046Y1238722D03*
Y1228682D03*
X663496Y1245415D03*
Y1252108D03*
X657836Y1350877D03*
X653836D03*
X650036D03*
X661713Y1373981D03*
X655702Y1391107D03*
X659559Y1391027D03*
X655873Y1428844D03*
X652189Y1421276D03*
X659486Y1452895D03*
X661396Y1450295D03*
X652776D03*
X661396Y1455495D03*
X652776D03*
X662374Y1548563D03*
X651355Y1550797D03*
X651840Y1567752D03*
X660542Y1638169D03*
X657392Y1628137D03*
X652274Y1630366D03*
X650895Y1648115D03*
X655914Y1668744D03*
X659436Y1694697D03*
X649526Y1709274D03*
X663997Y1703111D03*
X659673Y1722174D03*
X661845Y1717340D03*
X654508Y1728000D03*
X654527Y1718229D03*
X659673Y1732836D03*
X672843Y23788D03*
X668739Y45262D03*
X677594Y36205D03*
X675887Y45262D03*
X666411Y69507D03*
X678664Y88080D03*
X673751Y78092D03*
X673691Y200672D03*
X673301Y211332D03*
X671753Y397936D03*
X670000Y457844D03*
X669955Y495468D03*
X671500Y529500D03*
X677055Y776911D03*
X667896Y791970D03*
X677055Y783604D03*
Y807029D03*
Y813722D03*
Y820415D03*
X667896Y828781D03*
X677055Y843840D03*
Y850533D03*
X667896Y865592D03*
X677055Y857226D03*
Y880651D03*
Y887344D03*
Y894037D03*
X667896Y902403D03*
X677055Y917462D03*
Y924155D03*
X667896Y939214D03*
X677055Y930848D03*
Y954273D03*
Y960966D03*
Y967659D03*
Y974352D03*
Y981045D03*
Y987737D03*
Y994430D03*
Y1004470D03*
Y1034588D03*
Y1041281D03*
Y1047974D03*
Y1054667D03*
Y1061360D03*
Y1071399D03*
X667896Y1086458D03*
X677055Y1078092D03*
Y1101517D03*
Y1108210D03*
Y1114903D03*
X667896Y1123269D03*
X677055Y1138328D03*
Y1145021D03*
X667896Y1160080D03*
X677055Y1151714D03*
Y1175139D03*
Y1181832D03*
Y1188525D03*
X667896Y1196891D03*
X677055Y1211950D03*
Y1218643D03*
X667896Y1233702D03*
X677055Y1225336D03*
Y1248761D03*
Y1255454D03*
X674552Y1351988D03*
Y1349488D03*
X666176Y1450295D03*
Y1455495D03*
X666050Y1501670D03*
X672684Y1522690D03*
X674687Y1519726D03*
X665800Y1530575D03*
X674620Y1535271D03*
Y1542125D03*
X672617Y1545089D03*
Y1538235D03*
X674894Y1629042D03*
X673982Y1639289D03*
X665802Y1652337D03*
X674486Y1647842D03*
X673480Y1662668D03*
X671631Y1690786D03*
X693672Y32684D03*
X686855Y43701D03*
X679719Y59066D03*
X682946Y69982D03*
X682891Y72642D03*
X688552Y79166D03*
X681895Y82212D03*
X685783Y78768D03*
X684954Y104968D03*
X691058Y131408D03*
X684521Y152482D03*
X688521D03*
X692521D03*
X682264Y224116D03*
X691547Y386834D03*
X688249Y405628D03*
X679862Y409320D03*
X679500Y526834D03*
X691496Y575081D03*
X688078Y675493D03*
X681605Y756766D03*
X681671Y760178D03*
X688647Y756766D03*
X693197Y773564D03*
X688647Y763766D03*
X681605Y767266D03*
X687747Y786950D03*
X693197Y780257D03*
X681455Y795316D03*
X687747Y796989D03*
X693197Y803682D03*
Y810375D03*
Y817068D03*
X681455Y832127D03*
X687747Y833800D03*
Y823761D03*
X693197Y840493D03*
Y847186D03*
X687747Y860572D03*
X693197Y853879D03*
X681455Y868938D03*
X687747Y870611D03*
X693197Y877304D03*
Y883997D03*
Y890690D03*
X681455Y905750D03*
X687747Y897383D03*
Y907423D03*
X693197Y914115D03*
Y920808D03*
X687747Y934194D03*
X693197Y927501D03*
X681455Y942561D03*
X687747Y944234D03*
X693197Y950926D03*
Y957619D03*
Y964312D03*
Y971005D03*
Y977698D03*
Y984391D03*
Y991084D03*
Y997777D03*
Y1004470D03*
Y1031241D03*
Y1037934D03*
Y1044627D03*
Y1051320D03*
Y1058013D03*
Y1068052D03*
Y1074745D03*
X681455Y1089805D03*
X687747Y1081438D03*
Y1091478D03*
X693197Y1098171D03*
Y1104863D03*
X687747Y1118249D03*
X693197Y1111556D03*
X681455Y1126616D03*
X687747Y1128289D03*
X693197Y1134982D03*
Y1141675D03*
Y1148367D03*
X681455Y1163427D03*
X687747Y1155060D03*
Y1165100D03*
X693197Y1171793D03*
Y1178486D03*
X687747Y1191871D03*
X693197Y1185178D03*
X681455Y1200238D03*
X687747Y1201911D03*
X693197Y1208604D03*
Y1215297D03*
Y1221989D03*
X681455Y1237049D03*
X687747Y1238722D03*
Y1228682D03*
X693197Y1245415D03*
Y1252108D03*
X688076Y1297506D03*
Y1305206D03*
Y1300006D03*
Y1302606D03*
X683052Y1352048D03*
Y1349548D03*
X685187Y1368700D03*
Y1363500D03*
Y1366100D03*
X687577Y1425054D03*
X688120Y1519601D03*
X683352Y1530526D03*
Y1526526D03*
X682016Y1539067D03*
X688308Y1631636D03*
X693150Y1640773D03*
X682925Y1657116D03*
X686825Y1647430D03*
X685485Y1682259D03*
X694843Y23788D03*
X701839Y45112D03*
X707608Y69718D03*
X705570Y133760D03*
X704144Y122602D03*
X707243Y123946D03*
X701927Y166535D03*
Y172441D03*
Y178346D03*
Y184252D03*
Y196063D03*
Y190157D03*
Y201968D03*
Y207874D03*
Y213779D03*
Y219685D03*
X696105Y364149D03*
X696500Y529862D03*
X700500Y545862D03*
X704500Y555862D03*
X701496Y580556D03*
X697392Y601686D03*
X697642Y733401D03*
X706756Y776911D03*
X697597Y791970D03*
X706756Y783604D03*
Y807029D03*
Y813722D03*
Y820415D03*
X697597Y828781D03*
X706756Y843840D03*
Y850533D03*
X697597Y865592D03*
X706756Y857226D03*
Y880651D03*
Y887344D03*
Y894037D03*
X697597Y902403D03*
X706756Y924155D03*
Y917462D03*
X697597Y939214D03*
X706756Y930848D03*
Y954273D03*
Y960966D03*
Y967659D03*
Y974352D03*
Y981045D03*
Y987737D03*
Y994430D03*
Y1004470D03*
Y1041281D03*
Y1034588D03*
Y1047974D03*
Y1054667D03*
Y1071399D03*
Y1061360D03*
Y1078092D03*
X697597Y1086458D03*
X706756Y1101517D03*
Y1114903D03*
Y1108210D03*
X697597Y1123269D03*
X706756Y1145021D03*
Y1138328D03*
Y1151714D03*
X697597Y1160080D03*
X706756Y1175139D03*
Y1181832D03*
Y1188525D03*
X697597Y1196891D03*
X706756Y1211950D03*
Y1218643D03*
Y1225336D03*
X697597Y1233702D03*
X706756Y1248761D03*
Y1255454D03*
X697483Y1297506D03*
Y1305206D03*
Y1300006D03*
Y1302606D03*
X701771Y1351988D03*
Y1349488D03*
X699467Y1368710D03*
Y1363510D03*
Y1366110D03*
X703568Y1379476D03*
X699610Y1580523D03*
X706681Y1627361D03*
X705833Y1633568D03*
X706089Y1643411D03*
X705815Y1654918D03*
X703473Y1663001D03*
X695400Y1685887D03*
X705366Y1684064D03*
X723479Y-28508D03*
X716843Y23788D03*
X717342Y57098D03*
X720328Y344824D03*
X711500Y360862D03*
X719500D03*
X711556Y575081D03*
X714583Y587642D03*
X715037Y603278D03*
X713280Y636897D03*
X712319Y654954D03*
X711306Y756766D03*
Y760178D03*
X718348Y756766D03*
X722898Y773564D03*
X718348Y763766D03*
X711306Y767266D03*
X722898Y780257D03*
X717448Y786950D03*
X722898Y803682D03*
X711156Y795316D03*
X717448Y796989D03*
X722898Y810375D03*
Y817068D03*
X717448Y823761D03*
Y833800D03*
X711156Y832127D03*
X722898Y847186D03*
Y840493D03*
Y853879D03*
X717448Y860572D03*
X722898Y877304D03*
X717448Y870611D03*
X711156Y868938D03*
X722898Y883997D03*
Y890690D03*
X717448Y897383D03*
Y907423D03*
X711156Y905750D03*
X722898Y920808D03*
Y914115D03*
Y927501D03*
X717448Y934194D03*
X722898Y950926D03*
X717448Y944234D03*
X711156Y942561D03*
X722898Y957619D03*
Y971005D03*
Y964312D03*
Y984391D03*
Y977698D03*
Y991084D03*
Y997777D03*
Y1004470D03*
Y1031241D03*
Y1037934D03*
Y1044627D03*
Y1051320D03*
Y1058013D03*
Y1068052D03*
Y1074745D03*
X717448Y1081438D03*
X711156Y1089805D03*
X717448Y1091478D03*
X722898Y1098171D03*
Y1104863D03*
Y1111556D03*
X717448Y1118249D03*
Y1128289D03*
X711156Y1126616D03*
X722898Y1134982D03*
Y1148367D03*
Y1141675D03*
X717448Y1165100D03*
X711156Y1163427D03*
X717448Y1155060D03*
X722898Y1178486D03*
Y1171793D03*
Y1185178D03*
X717448Y1191871D03*
X722898Y1208604D03*
X711156Y1200238D03*
X717448Y1201911D03*
X722898Y1215297D03*
Y1221989D03*
X717448Y1228682D03*
Y1238722D03*
X711156Y1237049D03*
X722898Y1252108D03*
Y1245415D03*
X721361Y1297546D03*
X711954D03*
X721361Y1305246D03*
Y1302646D03*
Y1300046D03*
X711954Y1305246D03*
Y1302646D03*
Y1300046D03*
X710221Y1351988D03*
Y1349488D03*
X716707Y1385281D03*
X719137D03*
X720233Y1378525D03*
Y1381482D03*
Y1375418D03*
X722833D03*
X714277Y1385281D03*
X715033Y1378525D03*
X717633D03*
X712433D03*
X717633Y1381482D03*
X715033Y1375418D03*
X717633D03*
X712433D03*
X719186Y1403296D03*
X719137Y1390881D03*
X714277D03*
X716707D03*
X709551Y1406578D03*
X716770Y1531459D03*
X715122Y1533378D03*
X716989Y1537249D03*
X713357Y1535212D03*
X715224Y1539083D03*
X713459Y1540917D03*
X722876Y1611343D03*
X717749Y1654921D03*
X709771Y1654927D03*
X712354Y1682279D03*
X738843Y23788D03*
X728981Y39872D03*
X736791Y39832D03*
X730131Y60757D03*
X736524Y58069D03*
X730958Y71014D03*
X738044Y71526D03*
X727944Y88972D03*
X727986Y101979D03*
X729900Y98090D03*
X727986Y105477D03*
X737624Y98858D03*
X734524Y98758D03*
X735734Y111988D03*
X726720Y574910D03*
X724001Y636790D03*
X726952Y648667D03*
X736457Y776911D03*
Y783604D03*
X727298Y791970D03*
X736457Y807029D03*
Y813722D03*
Y820415D03*
X727298Y828781D03*
X736457Y843840D03*
Y850533D03*
X727298Y865592D03*
X736457Y857226D03*
Y880651D03*
Y887344D03*
Y894037D03*
X727298Y902403D03*
X736457Y924155D03*
Y917462D03*
X727298Y939214D03*
X736457Y930848D03*
Y954273D03*
Y960966D03*
Y967659D03*
Y974352D03*
Y981045D03*
Y987737D03*
Y994430D03*
Y1004470D03*
Y1034588D03*
Y1041281D03*
Y1047974D03*
Y1054667D03*
Y1071399D03*
Y1061360D03*
X727298Y1086458D03*
X736457Y1078092D03*
Y1101517D03*
Y1114903D03*
Y1108210D03*
X727298Y1123269D03*
X736457Y1145021D03*
Y1138328D03*
X727298Y1160080D03*
X736457Y1151714D03*
Y1175139D03*
Y1181832D03*
Y1188525D03*
X727298Y1196891D03*
X736457Y1211950D03*
Y1218643D03*
X727298Y1233702D03*
X736457Y1225336D03*
Y1248761D03*
Y1255454D03*
X735954Y1297546D03*
Y1305246D03*
Y1302646D03*
Y1300046D03*
X727098Y1351977D03*
X730900Y1352131D03*
X727098Y1349077D03*
X730900Y1349231D03*
X734047Y1372880D03*
X731447D03*
X734047Y1370280D03*
Y1367680D03*
X731447D03*
Y1370280D03*
X728348Y1380832D03*
Y1377875D03*
X736280Y1379580D03*
X732797Y1375380D03*
X725333Y1375418D03*
X727777Y1375434D03*
X738230Y1402898D03*
X734925Y1657826D03*
X730302Y1658050D03*
X726302Y1658022D03*
X738370Y1677909D03*
X736001Y1695509D03*
X728454Y1690491D03*
X732434Y1690660D03*
X738550Y1693215D03*
X742841Y39832D03*
X744477Y58373D03*
X744988Y49062D03*
X747488D03*
X752261Y59782D03*
X745131Y69507D03*
X750090Y72820D03*
X745712Y212760D03*
X746705Y315647D03*
X742278Y566667D03*
X753500Y675800D03*
X748049Y756766D03*
X741007D03*
Y760266D03*
X752599Y773564D03*
X741007Y767266D03*
X748049Y763766D03*
X752599Y780257D03*
X747149Y786950D03*
X752599Y803682D03*
X747149Y796989D03*
X740857Y795316D03*
X752599Y810375D03*
Y817068D03*
X747149Y823761D03*
Y833800D03*
X740857Y832127D03*
X752599Y840493D03*
Y847186D03*
Y853879D03*
X747149Y860572D03*
X752599Y877304D03*
X747149Y870611D03*
X740857Y868938D03*
X752599Y890690D03*
Y883997D03*
X747149Y897383D03*
Y907423D03*
X740857Y905750D03*
X752599Y920808D03*
Y914115D03*
X747149Y934194D03*
X752599Y927501D03*
Y950926D03*
X747149Y944234D03*
X740857Y942561D03*
X752599Y957619D03*
Y971005D03*
Y964312D03*
Y984391D03*
Y977698D03*
Y991084D03*
Y997777D03*
Y1004470D03*
Y1031241D03*
Y1037934D03*
Y1044627D03*
Y1051320D03*
Y1058013D03*
Y1068052D03*
Y1074745D03*
X747149Y1081438D03*
X740857Y1089805D03*
X752599Y1098171D03*
Y1104863D03*
X747149Y1091478D03*
X752599Y1111556D03*
X747149Y1118249D03*
Y1128289D03*
X740857Y1126616D03*
X752599Y1134982D03*
Y1148367D03*
Y1141675D03*
X740857Y1163427D03*
X747149Y1165100D03*
Y1155060D03*
X752599Y1178486D03*
Y1171793D03*
Y1185178D03*
X747149Y1191871D03*
X752599Y1208604D03*
X740857Y1200238D03*
X747149Y1201911D03*
X752599Y1215297D03*
Y1221989D03*
X747149Y1228682D03*
Y1238722D03*
X740857Y1237049D03*
X752599Y1252108D03*
Y1245415D03*
X745475Y1297246D03*
Y1304946D03*
Y1302346D03*
Y1299746D03*
X739500Y1352031D03*
Y1349131D03*
X753015Y1381582D03*
Y1378625D03*
Y1375518D03*
X747059Y1385381D03*
X745215Y1378625D03*
X747815D03*
Y1375518D03*
X745215D03*
X750415Y1381582D03*
Y1378625D03*
Y1375518D03*
X749489Y1385381D03*
X751919D03*
X751968Y1403396D03*
X751919Y1390981D03*
X747059D03*
X749489D03*
X739888Y1404849D03*
X743740Y1657327D03*
X743039Y1643326D03*
X760843Y23788D03*
X754621Y74562D03*
X754634Y105288D03*
Y108288D03*
X762173Y123898D03*
X770073Y143438D03*
X756083Y220240D03*
X757464Y284087D03*
X754556Y283976D03*
X755335Y295589D03*
X758959Y319596D03*
X753959Y343790D03*
X766158Y776911D03*
Y783604D03*
X756999Y791970D03*
X766158Y807029D03*
Y813722D03*
Y820415D03*
X756999Y828781D03*
X766158Y843840D03*
Y850533D03*
Y857226D03*
X756999Y865592D03*
X766158Y880651D03*
Y887344D03*
Y894037D03*
X756999Y902403D03*
X766158Y924155D03*
Y917462D03*
X756999Y939214D03*
X766158Y930848D03*
Y954273D03*
Y960966D03*
Y967659D03*
Y974352D03*
Y981045D03*
Y987737D03*
Y994430D03*
Y1004470D03*
Y1041281D03*
Y1034588D03*
Y1047974D03*
Y1054667D03*
Y1071399D03*
Y1061360D03*
X756999Y1086458D03*
X766158Y1078092D03*
Y1101517D03*
Y1114903D03*
Y1108210D03*
X756999Y1123269D03*
X766158Y1145021D03*
Y1138328D03*
X756999Y1160080D03*
X766158Y1151714D03*
Y1175139D03*
Y1181832D03*
Y1188525D03*
X756999Y1196891D03*
X766158Y1211950D03*
Y1218643D03*
Y1225336D03*
X756999Y1233702D03*
X766158Y1248761D03*
Y1255454D03*
X759854Y1297246D03*
Y1304946D03*
Y1302346D03*
Y1299746D03*
X761800Y1352031D03*
Y1349131D03*
X764229Y1372880D03*
X766829D03*
Y1370380D03*
Y1367780D03*
X764229D03*
Y1370380D03*
X761130Y1380932D03*
Y1377975D03*
X755615Y1375518D03*
X758115D03*
X760559Y1375534D03*
X765579Y1375480D03*
X767381Y1676594D03*
X769475Y75360D03*
X771356Y167518D03*
X773221Y296262D03*
X780618Y296345D03*
X779121Y306155D03*
X773944Y312588D03*
X780808Y419865D03*
X777900Y756766D03*
X770708D03*
Y760266D03*
X782300Y773564D03*
X770708Y767266D03*
X777900Y763766D03*
X776850Y786950D03*
X782300Y780257D03*
X776850Y796989D03*
X770558Y795316D03*
X782300Y803682D03*
Y810375D03*
Y817068D03*
X770558Y832127D03*
X776850Y823761D03*
Y833800D03*
X782300Y847186D03*
Y840493D03*
X776850Y860572D03*
X782300Y853879D03*
Y877304D03*
X776850Y870611D03*
X770558Y868938D03*
X782300Y890690D03*
Y883997D03*
X776850Y897383D03*
Y907423D03*
X770558Y905750D03*
X782300Y920808D03*
Y914115D03*
X776850Y934194D03*
X782300Y927501D03*
X776850Y944234D03*
X770558Y942561D03*
X782300Y950926D03*
Y957619D03*
Y971005D03*
Y964312D03*
Y984391D03*
Y977698D03*
Y991084D03*
Y997777D03*
Y1004470D03*
Y1031241D03*
Y1037934D03*
Y1044627D03*
Y1051320D03*
Y1058013D03*
Y1068052D03*
Y1074745D03*
X776850Y1081438D03*
X770558Y1089805D03*
X782300Y1098171D03*
Y1104863D03*
X776850Y1091478D03*
Y1118249D03*
X782300Y1111556D03*
X776850Y1128289D03*
X770558Y1126616D03*
X782300Y1134982D03*
Y1148367D03*
Y1141675D03*
X776850Y1165100D03*
X770558Y1163427D03*
X776850Y1155060D03*
X782300Y1178486D03*
Y1171793D03*
Y1185178D03*
X776850Y1191871D03*
X782300Y1208604D03*
X770558Y1200238D03*
X776850Y1201911D03*
X782300Y1215297D03*
Y1221989D03*
X776850Y1228682D03*
Y1238722D03*
X770558Y1237049D03*
X782300Y1252108D03*
Y1245415D03*
X769521Y1297199D03*
Y1304899D03*
Y1299699D03*
Y1302299D03*
X770990Y1349091D03*
Y1351991D03*
X773069Y1375500D03*
X770469D03*
X776010Y1380750D03*
X787456Y49379D03*
X797594Y282233D03*
X797444Y271469D03*
X795668Y298801D03*
X792488Y377452D03*
X797252Y459344D03*
Y471344D03*
X794425Y541425D03*
X794059Y553559D03*
X791500Y560000D03*
X785000Y563500D03*
X795858Y776911D03*
Y783604D03*
X786700Y791970D03*
X795858Y807029D03*
Y820415D03*
Y813722D03*
X786700Y828781D03*
X795858Y843840D03*
Y850533D03*
X786700Y865592D03*
X795858Y857226D03*
Y880651D03*
Y894037D03*
Y887344D03*
X786700Y902403D03*
X795858Y924155D03*
Y917462D03*
X786700Y939214D03*
X795858Y930848D03*
Y954273D03*
Y960966D03*
Y967659D03*
Y981045D03*
Y974352D03*
Y994430D03*
Y987737D03*
Y1004470D03*
Y1041281D03*
Y1034588D03*
Y1054667D03*
Y1047974D03*
Y1071399D03*
Y1061360D03*
X786700Y1086458D03*
X795858Y1078092D03*
Y1101517D03*
Y1114903D03*
Y1108210D03*
X786700Y1123269D03*
X795858Y1145021D03*
Y1138328D03*
X786700Y1160080D03*
X795858Y1151714D03*
Y1175139D03*
Y1181832D03*
Y1188525D03*
X786700Y1196891D03*
X795858Y1218643D03*
Y1211950D03*
X786700Y1233702D03*
X795858Y1225336D03*
Y1248761D03*
Y1255454D03*
X809456Y49379D03*
X806984Y265653D03*
X798621Y312773D03*
X803264Y330102D03*
X808401Y341670D03*
X811569Y387674D03*
X813175Y422687D03*
X810360Y442079D03*
X802752Y455344D03*
X812500Y504000D03*
X807450Y756766D03*
X800408D03*
Y760266D03*
X812000Y773564D03*
X800408Y767266D03*
X812000Y780257D03*
X806550Y786950D03*
X812000Y803682D03*
X806550Y796989D03*
X800258Y795316D03*
X812000Y817068D03*
Y810375D03*
X800258Y832127D03*
X806550Y833800D03*
Y823761D03*
X812000Y847186D03*
Y840493D03*
X806550Y860572D03*
X812000Y853879D03*
Y877304D03*
X806550Y870611D03*
X800258Y868938D03*
X812000Y890690D03*
Y883997D03*
X806550Y897383D03*
Y907423D03*
X800258Y905750D03*
X812000Y920808D03*
Y914115D03*
Y927501D03*
X806550Y934194D03*
X812000Y950926D03*
X800258Y942561D03*
X806550Y944234D03*
X812000Y957619D03*
Y971005D03*
Y964312D03*
Y984391D03*
Y977698D03*
Y997777D03*
Y991084D03*
Y1004470D03*
Y1044627D03*
Y1037934D03*
Y1031241D03*
Y1058013D03*
Y1051320D03*
Y1068052D03*
Y1074745D03*
X806550Y1081438D03*
X800258Y1089805D03*
X812000Y1098171D03*
Y1104863D03*
X806550Y1091478D03*
X812000Y1111556D03*
X806550Y1118249D03*
Y1128289D03*
X800258Y1126616D03*
X812000Y1134982D03*
Y1148367D03*
Y1141675D03*
X806550Y1165100D03*
X800258Y1163427D03*
X806550Y1155060D03*
X812000Y1178486D03*
Y1171793D03*
Y1185178D03*
X806550Y1191871D03*
X812000Y1208604D03*
X806550Y1201911D03*
X800258Y1200238D03*
X812000Y1221989D03*
Y1215297D03*
X806550Y1228682D03*
Y1238722D03*
X800258Y1237049D03*
X812000Y1245415D03*
Y1252108D03*
X822699Y56712D03*
X821119Y134632D03*
X825699Y139062D03*
X816322Y284369D03*
X826665Y423425D03*
X817426Y487232D03*
X824500Y514500D03*
X817441Y517941D03*
X822559Y530876D03*
X826552Y543612D03*
X823777Y560988D03*
X816400Y828781D03*
Y865592D03*
Y902403D03*
Y939214D03*
Y1086458D03*
Y1123269D03*
Y1160080D03*
Y1196891D03*
Y1233702D03*
X826112Y1269546D03*
X833407Y-26181D03*
X836660Y-26167D03*
Y-16167D03*
X833407Y-16181D03*
X839700Y-14972D03*
X833422Y-13666D03*
X836675Y-13652D03*
X833412Y-19948D03*
X836674D03*
X836675Y-23652D03*
X833422Y-23666D03*
X839700Y-24972D03*
X833412Y52D03*
X836674D03*
X833412Y-9948D03*
X836674D03*
X836675Y-3652D03*
X833422Y-3666D03*
X839700Y-4972D03*
X833407Y-6181D03*
X836660Y-6167D03*
X836675Y16348D03*
X833422Y16334D03*
X839700Y15028D03*
X833407Y13819D03*
X836660Y13833D03*
X836674Y10052D03*
X833412D03*
X836675Y6348D03*
X833422Y6334D03*
X839700Y5028D03*
X833407Y3819D03*
X836660Y3833D03*
X836659Y24250D03*
X836674Y26765D03*
X833406Y24236D03*
X839699Y25445D03*
X833421Y26751D03*
X833376Y19206D03*
X833391Y21721D03*
X831456Y49379D03*
X836127Y62681D03*
X837792Y85186D03*
X831298Y104206D03*
X834616Y94324D03*
X842865Y110296D03*
X830340Y228143D03*
X832525Y268579D03*
X829572Y296511D03*
X840288Y287593D03*
X829167Y288063D03*
X832686Y331028D03*
X836840Y382003D03*
X841862Y390441D03*
X834430Y434634D03*
X834251Y459578D03*
X835425Y477890D03*
X830743Y500740D03*
X831756Y901318D03*
X835554Y1281324D03*
X835682Y1285472D03*
X836670Y1291355D03*
X836587Y1295333D03*
X842500Y1310000D03*
Y1306000D03*
Y1302000D03*
X834017Y1333584D03*
X834071Y1342457D03*
X839188Y1348937D03*
X841203Y1361376D03*
X853456Y49379D03*
X854108Y91232D03*
X851895Y160141D03*
X853800Y265057D03*
X847939Y265092D03*
X854334Y276117D03*
X854225Y280027D03*
Y283527D03*
X857334Y276117D03*
X852780Y291559D03*
X852801Y288562D03*
X853201Y297462D03*
X856701Y304862D03*
X846275Y335575D03*
X849750Y401280D03*
X852240Y470946D03*
X849126Y530138D03*
X845126D03*
X848660Y651127D03*
X846725Y1269785D03*
X861351Y61672D03*
X858528Y262382D03*
X860834Y276817D03*
X863934Y276917D03*
X862044Y290047D03*
X862075Y398537D03*
X872020Y413300D03*
X867590Y642420D03*
X864700Y836100D03*
X859446Y1284288D03*
X875345Y51595D03*
X877462Y139540D03*
X878221Y192055D03*
X880944Y283347D03*
Y286347D03*
X875447Y301500D03*
X884740Y316000D03*
X874500Y328000D03*
X873884Y453383D03*
X886707Y1254742D03*
Y1251742D03*
X881807Y1248920D03*
Y1245920D03*
X881937Y1251857D03*
X877480Y1248844D03*
X886707Y1257742D03*
X885000Y1307500D03*
X877000Y1340241D03*
X884462Y1446974D03*
X876044Y1444317D03*
X898720Y145206D03*
X888560Y469527D03*
X902376Y594657D03*
X903556Y614062D03*
X899678Y601043D03*
X897824Y909093D03*
X891648Y1137843D03*
X900723Y1146553D03*
X896107Y1254742D03*
Y1251742D03*
X896907Y1245920D03*
Y1248920D03*
X896107Y1257742D03*
X917386Y179500D03*
Y177000D03*
Y169500D03*
Y172000D03*
Y174500D03*
Y167000D03*
X909298Y195925D03*
X909161Y203012D03*
X909320Y210098D03*
Y217185D03*
Y224271D03*
Y231358D03*
X914575Y560027D03*
X906597Y579695D03*
X907035Y590172D03*
X906597Y628426D03*
X906734Y619373D03*
X906570Y663930D03*
X906387Y818471D03*
X903941Y874000D03*
X917622Y887545D03*
X909000Y909000D03*
X905000D03*
X904719Y921792D03*
X911500Y931000D03*
X908500Y927500D03*
X909890Y950217D03*
X910066Y960332D03*
X909203Y970709D03*
X916763Y972343D03*
X908799Y985291D03*
X910707Y1254742D03*
Y1251742D03*
X905007Y1248920D03*
Y1245920D03*
X905074Y1252177D03*
X910707Y1257742D03*
X920720Y145206D03*
X919886Y167000D03*
Y169500D03*
Y172000D03*
Y174500D03*
Y177000D03*
Y179500D03*
X927134Y189386D03*
X925321Y203399D03*
X926983Y604751D03*
X927127Y619251D03*
X930926Y664791D03*
X923916Y843990D03*
X918500Y856925D03*
X930925Y860925D03*
X929603Y889000D03*
X931948Y891397D03*
X919916Y908916D03*
X920276Y900554D03*
X931877Y918168D03*
X928535Y913454D03*
X920409Y918274D03*
X918000Y928000D03*
X926062Y938727D03*
X926004Y952716D03*
X925200Y1110443D03*
Y1107843D03*
Y1117443D03*
Y1114843D03*
Y1124443D03*
Y1121843D03*
Y1131443D03*
Y1128843D03*
X920107Y1251742D03*
Y1254742D03*
Y1248920D03*
Y1245920D03*
Y1257742D03*
X924000Y1310000D03*
X920738Y1321363D03*
X927869Y1317417D03*
X923680Y1339520D03*
X919758Y1348990D03*
X931798Y1660762D03*
X923798D03*
X945006Y593609D03*
X935649Y590751D03*
X939391Y600571D03*
X946366Y668811D03*
X940391Y859947D03*
X944057Y882886D03*
X940514Y918134D03*
X933021Y933979D03*
X939670Y945169D03*
X942924Y982547D03*
X943135Y977129D03*
X938507Y1137843D03*
X945691Y1254742D03*
Y1251742D03*
X940791Y1248920D03*
Y1245920D03*
X940921Y1251857D03*
X936464Y1248844D03*
X945691Y1257742D03*
X938000Y1309500D03*
Y1301500D03*
Y1304500D03*
X933586Y1325501D03*
X933041Y1315920D03*
X944406Y1532791D03*
X939798Y1660762D03*
X955529Y614017D03*
X951839Y812730D03*
X958051Y859384D03*
X952425Y876575D03*
X948060Y891468D03*
X951367Y913648D03*
X951500Y930925D03*
X955091Y1254742D03*
Y1251742D03*
X955891Y1245920D03*
Y1248920D03*
X955000Y1267000D03*
X955091Y1257742D03*
X955000Y1271000D03*
Y1275000D03*
Y1279000D03*
X960518Y1656185D03*
X957758D03*
X957848Y1659375D03*
X960608D03*
X960558Y1662015D03*
X957798D03*
X947798Y1660762D03*
X964720Y145206D03*
X975689Y156950D03*
Y153950D03*
X971192Y219589D03*
X968692D03*
X973616Y317648D03*
X963134Y882936D03*
X968919Y1116177D03*
Y1118777D03*
Y1109177D03*
Y1111777D03*
X968800Y1130046D03*
Y1132646D03*
X968919Y1123177D03*
Y1125777D03*
X969691Y1254742D03*
Y1251742D03*
X963991Y1248920D03*
Y1245920D03*
X964058Y1252177D03*
X969691Y1257742D03*
X975000Y1307500D03*
X967500Y1340241D03*
X963120Y1520080D03*
Y1523080D03*
Y1526080D03*
X976858Y1656185D03*
X976898Y1662015D03*
X976948Y1659375D03*
X986720Y145206D03*
X988593Y189347D03*
X981445Y185389D03*
X982455Y264781D03*
Y275443D03*
X989227Y389311D03*
X992037Y485369D03*
X979091Y1251742D03*
Y1254742D03*
Y1248920D03*
Y1245920D03*
Y1257742D03*
X986486Y1523080D03*
Y1520080D03*
Y1526080D03*
X985318Y1656105D03*
X988078D03*
X979618Y1656185D03*
X985358Y1661935D03*
X988118D03*
X985408Y1659295D03*
X988168D03*
X979658Y1662015D03*
X979708Y1659375D03*
X995189Y263340D03*
Y274002D03*
X992915Y280389D03*
X1007083Y363461D03*
X996232Y424440D03*
X999304Y1282574D03*
Y1289215D03*
X999303Y1285693D03*
X1004418Y1656105D03*
X1007178D03*
X1004508Y1659295D03*
X1004458Y1661935D03*
X1008720Y145206D03*
X1020661Y146580D03*
X1023221Y191574D03*
X1019803Y218099D03*
X1017870Y294386D03*
X1009618Y396125D03*
X1021425Y404925D03*
X1013365Y433426D03*
X1008789Y488642D03*
Y493655D03*
X1012211Y547574D03*
X1015061D03*
X1015961Y554432D03*
X1007703Y759012D03*
X1007587Y800384D03*
Y802884D03*
Y811352D03*
Y813852D03*
Y822252D03*
Y824752D03*
Y833356D03*
Y835856D03*
Y844256D03*
X1021908Y1289124D03*
X1019314Y1289159D03*
X1017069Y1290346D03*
X1013500Y1312500D03*
X1013000Y1306500D03*
X1013500Y1325500D03*
X1011500Y1335000D03*
X1013500Y1344500D03*
X1009852Y1523080D03*
Y1520080D03*
Y1526080D03*
X1007268Y1659295D03*
X1007218Y1661935D03*
X1023187Y146580D03*
X1027724Y397726D03*
X1030525Y391362D03*
X1027760Y451832D03*
X1022461Y558932D03*
X1027579D03*
X1032579Y559934D03*
X1025493Y768719D03*
X1035645Y773582D03*
X1033218Y1523080D03*
Y1520080D03*
Y1526080D03*
X1033798Y1656675D03*
X1033748Y1659315D03*
X1040199Y49379D03*
X1040891Y406586D03*
X1045100Y427059D03*
X1045015Y444404D03*
X1041254Y523874D03*
X1043180Y547027D03*
X1040890Y735717D03*
X1050015Y756765D03*
Y760265D03*
X1045465Y776910D03*
X1050015Y767265D03*
X1045465Y783603D03*
X1041065Y795315D03*
X1045465Y807028D03*
Y813721D03*
Y820414D03*
X1041065Y832126D03*
X1045465Y850532D03*
Y843839D03*
Y857225D03*
X1041065Y868937D03*
X1045465Y880650D03*
Y887343D03*
Y894036D03*
X1041065Y905749D03*
X1045465Y917461D03*
Y924154D03*
Y930847D03*
X1041065Y942560D03*
X1045465Y954272D03*
Y967658D03*
Y960965D03*
Y974351D03*
Y981044D03*
Y987736D03*
Y994429D03*
Y1004469D03*
Y1041280D03*
Y1034587D03*
Y1047973D03*
Y1054666D03*
Y1061359D03*
Y1071398D03*
Y1078091D03*
X1041065Y1089804D03*
X1045465Y1101516D03*
Y1108209D03*
Y1114902D03*
X1041065Y1126615D03*
X1045465Y1138327D03*
Y1145020D03*
Y1151713D03*
X1041065Y1163426D03*
X1045465Y1175138D03*
Y1188524D03*
Y1181831D03*
X1041065Y1200237D03*
X1045465Y1211949D03*
Y1218642D03*
X1041065Y1237048D03*
X1045465Y1225335D03*
Y1248760D03*
Y1255453D03*
X1048684Y1350724D03*
X1051684D03*
X1050866Y1659548D03*
X1062199Y49379D03*
X1061456Y406560D03*
X1063614Y733409D03*
X1057057Y756765D03*
X1061607Y773563D03*
X1057057Y763765D03*
X1057207Y791969D03*
X1056157Y786949D03*
X1061607Y780256D03*
Y803681D03*
X1056157Y796988D03*
X1061607Y810374D03*
Y817067D03*
X1056157Y823760D03*
Y833799D03*
X1057207Y828780D03*
X1061607Y847185D03*
Y840492D03*
Y853878D03*
X1056157Y860571D03*
X1057207Y865591D03*
X1056157Y870610D03*
X1061607Y877303D03*
Y883996D03*
Y890689D03*
X1056157Y907422D03*
Y897382D03*
X1057207Y902402D03*
X1061607Y914114D03*
Y920807D03*
Y927500D03*
X1056157Y934193D03*
X1057207Y939213D03*
X1061607Y950925D03*
X1056157Y944233D03*
X1061607Y964311D03*
Y971004D03*
Y957618D03*
Y977697D03*
Y984390D03*
Y991083D03*
Y997776D03*
Y1004469D03*
Y1037933D03*
Y1044626D03*
Y1031240D03*
Y1051319D03*
Y1058012D03*
Y1074744D03*
Y1068051D03*
X1057207Y1086457D03*
X1056157Y1081437D03*
Y1091477D03*
X1061607Y1098170D03*
Y1104862D03*
X1056157Y1118248D03*
X1061607Y1111555D03*
Y1134981D03*
X1057207Y1123268D03*
X1056157Y1128288D03*
X1061607Y1141674D03*
Y1148366D03*
X1056157Y1155059D03*
Y1165099D03*
X1057207Y1160079D03*
X1061607Y1171792D03*
Y1178485D03*
X1056157Y1191870D03*
X1061607Y1185177D03*
X1056157Y1201910D03*
X1057207Y1196890D03*
X1061607Y1208603D03*
Y1215296D03*
Y1221988D03*
X1056157Y1238721D03*
X1057207Y1233701D03*
X1056157Y1228681D03*
X1061607Y1245414D03*
Y1252107D03*
X1060684Y1350724D03*
X1057684D03*
X1054684D03*
X1056584Y1523080D03*
Y1520080D03*
Y1526080D03*
X1063751Y1653834D03*
X1064221Y1662726D03*
X1068221Y1662778D03*
X1068827Y389734D03*
X1074800Y391262D03*
X1077418Y411322D03*
Y416763D03*
Y421922D03*
X1081133Y461516D03*
X1071239Y479655D03*
X1081632Y648854D03*
X1079716Y756765D03*
Y760265D03*
Y767265D03*
X1075166Y776910D03*
Y783603D03*
X1070766Y795315D03*
X1075166Y807028D03*
Y813721D03*
Y820414D03*
X1070766Y832126D03*
X1075166Y850532D03*
Y843839D03*
Y857225D03*
X1070766Y868937D03*
X1075166Y880650D03*
Y887343D03*
Y894036D03*
X1070766Y905749D03*
X1075166Y917461D03*
Y924154D03*
Y930847D03*
X1070766Y942560D03*
X1075166Y954272D03*
Y967658D03*
Y960965D03*
Y974351D03*
Y981044D03*
Y987736D03*
Y994429D03*
Y1004469D03*
Y1034587D03*
Y1041280D03*
Y1047973D03*
Y1054666D03*
Y1061359D03*
Y1071398D03*
Y1078091D03*
X1070766Y1089804D03*
X1075166Y1101516D03*
Y1108209D03*
Y1114902D03*
X1070766Y1126615D03*
X1075166Y1138327D03*
Y1145020D03*
Y1151713D03*
X1070766Y1163426D03*
X1075166Y1175138D03*
Y1188524D03*
Y1181831D03*
X1070766Y1200237D03*
X1075166Y1211949D03*
Y1218642D03*
X1070766Y1237048D03*
X1075166Y1225335D03*
Y1248760D03*
Y1255453D03*
X1070949Y1337752D03*
X1067929Y1337702D03*
X1079215Y1357390D03*
X1076615D03*
X1071908Y1361660D03*
X1080889Y1367253D03*
X1076615Y1360497D03*
X1079215D03*
X1078459Y1367253D03*
Y1372853D03*
X1080889D03*
X1073733Y1388198D03*
X1068094Y1654099D03*
X1084199Y49379D03*
X1086936Y370532D03*
X1083583Y395195D03*
X1093722Y427960D03*
X1087000Y477500D03*
X1096473Y484391D03*
Y489391D03*
X1088730Y509362D03*
X1086758Y756765D03*
X1091308Y773563D03*
X1086758Y763765D03*
X1086908Y791969D03*
X1091308Y780256D03*
X1085858Y786949D03*
X1091308Y803681D03*
X1085858Y796988D03*
X1091308Y810374D03*
Y817067D03*
X1085858Y823760D03*
Y833799D03*
X1086908Y828780D03*
X1091308Y840492D03*
Y847185D03*
Y853878D03*
X1085858Y860571D03*
X1086908Y865591D03*
X1085858Y870610D03*
X1091308Y877303D03*
Y883996D03*
Y890689D03*
X1085858Y907422D03*
Y897382D03*
X1086908Y902402D03*
X1091308Y914114D03*
Y920807D03*
X1085858Y934193D03*
X1091308Y927500D03*
X1086908Y939213D03*
X1085858Y944233D03*
X1091308Y950925D03*
Y964311D03*
Y971004D03*
Y957618D03*
Y977697D03*
Y984390D03*
Y991083D03*
Y997776D03*
Y1004469D03*
Y1031240D03*
Y1037933D03*
Y1044626D03*
Y1051319D03*
Y1058012D03*
Y1074744D03*
Y1068051D03*
X1086908Y1086457D03*
X1085858Y1081437D03*
Y1091477D03*
X1091308Y1098170D03*
Y1104862D03*
X1085858Y1118248D03*
X1091308Y1111555D03*
Y1134981D03*
X1086908Y1123268D03*
X1085858Y1128288D03*
X1091308Y1141674D03*
Y1148366D03*
X1085858Y1155059D03*
Y1165099D03*
X1086908Y1160079D03*
X1091308Y1171792D03*
Y1178485D03*
X1085858Y1191870D03*
X1091308Y1185177D03*
X1085858Y1201910D03*
X1086908Y1196890D03*
X1091308Y1208603D03*
Y1215296D03*
Y1221988D03*
X1085858Y1238721D03*
Y1228681D03*
X1086908Y1233701D03*
X1091308Y1245414D03*
Y1252107D03*
X1095809Y1337824D03*
X1087015Y1357390D03*
X1095629Y1352252D03*
Y1349652D03*
Y1354852D03*
X1089515Y1357390D03*
X1091959Y1357406D03*
X1084415Y1357390D03*
X1081815D03*
X1092905Y1363394D03*
Y1360437D03*
X1083319Y1367253D03*
X1081815Y1360497D03*
X1084415D03*
X1081815Y1363454D03*
X1084415D03*
X1083319Y1372853D03*
X1083368Y1385268D03*
X1096469Y1643468D03*
X1090143Y1643625D03*
X1091026Y1653031D03*
X1092030Y1720841D03*
X1106199Y49379D03*
X1101942Y395361D03*
X1109416Y756765D03*
Y760265D03*
Y767265D03*
X1104866Y776910D03*
Y783603D03*
X1100466Y795315D03*
X1104866Y807028D03*
Y813721D03*
Y820414D03*
X1100466Y832126D03*
X1104866Y850532D03*
Y843839D03*
Y857225D03*
X1100466Y868937D03*
X1104866Y880650D03*
Y887343D03*
Y894036D03*
X1100466Y905749D03*
X1104866Y917461D03*
Y924154D03*
Y930847D03*
X1100466Y942560D03*
X1104866Y954272D03*
Y967658D03*
Y960965D03*
Y974351D03*
Y981044D03*
Y987736D03*
Y994429D03*
Y1004469D03*
Y1034587D03*
Y1041280D03*
Y1047973D03*
Y1054666D03*
Y1071398D03*
Y1061359D03*
Y1078091D03*
X1100466Y1089804D03*
X1104866Y1101516D03*
Y1108209D03*
Y1114902D03*
X1100466Y1126615D03*
X1104866Y1138327D03*
Y1145020D03*
Y1151713D03*
X1100466Y1163426D03*
X1104866Y1175138D03*
Y1188524D03*
Y1181831D03*
X1100466Y1200237D03*
X1104866Y1211949D03*
Y1218642D03*
X1100466Y1237048D03*
X1104866Y1225335D03*
Y1248760D03*
Y1255453D03*
X1103529Y1337792D03*
X1109289Y1337752D03*
X1098409Y1337824D03*
X1109215Y1357390D03*
X1098229Y1352252D03*
Y1349652D03*
X1096979Y1357352D03*
X1098229Y1354852D03*
X1104448Y1361680D03*
X1109215Y1360497D03*
X1111059Y1367253D03*
Y1372853D03*
X1103888Y1386721D03*
X1102230Y1384770D03*
X1105000Y1682132D03*
X1109521Y1724109D03*
X1113943Y452055D03*
X1116458Y756765D03*
X1121008Y773563D03*
X1116459Y763765D03*
X1116608Y791969D03*
X1121008Y780256D03*
X1115558Y786949D03*
X1121008Y803681D03*
X1115558Y796988D03*
X1121008Y810374D03*
Y817067D03*
X1115558Y823760D03*
Y833799D03*
X1116608Y828780D03*
X1121008Y847185D03*
Y840492D03*
Y853878D03*
X1115558Y860571D03*
X1116608Y865591D03*
X1115558Y870610D03*
X1121008Y877303D03*
Y883996D03*
Y890689D03*
X1115558Y907422D03*
Y897382D03*
X1116608Y902402D03*
X1121008Y914114D03*
Y920807D03*
X1115558Y934193D03*
X1121008Y927500D03*
X1116608Y939213D03*
X1115558Y944233D03*
X1121008Y950925D03*
Y964311D03*
Y971004D03*
Y957618D03*
Y977697D03*
Y984390D03*
Y991083D03*
Y997776D03*
Y1004469D03*
Y1031240D03*
Y1037933D03*
Y1044626D03*
Y1051319D03*
Y1058012D03*
Y1074744D03*
Y1068051D03*
X1116608Y1086457D03*
X1115558Y1081437D03*
Y1091477D03*
X1121008Y1098170D03*
Y1104862D03*
X1115558Y1118248D03*
X1121008Y1111555D03*
Y1134981D03*
X1116608Y1123268D03*
X1115558Y1128288D03*
X1121008Y1141674D03*
Y1148366D03*
X1115558Y1155059D03*
Y1165099D03*
X1116608Y1160079D03*
X1121008Y1171792D03*
Y1178485D03*
X1115558Y1191870D03*
X1121008Y1185177D03*
X1115558Y1201910D03*
X1116608Y1196890D03*
X1121008Y1208603D03*
Y1215296D03*
Y1221988D03*
X1115558Y1238721D03*
Y1228681D03*
X1116608Y1233701D03*
X1121008Y1245414D03*
Y1252107D03*
X1119615Y1357390D03*
X1122115D03*
X1124559Y1357406D03*
X1117015Y1357390D03*
X1111815D03*
X1114415D03*
X1117015Y1363454D03*
Y1360497D03*
X1115919Y1372853D03*
X1125505Y1363394D03*
Y1360437D03*
X1115919Y1367253D03*
X1113489D03*
X1114415Y1363454D03*
X1111815Y1360497D03*
X1114415D03*
X1113489Y1372853D03*
X1115968Y1385268D03*
X1117946Y1467955D03*
X1117828Y1473091D03*
X1118326Y1594118D03*
X1118004Y1584908D03*
X1113785Y1601462D03*
X1117263Y1601526D03*
X1115394Y1620306D03*
X1120376Y1641684D03*
X1125487Y1641754D03*
X1125771Y1652189D03*
X1120595Y1652037D03*
X1120200Y1646597D03*
X1116000Y1671029D03*
X1125732Y1666072D03*
X1120303Y1682055D03*
X1113948Y1714244D03*
X1128199Y49379D03*
X1142830Y53186D03*
X1139200Y380533D03*
Y385698D03*
X1127471Y404788D03*
X1132387Y615658D03*
X1139117Y756765D03*
Y760265D03*
Y767265D03*
X1134567Y776910D03*
Y783603D03*
X1130167Y795315D03*
X1134567Y807028D03*
Y813721D03*
Y820414D03*
X1130167Y832126D03*
X1134567Y850532D03*
Y843839D03*
Y857225D03*
X1130167Y868937D03*
X1134567Y880650D03*
Y887343D03*
Y894036D03*
X1130167Y905749D03*
X1134567Y917461D03*
Y924154D03*
Y930847D03*
X1130167Y942560D03*
X1134567Y954272D03*
Y967658D03*
Y960965D03*
Y974351D03*
Y981044D03*
Y987736D03*
Y994429D03*
Y1004469D03*
Y1034587D03*
Y1041280D03*
Y1047973D03*
Y1054666D03*
Y1061359D03*
Y1071398D03*
X1130167Y1089804D03*
X1134567Y1078091D03*
Y1101516D03*
Y1108209D03*
Y1114902D03*
X1130167Y1126615D03*
X1134567Y1138327D03*
Y1145020D03*
X1130167Y1163426D03*
X1134567Y1151713D03*
Y1175138D03*
Y1188524D03*
Y1181831D03*
X1130167Y1200237D03*
X1134567Y1211949D03*
Y1218642D03*
X1130167Y1237048D03*
X1134567Y1225335D03*
Y1248760D03*
Y1255453D03*
X1136219Y1337794D03*
X1133619D03*
X1130829Y1352252D03*
Y1349652D03*
Y1354852D03*
X1128229Y1352252D03*
Y1349652D03*
X1129579Y1357352D03*
X1128229Y1354852D03*
X1137218Y1361660D03*
X1136588Y1386721D03*
X1134930Y1384770D03*
X1137846Y1453487D03*
X1135043Y1553371D03*
X1137523Y1579453D03*
X1136173Y1573638D03*
X1131790Y1597984D03*
X1131832Y1607245D03*
X1132168Y1620860D03*
X1138752Y1624627D03*
X1130772Y1641753D03*
X1130684Y1646949D03*
X1130245Y1652189D03*
X1140117Y1671421D03*
X1132209Y1672033D03*
X1129230Y1666174D03*
X1137492Y1685240D03*
X1128934Y1688600D03*
X1150199Y49379D03*
X1155577Y73939D03*
X1147813Y492319D03*
X1146159Y756765D03*
X1150709Y773563D03*
X1146160Y763765D03*
X1146309Y791969D03*
X1145259Y786949D03*
X1150709Y780256D03*
X1145259Y796988D03*
X1150709Y803681D03*
Y810374D03*
Y817067D03*
X1146309Y828780D03*
X1145259Y823760D03*
Y833799D03*
X1150709Y840492D03*
Y847185D03*
X1146309Y865591D03*
X1145259Y860571D03*
X1150709Y853878D03*
X1145259Y870610D03*
X1150709Y877303D03*
Y883996D03*
Y890689D03*
X1145259Y907422D03*
X1146309Y902402D03*
X1145259Y897382D03*
X1150709Y914114D03*
Y920807D03*
X1145259Y934193D03*
X1146309Y939213D03*
X1150709Y927500D03*
X1145259Y944233D03*
X1150709Y950925D03*
Y964311D03*
Y971004D03*
Y957618D03*
Y977697D03*
Y984390D03*
Y991083D03*
Y997776D03*
Y1004469D03*
Y1031240D03*
Y1037933D03*
Y1044626D03*
Y1051319D03*
Y1058012D03*
Y1074744D03*
Y1068051D03*
X1146309Y1086457D03*
X1145259Y1081437D03*
Y1091477D03*
X1150709Y1098170D03*
Y1104862D03*
X1145259Y1118248D03*
X1150709Y1111555D03*
Y1134981D03*
X1146309Y1123268D03*
X1145259Y1128288D03*
X1150709Y1141674D03*
Y1148366D03*
X1145259Y1155059D03*
X1146309Y1160079D03*
X1145259Y1165099D03*
X1150709Y1171792D03*
Y1178485D03*
X1145259Y1191870D03*
X1150709Y1185177D03*
X1145259Y1201910D03*
X1146309Y1196890D03*
X1150709Y1208603D03*
Y1215296D03*
Y1221988D03*
X1145259Y1238721D03*
X1146309Y1233701D03*
X1145259Y1228681D03*
X1150709Y1245414D03*
Y1252107D03*
X1154839Y1337834D03*
X1145819D03*
X1143219D03*
X1152315Y1357390D03*
X1154815D03*
X1147115D03*
X1149715D03*
X1141915D03*
X1144515D03*
X1147115Y1360497D03*
X1149715Y1363454D03*
Y1360497D03*
X1147115Y1363454D03*
X1146189Y1372853D03*
X1148619D03*
Y1367253D03*
X1146189D03*
X1141915Y1360497D03*
X1144515D03*
X1143759Y1367253D03*
Y1372853D03*
X1148668Y1385268D03*
X1150458Y1433146D03*
X1144118Y1449628D03*
X1151384Y1556029D03*
X1143063Y1580334D03*
X1152186Y1570567D03*
X1149278Y1589453D03*
X1145060Y1588837D03*
X1141645Y1640017D03*
X1146316Y1649422D03*
X1143127Y1649068D03*
X1144107Y1671118D03*
X1146477Y1658441D03*
X1168687Y74202D03*
X1163113Y481691D03*
X1165589Y569118D03*
X1168818Y756765D03*
Y760265D03*
X1164268Y776910D03*
X1168818Y767265D03*
X1164268Y783603D03*
X1159868Y795315D03*
X1164268Y807028D03*
Y820414D03*
Y813721D03*
X1159868Y832126D03*
X1164268Y850532D03*
Y843839D03*
Y857225D03*
X1159868Y868937D03*
X1164268Y880650D03*
Y887343D03*
Y894036D03*
X1159868Y905749D03*
X1164268Y917461D03*
Y924154D03*
Y930847D03*
X1159868Y942560D03*
X1164268Y954272D03*
Y960965D03*
Y967658D03*
Y974351D03*
Y981044D03*
Y987736D03*
Y994429D03*
Y1004469D03*
Y1034587D03*
Y1041280D03*
Y1047973D03*
Y1054666D03*
Y1061359D03*
Y1071398D03*
X1159868Y1089804D03*
X1164268Y1078091D03*
Y1101516D03*
Y1108209D03*
Y1114902D03*
X1159868Y1126615D03*
X1164268Y1138327D03*
Y1145020D03*
X1159868Y1163426D03*
X1164268Y1151713D03*
Y1175138D03*
Y1181831D03*
Y1188524D03*
X1159868Y1200237D03*
X1164268Y1211949D03*
Y1218642D03*
X1159868Y1237048D03*
X1164268Y1225335D03*
Y1248760D03*
Y1255453D03*
X1167509Y1337884D03*
X1164909D03*
X1157439Y1337834D03*
X1160929Y1352252D03*
X1163529D03*
X1160929Y1349652D03*
X1163529D03*
X1162279Y1357352D03*
X1163529Y1354852D03*
X1157259Y1357406D03*
X1170138Y1361800D03*
X1158205Y1363394D03*
Y1360437D03*
X1169488Y1386721D03*
X1167830Y1384770D03*
X1161311Y1548204D03*
X1172523Y1573250D03*
X1160031Y1591163D03*
X1162144Y1658042D03*
X1159741Y1669759D03*
X1169187Y1687117D03*
X1174958Y-24648D03*
Y5352D03*
Y15352D03*
X1177429Y89556D03*
Y93556D03*
X1185952Y432202D03*
Y440202D03*
Y448202D03*
X1185707Y465272D03*
Y460202D03*
Y470392D03*
X1185117Y571807D03*
X1181445Y592868D03*
X1175860Y756765D03*
X1180410Y773563D03*
X1175860Y763765D03*
X1176010Y791969D03*
X1180410Y780256D03*
X1174960Y786949D03*
X1180410Y803681D03*
X1174960Y796988D03*
X1180410Y817067D03*
Y810374D03*
X1176010Y828780D03*
X1174960Y833799D03*
Y823760D03*
X1180410Y847185D03*
Y840492D03*
X1176010Y865591D03*
X1180410Y853878D03*
X1174960Y860571D03*
X1180410Y877303D03*
X1174960Y870610D03*
X1180410Y890689D03*
Y883996D03*
X1176010Y902402D03*
X1174960Y897382D03*
Y907422D03*
X1180410Y914114D03*
Y920807D03*
X1176010Y939213D03*
X1174960Y934193D03*
X1180410Y927500D03*
X1174960Y944233D03*
X1180410Y950925D03*
Y957618D03*
Y964311D03*
Y971004D03*
Y977697D03*
Y984390D03*
Y991083D03*
Y997776D03*
Y1004469D03*
Y1031240D03*
Y1037933D03*
Y1044626D03*
Y1051319D03*
Y1058012D03*
Y1068051D03*
Y1074744D03*
X1176010Y1086457D03*
X1174960Y1081437D03*
Y1091477D03*
X1180410Y1098170D03*
Y1104862D03*
X1174960Y1118248D03*
X1180410Y1111555D03*
X1176010Y1123268D03*
X1174960Y1128288D03*
X1180410Y1134981D03*
Y1141674D03*
Y1148366D03*
X1176010Y1160079D03*
X1174960Y1155059D03*
Y1165099D03*
X1180410Y1171792D03*
Y1178485D03*
X1174960Y1191870D03*
X1180410Y1185177D03*
X1176010Y1196890D03*
X1174960Y1201910D03*
X1180410Y1208603D03*
Y1215296D03*
Y1221988D03*
X1176010Y1233701D03*
X1174960Y1238721D03*
Y1228681D03*
X1180410Y1245414D03*
Y1252107D03*
X1182615Y1357390D03*
X1185215D03*
X1177415D03*
X1174815D03*
X1180015D03*
X1182615Y1363454D03*
Y1360497D03*
X1180015Y1363454D03*
X1174815Y1360497D03*
X1177415D03*
X1180015D03*
X1176659Y1367253D03*
Y1372853D03*
X1179089D03*
X1181519D03*
Y1367253D03*
X1179089D03*
X1181568Y1385268D03*
X1185000Y1396500D03*
Y1401000D03*
X1184100Y1410000D03*
X1185000Y1405500D03*
X1178400Y1433000D03*
X1181324Y1485895D03*
X1183234Y1483295D03*
Y1488495D03*
X1181314Y1492995D03*
X1176534D03*
X1174624Y1495595D03*
X1181314Y1498195D03*
X1176534D03*
X1180047Y1533247D03*
X1181853Y1561731D03*
X1172523Y1562350D03*
X1179187Y1666429D03*
X1175454Y1668046D03*
X1178932Y1686698D03*
X1185676Y1697249D03*
X1194199Y49379D03*
X1198694Y57015D03*
X1191488Y87125D03*
Y91125D03*
X1200518Y100875D03*
X1189701Y173187D03*
X1201157Y431875D03*
X1189540Y481691D03*
X1188192Y589263D03*
X1191646Y589567D03*
X1195729Y591022D03*
X1198519Y756765D03*
Y760265D03*
X1193969Y776910D03*
X1198519Y767265D03*
X1193969Y783603D03*
X1189569Y795315D03*
X1193969Y807028D03*
Y820414D03*
Y813721D03*
X1189569Y832126D03*
X1193969Y850532D03*
Y843839D03*
Y857225D03*
X1189569Y868937D03*
X1193969Y880650D03*
Y887343D03*
Y894036D03*
X1189569Y905749D03*
X1193969Y917461D03*
Y924154D03*
Y930847D03*
Y954272D03*
X1189569Y942560D03*
X1193969Y960965D03*
Y967658D03*
Y974351D03*
Y981044D03*
Y987736D03*
Y994429D03*
Y1004469D03*
Y1034587D03*
Y1041280D03*
Y1047973D03*
Y1054666D03*
Y1061359D03*
Y1071398D03*
X1189569Y1089804D03*
X1193969Y1078091D03*
Y1101516D03*
Y1108209D03*
Y1114902D03*
X1189569Y1126615D03*
X1193969Y1138327D03*
Y1145020D03*
X1189569Y1163426D03*
X1193969Y1151713D03*
Y1175138D03*
Y1181831D03*
Y1188524D03*
X1189569Y1200237D03*
X1193969Y1211949D03*
Y1218642D03*
X1189569Y1237048D03*
X1193969Y1225335D03*
Y1248760D03*
Y1255453D03*
X1196159Y1326549D03*
X1193659Y1326589D03*
Y1324049D03*
X1196259D03*
X1193659Y1321549D03*
X1196259D03*
X1199899Y1338065D03*
X1193829Y1352252D03*
X1196429D03*
X1193829Y1349652D03*
X1196429D03*
X1193829Y1354852D03*
X1190159Y1357406D03*
X1195179Y1357352D03*
X1196429Y1354852D03*
X1187715Y1357390D03*
X1191105Y1363394D03*
Y1360437D03*
X1200690Y1384572D03*
X1194000Y1418000D03*
X1187925Y1417000D03*
X1194000Y1428500D03*
Y1433000D03*
X1187925Y1440400D03*
X1188014Y1483295D03*
Y1488495D03*
X1194724Y1505295D03*
X1196634Y1502695D03*
Y1507895D03*
X1196127Y1583797D03*
X1195261Y1622884D03*
X1200217D03*
X1195050Y1620040D03*
X1195261Y1627876D03*
X1200217D03*
Y1654796D03*
X1195261D03*
X1200217Y1659788D03*
X1195261D03*
X1192903Y1666276D03*
X1189462Y1691366D03*
X1196767Y1712261D03*
X1196814Y1726261D03*
X1215528Y172395D03*
X1214156Y292066D03*
X1214856Y421018D03*
X1213866Y455376D03*
X1208400Y591631D03*
X1201440Y668138D03*
X1207177Y668115D03*
X1205561Y756765D03*
X1210111Y773563D03*
X1205561Y763765D03*
X1205711Y791969D03*
X1210111Y780256D03*
X1204661Y786949D03*
X1210111Y803681D03*
X1204661Y796988D03*
X1210111Y817067D03*
Y810374D03*
X1205711Y828780D03*
X1204661Y833799D03*
Y823760D03*
X1210111Y847185D03*
Y840492D03*
X1205711Y865591D03*
X1210111Y853878D03*
X1204661Y860571D03*
X1210111Y877303D03*
X1204661Y870610D03*
X1210111Y890689D03*
Y883996D03*
X1205711Y902402D03*
X1204661Y897382D03*
Y907422D03*
X1210111Y914114D03*
Y920807D03*
X1205711Y939213D03*
X1204661Y934193D03*
X1210111Y927500D03*
X1204661Y944233D03*
X1210111Y950925D03*
Y957618D03*
Y964311D03*
Y971004D03*
Y977697D03*
Y984390D03*
Y991083D03*
Y997776D03*
Y1004469D03*
Y1031240D03*
Y1037933D03*
Y1044626D03*
Y1051319D03*
Y1058012D03*
Y1068051D03*
Y1074744D03*
X1205711Y1086457D03*
X1204661Y1081437D03*
Y1091477D03*
X1210111Y1098170D03*
Y1104862D03*
X1204661Y1118248D03*
X1210111Y1111555D03*
X1205711Y1123268D03*
X1204661Y1128288D03*
X1210111Y1134981D03*
Y1141674D03*
Y1148366D03*
X1205711Y1160079D03*
X1204661Y1155059D03*
Y1165099D03*
X1210111Y1171792D03*
Y1178485D03*
X1204661Y1191870D03*
X1210111Y1185177D03*
X1205711Y1196890D03*
X1204661Y1201910D03*
X1210111Y1208603D03*
Y1215296D03*
Y1221988D03*
X1205711Y1233701D03*
X1204661Y1228681D03*
Y1238721D03*
X1210111Y1245414D03*
Y1252107D03*
X1205189Y1321492D03*
Y1323992D03*
X1202689Y1321492D03*
Y1324032D03*
X1211299Y1338105D03*
X1202399D03*
X1215415Y1357390D03*
X1212815D03*
X1210215D03*
X1207615D03*
X1202988Y1361490D03*
X1215415Y1363454D03*
Y1360497D03*
X1212815Y1363454D03*
Y1360497D03*
X1210215D03*
X1207615D03*
X1214319Y1372853D03*
X1211889D03*
X1209459D03*
Y1367253D03*
X1214319D03*
X1211889D03*
X1214368Y1385268D03*
X1202288Y1386721D03*
X1202484Y1402467D03*
X1203334Y1492995D03*
X1208114D03*
X1210034Y1483295D03*
X1214814D03*
X1208124Y1485895D03*
X1210034Y1488495D03*
X1214814D03*
X1201424Y1495595D03*
X1203334Y1498195D03*
X1208114D03*
X1201414Y1502695D03*
Y1507895D03*
X1200851Y1583797D03*
X1205576Y1583897D03*
X1210300Y1583697D03*
X1215025Y1583897D03*
X1207321Y1622884D03*
X1212277D03*
X1201291Y1637876D03*
Y1632884D03*
X1206247D03*
Y1637876D03*
X1213351D03*
Y1632884D03*
X1207321Y1627876D03*
X1212277D03*
X1207321Y1654796D03*
X1206247Y1649788D03*
X1201291D03*
X1212277Y1654796D03*
X1213351Y1649788D03*
X1206247Y1644796D03*
X1201291D03*
X1213351D03*
X1207321Y1659788D03*
X1212277D03*
X1204804Y1691375D03*
X1216199Y49379D03*
X1230156Y292066D03*
X1222094Y286948D03*
X1219463Y1338122D03*
X1229809Y1338105D03*
X1226629Y1352252D03*
X1229229D03*
X1226629Y1349652D03*
X1229229D03*
X1222959Y1357406D03*
X1227979Y1357352D03*
X1226629Y1354852D03*
X1229229D03*
X1220515Y1357390D03*
X1218015D03*
X1223905Y1363394D03*
Y1360437D03*
X1230134Y1492995D03*
X1228224Y1495595D03*
X1221524Y1505295D03*
X1230134Y1498195D03*
X1228214Y1502695D03*
X1223434D03*
Y1507895D03*
X1228214D03*
X1219749Y1583897D03*
X1224474Y1583697D03*
X1229198Y1583797D03*
X1219381Y1622884D03*
X1224337D03*
X1218307Y1637876D03*
Y1632884D03*
X1230367Y1637876D03*
X1225411D03*
X1230367Y1632884D03*
X1225411D03*
X1219381Y1627876D03*
X1224337D03*
Y1654796D03*
X1219381D03*
X1218307Y1649788D03*
X1225411D03*
X1230367D03*
X1218307Y1644796D03*
X1225411D03*
X1230367D03*
X1224337Y1659788D03*
X1219381D03*
X1219738Y1717011D03*
Y1731011D03*
X1236844Y-34348D03*
X1236829Y-36863D03*
X1236798Y-31476D03*
X1236813Y-28961D03*
X1240097Y-34334D03*
X1243122Y-35654D03*
X1240082Y-36849D03*
X1236877Y-26227D03*
X1236932Y-19948D03*
X1236942Y-13666D03*
X1236927Y-16181D03*
X1236892Y-23712D03*
X1240130Y-26213D03*
X1240194Y-19948D03*
X1240195Y-13652D03*
X1243220Y-14972D03*
X1240180Y-16167D03*
X1240145Y-23698D03*
X1243170Y-25018D03*
X1236932Y-9948D03*
Y52D03*
X1236942Y-3666D03*
X1236927Y-6181D03*
X1240194Y-9948D03*
Y52D03*
X1240195Y-3652D03*
X1243220Y-4972D03*
X1240180Y-6167D03*
X1236927Y13819D03*
X1236942Y16334D03*
X1236932Y10052D03*
X1236942Y6334D03*
X1236927Y3819D03*
X1240180Y13833D03*
X1243220Y15028D03*
X1240195Y16348D03*
X1240194Y10052D03*
X1240195Y6348D03*
X1243220Y5028D03*
X1240180Y3833D03*
X1236911Y21721D03*
X1236896Y19206D03*
X1236941Y26751D03*
X1236926Y24236D03*
X1243219Y25445D03*
X1240194Y26765D03*
X1240179Y24250D03*
X1238199Y49379D03*
X1245606Y1314351D03*
Y1311244D03*
X1240899Y1315460D03*
X1240240Y1339578D03*
X1232409Y1338105D03*
X1242500Y1430075D03*
X1237100Y1442500D03*
X1242500Y1437075D03*
X1234924Y1485895D03*
X1241614Y1483295D03*
X1236834D03*
X1241614Y1488495D03*
X1236834D03*
X1234914Y1492995D03*
Y1498195D03*
X1233923Y1583897D03*
X1238647D03*
X1243372D03*
X1231441Y1622884D03*
X1236397D03*
X1243501D03*
X1237471Y1637876D03*
Y1632884D03*
X1242427Y1637876D03*
Y1632884D03*
X1236397Y1627876D03*
X1231441D03*
X1243501D03*
X1231441Y1654796D03*
X1236397D03*
X1237471Y1649788D03*
X1243501Y1654796D03*
X1242427Y1649788D03*
X1237471Y1644796D03*
X1242427D03*
X1231441Y1659788D03*
X1236397D03*
X1243501D03*
X1260199Y49379D03*
X1256064Y101100D03*
X1254094Y286948D03*
X1245825Y305275D03*
X1260227Y407128D03*
Y411128D03*
X1248902Y470733D03*
X1257016Y467253D03*
X1246490Y483302D03*
X1257450Y1291721D03*
X1260050D03*
X1249650D03*
X1247050D03*
X1258506Y1311244D03*
X1256006D03*
X1253406Y1314351D03*
X1250806D03*
X1253406Y1311244D03*
X1250806D03*
X1248206Y1314351D03*
Y1311244D03*
X1252310Y1321107D03*
X1249880D03*
X1252310Y1326707D03*
X1253406Y1317308D03*
X1250806D03*
X1247450Y1326707D03*
Y1321107D03*
X1249880Y1326707D03*
X1252359Y1339122D03*
X1252315Y1417085D03*
X1254905Y1417026D03*
X1256934Y1492995D03*
X1255024Y1495595D03*
X1248324Y1505295D03*
X1256934Y1498195D03*
X1255014Y1502695D03*
X1250234D03*
X1255014Y1507895D03*
X1250234D03*
X1248096Y1583897D03*
X1252820Y1583697D03*
X1257544Y1583897D03*
X1248457Y1622884D03*
X1255561D03*
X1254487Y1637876D03*
Y1632884D03*
X1249531Y1637876D03*
Y1632884D03*
X1248457Y1627876D03*
X1255561D03*
X1248457Y1654796D03*
X1254487Y1649788D03*
X1249531D03*
X1255561Y1654796D03*
X1254487Y1644796D03*
X1249531D03*
X1248657Y1659588D03*
X1255561Y1659788D03*
X1266146Y121022D03*
X1263582Y164051D03*
Y160051D03*
Y180551D03*
Y176051D03*
Y172051D03*
Y168051D03*
Y185051D03*
X1270094Y286948D03*
X1262156Y292066D03*
X1270670Y1291624D03*
X1268070D03*
X1261896Y1314291D03*
X1260950Y1311260D03*
X1267220Y1306106D03*
Y1308706D03*
Y1303506D03*
X1265970Y1311206D03*
X1264620Y1303506D03*
Y1306106D03*
Y1308706D03*
X1273869Y1315300D03*
X1261896Y1317248D03*
X1273175Y1340547D03*
X1271517Y1338596D03*
X1275124Y1485895D03*
X1261724D03*
X1263634Y1483295D03*
X1268414D03*
X1263634Y1488495D03*
X1268414D03*
X1261714Y1492995D03*
Y1498195D03*
X1262269Y1583897D03*
X1266993Y1583797D03*
X1267621Y1622884D03*
X1260517D03*
X1272577D03*
X1261591Y1637876D03*
X1266547D03*
X1261591Y1632884D03*
X1266547D03*
X1273651Y1637876D03*
Y1632790D03*
X1267621Y1627876D03*
X1260517D03*
X1272577D03*
X1260517Y1654796D03*
X1267621D03*
X1266547Y1649788D03*
X1261591D03*
X1272577Y1654796D03*
X1273651Y1649788D03*
X1266547Y1644796D03*
X1261591D03*
X1273651D03*
X1260517Y1659788D03*
X1267621D03*
X1272577D03*
X1282199Y49379D03*
X1278111Y150030D03*
X1285391Y142553D03*
X1286094Y286948D03*
X1278156Y292066D03*
X1277598Y404428D03*
X1282165Y408987D03*
X1288202Y405741D03*
X1288902Y1311216D03*
X1286302Y1314323D03*
X1283702D03*
X1286302Y1311216D03*
X1283702D03*
X1278502Y1314323D03*
X1281102D03*
Y1311216D03*
X1278502D03*
X1285206Y1326679D03*
X1286302Y1317280D03*
X1283702D03*
X1285206Y1321079D03*
X1282776D03*
Y1326679D03*
X1280346Y1321079D03*
Y1326679D03*
X1285255Y1339094D03*
X1277034Y1483295D03*
X1281814D03*
X1277034Y1488495D03*
X1281814D03*
X1284510Y1556953D03*
X1278012Y1581563D03*
X1279681Y1622884D03*
X1284637D03*
X1278607Y1637876D03*
Y1632790D03*
X1285711Y1637876D03*
Y1632884D03*
X1279681Y1627876D03*
X1284637D03*
X1279681Y1654796D03*
X1278607Y1649788D03*
X1284637Y1654796D03*
X1285711Y1649788D03*
X1278607Y1644796D03*
X1285711D03*
X1279681Y1659788D03*
X1284637D03*
X1304199Y49379D03*
X1300668Y125739D03*
Y133739D03*
Y129739D03*
X1306431Y149330D03*
X1300668Y145739D03*
X1292082Y166051D03*
Y162051D03*
Y171551D03*
Y184051D03*
X1302094Y298066D03*
Y286948D03*
X1294156Y292066D03*
X1293277Y401125D03*
X1296228Y408125D03*
X1299076Y530023D03*
X1297487Y590607D03*
X1302890Y1291759D03*
X1298350Y1291721D03*
X1295750D03*
X1300116Y1306078D03*
Y1303478D03*
Y1308678D03*
X1298866Y1311178D03*
X1294792Y1314263D03*
X1297516Y1306078D03*
Y1303478D03*
Y1308678D03*
X1291402Y1311216D03*
X1293846Y1311232D03*
X1294792Y1317220D03*
X1304421Y1338539D03*
X1304596Y1492995D03*
X1302686Y1495595D03*
X1304596Y1498195D03*
X1291819Y1563595D03*
X1294319D03*
X1300560Y1554261D03*
X1291741Y1622884D03*
X1296697D03*
X1303801D03*
X1290667Y1637876D03*
Y1632884D03*
X1297771Y1637876D03*
Y1632884D03*
X1302727Y1637876D03*
Y1632884D03*
X1296697Y1627876D03*
X1291741D03*
X1303801D03*
X1291741Y1654796D03*
X1296697D03*
X1297771Y1649788D03*
X1290667D03*
X1303801Y1654796D03*
X1302727Y1649788D03*
X1297771Y1644796D03*
X1290667D03*
X1302727D03*
X1291741Y1659788D03*
X1296697D03*
X1303801D03*
X1306449Y92185D03*
X1306431Y152830D03*
X1310156Y292066D03*
X1305600Y1291759D03*
X1316606Y1314266D03*
Y1311159D03*
X1314006Y1314266D03*
Y1311159D03*
X1319206Y1314266D03*
Y1311159D03*
X1311406Y1314266D03*
Y1311159D03*
X1306799Y1315440D03*
X1315680Y1326622D03*
X1318110D03*
X1316606Y1317223D03*
X1319206D03*
X1318110Y1321022D03*
X1315680D03*
X1313250D03*
Y1326622D03*
X1318159Y1339037D03*
X1306079Y1340490D03*
X1314580Y1425240D03*
X1310580D03*
X1318580D03*
X1309386Y1485895D03*
X1311296Y1483295D03*
X1316076D03*
X1311296Y1488495D03*
X1316076D03*
X1309376Y1492995D03*
Y1498195D03*
X1308290Y1533380D03*
X1309423Y1543800D03*
Y1547420D03*
Y1551040D03*
X1309915Y1561731D03*
X1308757Y1622884D03*
X1315861D03*
X1309831Y1637876D03*
Y1632884D03*
X1314787Y1637876D03*
Y1632884D03*
X1308757Y1627876D03*
X1315861D03*
X1308757Y1654796D03*
X1309831Y1649788D03*
X1315861Y1654796D03*
X1314787Y1649788D03*
X1309831Y1644796D03*
X1314787D03*
X1308757Y1659788D03*
X1315861D03*
X1326199Y49379D03*
X1334156Y292066D03*
X1326094Y286948D03*
X1330277Y857388D03*
X1329477Y1222158D03*
X1331202Y1211488D03*
X1332680Y1291861D03*
X1330080D03*
X1333020Y1308621D03*
X1331770Y1311121D03*
X1333020Y1306021D03*
Y1303421D03*
X1330420Y1306021D03*
Y1303421D03*
Y1308621D03*
X1327696Y1314206D03*
X1321806Y1311159D03*
X1324306D03*
X1326750Y1311175D03*
X1327696Y1317163D03*
X1334580Y1425240D03*
X1330580D03*
X1326580D03*
X1322580D03*
X1331396Y1492995D03*
X1322786Y1505295D03*
X1329486Y1495595D03*
X1331396Y1498195D03*
X1324696Y1502695D03*
X1329476D03*
X1324696Y1507895D03*
X1329476D03*
X1328913Y1583797D03*
X1333638Y1583897D03*
X1324189Y1583797D03*
X1327921Y1622884D03*
X1320817D03*
X1332877D03*
X1321891Y1637876D03*
X1326847D03*
X1321891Y1632884D03*
X1326847D03*
X1333951Y1637876D03*
Y1632884D03*
X1327921Y1627876D03*
X1320817D03*
X1332877D03*
X1320817Y1654796D03*
X1327921D03*
X1326847Y1649788D03*
X1321891D03*
X1332877Y1654796D03*
X1333951Y1649788D03*
X1326847Y1644796D03*
X1321891D03*
X1333951D03*
X1320817Y1659788D03*
X1327921D03*
X1332877D03*
X1348199Y49379D03*
X1351750Y72826D03*
X1339840Y72860D03*
X1342094Y286948D03*
X1339347Y857388D03*
X1337975Y1177999D03*
X1338142Y1181642D03*
X1338440Y1291949D03*
X1335670Y1291899D03*
X1346806Y1311359D03*
X1349406D03*
X1346806Y1314466D03*
X1349406D03*
X1344206Y1311359D03*
Y1314466D03*
X1339429Y1315570D03*
X1348480Y1326822D03*
X1349406Y1317423D03*
X1346050Y1321222D03*
Y1326822D03*
X1348480Y1321222D03*
X1338879Y1340690D03*
X1337221Y1338739D03*
X1346580Y1425240D03*
X1342580D03*
X1338580D03*
X1336176Y1492995D03*
X1338096Y1483295D03*
X1342876D03*
X1336186Y1485895D03*
X1338096Y1488495D03*
X1342876D03*
X1349586Y1505295D03*
X1336176Y1498195D03*
X1343087Y1583897D03*
X1347811D03*
X1338362Y1583697D03*
X1339981Y1622884D03*
X1344937D03*
X1338907Y1637876D03*
Y1632884D03*
X1346011Y1637876D03*
Y1632884D03*
X1339981Y1627876D03*
X1344937D03*
X1339981Y1654796D03*
X1338907Y1649788D03*
X1344937Y1654796D03*
X1346011Y1649788D03*
X1338907Y1644796D03*
X1346011D03*
X1339981Y1659788D03*
X1344937D03*
X1361550Y67264D03*
X1350156Y292066D03*
X1358094Y286948D03*
X1354257Y675765D03*
X1364490Y1293694D03*
X1361830Y1291809D03*
X1360496Y1314406D03*
X1363220Y1308821D03*
X1364570Y1311321D03*
X1363220Y1306221D03*
Y1303621D03*
X1359550Y1311375D03*
X1352006Y1311359D03*
X1357106D03*
X1354606D03*
X1352006Y1314466D03*
X1360496Y1317363D03*
X1350910Y1326822D03*
X1352006Y1317423D03*
X1350910Y1321222D03*
X1350959Y1339237D03*
X1362580Y1425240D03*
X1358580D03*
X1354580D03*
X1350580D03*
X1362986Y1485895D03*
X1364896Y1483295D03*
Y1488495D03*
X1358196Y1492995D03*
X1362976D03*
X1356286Y1495595D03*
X1358196Y1498195D03*
X1362976D03*
X1356276Y1502695D03*
X1351496D03*
X1356276Y1507895D03*
X1351496D03*
X1357260Y1583797D03*
X1361985Y1583897D03*
X1352536Y1583697D03*
X1352041Y1622884D03*
X1356997D03*
X1364101D03*
X1350967Y1637876D03*
Y1632884D03*
X1358071Y1637876D03*
Y1632884D03*
X1363027Y1637876D03*
Y1632884D03*
X1356997Y1627876D03*
X1352041D03*
X1364101D03*
X1352041Y1654796D03*
X1356997D03*
X1358071Y1649788D03*
X1350967D03*
X1364101Y1654796D03*
X1363027Y1649788D03*
X1358071Y1644796D03*
X1350967D03*
X1363027D03*
X1352041Y1659788D03*
X1356997D03*
X1364101D03*
X1370199Y49379D03*
X1371259Y98000D03*
X1366156Y292066D03*
X1377862Y485552D03*
Y511052D03*
X1368305Y1307340D03*
X1365820Y1308821D03*
X1368305Y1309840D03*
X1365820Y1306221D03*
Y1303621D03*
X1372149Y1334890D03*
X1379388Y1330690D03*
Y1333797D03*
X1378632Y1340553D03*
X1376788Y1330690D03*
Y1333797D03*
X1378632Y1346153D03*
X1371422Y1359024D03*
X1368922D03*
X1379101Y1418621D03*
X1368299Y1425240D03*
X1372164Y1423810D03*
X1375341Y1421268D03*
X1369676Y1483295D03*
Y1488495D03*
X1376386Y1505295D03*
X1378296Y1502695D03*
Y1507895D03*
X1376158Y1583897D03*
X1366709D03*
X1371434D03*
X1369057Y1622884D03*
X1376161D03*
X1370131Y1637876D03*
Y1632790D03*
X1375087Y1637876D03*
Y1632790D03*
X1369057Y1627876D03*
X1376161D03*
X1369057Y1654796D03*
X1370131Y1649788D03*
X1376161Y1654796D03*
X1375087Y1649788D03*
X1370131Y1644796D03*
X1375087D03*
X1369057Y1659788D03*
X1376161D03*
X1392199Y49379D03*
X1389688Y1330690D03*
X1392132Y1330706D03*
X1393078Y1333737D03*
Y1336694D03*
X1383492Y1340553D03*
X1381062D03*
X1381988Y1336754D03*
X1384588D03*
X1387188Y1330690D03*
X1381988D03*
Y1333797D03*
X1384588Y1330690D03*
Y1333797D03*
X1383541Y1358568D03*
X1381062Y1346153D03*
X1383492D03*
X1383284Y1415973D03*
X1387308Y1413643D03*
X1392021Y1410360D03*
X1389786Y1485895D03*
X1391696Y1483295D03*
Y1488495D03*
X1384996Y1492995D03*
X1389776D03*
X1383086Y1495595D03*
X1384996Y1498195D03*
X1389776D03*
X1383076Y1502695D03*
Y1507895D03*
X1390331Y1583897D03*
X1380882Y1583697D03*
X1385606Y1583897D03*
X1381117Y1622884D03*
X1382191Y1637876D03*
X1387147D03*
X1382191Y1632884D03*
X1387147D03*
X1381117Y1627876D03*
Y1654796D03*
X1382191Y1649788D03*
X1387147D03*
X1382191Y1644796D03*
X1387147D03*
X1392068Y1667907D03*
X1381918D03*
X1381117Y1659788D03*
X1387620Y1721418D03*
X1385061D03*
X1403500Y458377D03*
X1402452Y642825D03*
X1405716Y1310618D03*
X1401740Y1311980D03*
X1399240D03*
X1408690Y1324803D03*
X1396302Y1328152D03*
Y1325552D03*
X1398902Y1328152D03*
Y1325552D03*
X1396302Y1322952D03*
X1398902D03*
X1401406Y1334918D03*
X1397652Y1330652D03*
X1398375Y1403688D03*
X1401764Y1399928D03*
X1405207Y1395480D03*
X1408543Y1391826D03*
X1395463Y1406918D03*
X1403186Y1485895D03*
X1405096Y1483295D03*
X1396476D03*
X1405096Y1488495D03*
X1396476D03*
X1409456Y1537872D03*
X1406074Y1581563D03*
X1395055Y1583797D03*
X1398058Y1619683D03*
X1409660Y1619853D03*
X1397367Y1639951D03*
X1402425Y1649532D03*
X1414199Y49379D03*
X1414000Y460362D03*
X1415426Y1042765D03*
Y1038765D03*
X1424561Y1305566D03*
X1420690Y1324803D03*
X1417690D03*
X1414690D03*
X1411690D03*
X1424163Y1373240D03*
X1411508Y1388384D03*
X1414950Y1384942D03*
X1417491Y1381183D03*
X1420774Y1377106D03*
X1409876Y1483295D03*
Y1488495D03*
X1423735Y1536715D03*
X1412572Y1556953D03*
X1421232Y1606126D03*
X1422914Y1601663D03*
X1421392Y1621706D03*
X1416357Y1644027D03*
X1420042Y1649716D03*
X1433817Y-34648D03*
Y-4648D03*
Y5352D03*
X1436199Y49379D03*
X1434513Y106950D03*
X1439232Y596291D03*
X1425437Y1308184D03*
X1426202Y1310752D03*
X1427314Y1313482D03*
X1428458Y1316481D03*
X1429517Y1319447D03*
X1430312Y1322412D03*
X1431106Y1325219D03*
X1426441Y1369427D03*
X1428559Y1365296D03*
X1430465Y1361060D03*
X1438798Y1495595D03*
X1430431Y1563595D03*
X1427931D03*
X1424971Y1566764D03*
Y1564264D03*
X1435584Y1596545D03*
X1430075Y1613904D03*
X1430319Y1623504D03*
X1425390Y1635496D03*
X1433327Y1643287D03*
X1446869Y105129D03*
X1451353Y116158D03*
X1443551Y539318D03*
Y535318D03*
X1453345Y1015473D03*
Y1019016D03*
Y1022559D03*
X1445498Y1485895D03*
X1447408Y1483295D03*
X1452188D03*
X1447408Y1488495D03*
X1452188D03*
X1445488Y1492995D03*
X1440708D03*
X1445488Y1498195D03*
X1440708D03*
X1444200Y1533240D03*
X1445535Y1551040D03*
Y1547420D03*
Y1543800D03*
X1446027Y1561731D03*
X1445500Y1611500D03*
X1448500Y1601000D03*
X1442579Y1673303D03*
X1447579D03*
X1452579D03*
X1453950Y1681450D03*
X1458199Y49379D03*
X1459682Y450372D03*
X1468395Y487582D03*
X1464257Y552977D03*
Y564977D03*
X1468257Y696265D03*
X1460926Y1015473D03*
X1467926D03*
X1460926Y1019016D03*
Y1022559D03*
X1467926Y1019016D03*
Y1022559D03*
X1467508Y1492995D03*
X1458898Y1505295D03*
X1465598Y1495595D03*
X1467508Y1498195D03*
X1460808Y1502695D03*
X1465588D03*
X1460808Y1507895D03*
X1465588D03*
X1465025Y1583797D03*
X1460301D03*
X1464391Y1622884D03*
X1459435D03*
X1465465Y1637876D03*
Y1632884D03*
X1459435Y1627876D03*
X1464391D03*
Y1654796D03*
X1465465Y1649788D03*
Y1644796D03*
X1459435Y1654796D03*
X1464391Y1659788D03*
X1466500Y1666000D03*
X1469034Y1667794D03*
X1459435Y1659788D03*
X1456852Y1673320D03*
X1466599Y1679401D03*
X1466260Y1675155D03*
X1460457Y1685160D03*
X1480199Y49379D03*
X1483820Y122713D03*
X1482257Y552977D03*
Y560477D03*
Y567977D03*
X1481934Y699670D03*
X1480300Y697750D03*
X1472288Y1492995D03*
X1474208Y1483295D03*
X1478988D03*
X1472298Y1485895D03*
X1474208Y1488495D03*
X1478988D03*
X1472288Y1498195D03*
X1479199Y1583897D03*
X1483923D03*
X1469750D03*
X1474474Y1583697D03*
X1476451Y1622884D03*
X1471495D03*
X1483555D03*
X1470421Y1632884D03*
Y1637876D03*
X1482481D03*
X1477525D03*
X1482481Y1632884D03*
X1477525D03*
X1471495Y1627876D03*
X1483555D03*
X1476451D03*
X1471495Y1654796D03*
X1470421Y1649788D03*
X1476451Y1654796D03*
X1483555D03*
X1482481Y1649788D03*
X1477525D03*
X1470421Y1644796D03*
X1477525D03*
X1482481D03*
X1471495Y1659788D03*
X1476451D03*
X1483555D03*
X1471616Y1670098D03*
X1479375Y1685984D03*
X1495539Y131237D03*
X1492237Y123842D03*
X1489757Y552977D03*
X1497257D03*
Y560477D03*
X1489757Y567977D03*
X1497257D03*
X1494371Y594462D03*
X1492673Y828513D03*
X1494386Y1178743D03*
X1499098Y1485895D03*
X1494308Y1492995D03*
X1499088D03*
X1492398Y1495595D03*
X1485698Y1505295D03*
X1494308Y1498195D03*
X1499088D03*
X1492388Y1502695D03*
X1487608D03*
X1492388Y1507895D03*
X1487608D03*
X1493372Y1583797D03*
X1498097Y1583897D03*
X1488648Y1583697D03*
X1488511Y1622884D03*
X1495615D03*
X1494541Y1637876D03*
X1489585D03*
X1494541Y1632884D03*
X1489585D03*
X1488511Y1627876D03*
X1495615D03*
X1488511Y1654796D03*
X1495615D03*
X1489585Y1649788D03*
X1494541D03*
X1489585Y1644796D03*
X1494541D03*
X1488511Y1659788D03*
X1495615D03*
X1502199Y49379D03*
X1514576Y219730D03*
X1513348Y253954D03*
X1500757Y537438D03*
X1504757Y537378D03*
X1508757Y537456D03*
X1512757Y537477D03*
X1513382Y697750D03*
X1499243Y803513D03*
X1501730Y811872D03*
X1501338Y825147D03*
X1513470Y1178265D03*
X1504470D03*
X1505788Y1483295D03*
X1501008D03*
X1505788Y1488495D03*
X1501008D03*
X1512498Y1505295D03*
X1512270Y1583897D03*
X1502821D03*
X1507546D03*
X1500571Y1622884D03*
X1512631D03*
X1507675D03*
X1501645Y1637876D03*
Y1632884D03*
X1506601Y1637876D03*
Y1632884D03*
X1513705Y1637876D03*
Y1632884D03*
X1500571Y1627876D03*
X1512631D03*
X1507675D03*
X1500571Y1654796D03*
X1501645Y1649788D03*
X1507675Y1654796D03*
X1512631D03*
X1513705Y1649788D03*
X1506601D03*
X1501645Y1644796D03*
X1513705D03*
X1506601D03*
X1500571Y1659788D03*
X1507675D03*
X1512831Y1659588D03*
X1524124Y47570D03*
X1522917Y119912D03*
X1529384Y201245D03*
X1516452Y249724D03*
X1514900Y251839D03*
X1515016Y699670D03*
X1515192Y814294D03*
X1525898Y1485895D03*
X1527808Y1483295D03*
Y1488495D03*
X1521108Y1492995D03*
X1525888D03*
X1525898Y1505295D03*
X1519198Y1495595D03*
X1521108Y1498195D03*
X1525888D03*
X1519188Y1502695D03*
X1527808D03*
X1514408D03*
X1519188Y1507895D03*
X1514408D03*
X1526443Y1583897D03*
X1516994Y1583697D03*
X1521718Y1583897D03*
X1524691Y1622884D03*
X1519735D03*
X1518661Y1637876D03*
Y1632884D03*
X1525765Y1637876D03*
Y1632884D03*
X1519735Y1627876D03*
X1524691D03*
X1518661Y1649788D03*
X1524691Y1654796D03*
X1519735D03*
X1525765Y1649788D03*
X1518661Y1644796D03*
X1525765D03*
X1524991Y1659788D03*
X1519735D03*
X1530064Y-27930D03*
X1530049Y-30445D03*
X1533317Y-27916D03*
X1536342Y-29236D03*
X1533302Y-30431D03*
X1530048Y-20028D03*
X1530063Y-17513D03*
X1530018Y-25058D03*
X1530033Y-22543D03*
X1533301Y-20014D03*
X1533316Y-17499D03*
X1536341Y-18819D03*
X1543862Y75343D03*
X1539756Y71839D03*
X1534776D03*
X1539756Y66847D03*
X1534776D03*
X1532866Y69340D03*
X1536542Y300819D03*
Y304819D03*
X1539693Y535212D03*
X1542902Y543641D03*
X1540850Y1240863D03*
X1539298Y1485895D03*
X1541208Y1483295D03*
X1532588D03*
X1541208Y1488495D03*
X1532588D03*
X1542186Y1581563D03*
X1531167Y1583797D03*
X1536751Y1622884D03*
X1531795D03*
X1530721Y1637876D03*
Y1632884D03*
X1537825Y1637876D03*
X1542781D03*
X1537825Y1632790D03*
X1542781D03*
X1531795Y1627876D03*
X1536751D03*
X1531795Y1654796D03*
X1530721Y1649788D03*
X1536751Y1654796D03*
X1542781Y1649788D03*
X1537825D03*
X1530721Y1644796D03*
X1542781D03*
X1537825D03*
X1531795Y1659788D03*
X1536751D03*
X1550965Y3001D03*
X1555568Y17045D03*
Y22037D03*
X1553601Y19541D03*
X1555452Y25977D03*
X1553452Y23981D03*
X1548496D03*
X1546496Y25977D03*
X1554520Y37106D03*
X1547434D03*
X1554520Y48720D03*
X1547434D03*
X1556776Y71839D03*
X1550756Y72850D03*
X1545776D03*
X1554866Y69340D03*
X1556776Y66847D03*
X1550756Y77842D03*
X1545776D03*
X1552981Y220826D03*
X1555481Y218326D03*
X1553913Y298119D03*
X1558480Y302678D03*
X1545960Y565162D03*
X1551887Y606938D03*
X1555570Y1235968D03*
X1555367Y1248078D03*
X1555303Y1242557D03*
X1547062Y1258468D03*
X1553811Y1264488D03*
X1545988Y1483295D03*
Y1488495D03*
X1548684Y1556953D03*
X1555993Y1563595D03*
X1558493D03*
X1548811Y1622884D03*
X1543855D03*
X1555915D03*
X1549885Y1637876D03*
X1554841D03*
X1549885Y1632884D03*
X1554841D03*
X1543855Y1627876D03*
X1548811D03*
X1555915D03*
X1543855Y1654796D03*
X1555915D03*
X1548811D03*
X1554841Y1649788D03*
X1549885D03*
X1554841Y1644796D03*
X1549885D03*
X1543855Y1659788D03*
X1555915D03*
X1548811D03*
X1572965Y3001D03*
X1569742Y17045D03*
X1560548D03*
X1567774Y19541D03*
X1569742Y22037D03*
X1560548D03*
X1562669Y23981D03*
X1567625D03*
X1560669Y25977D03*
X1569625D03*
X1562557Y19541D03*
X1561607Y37106D03*
X1568693D03*
Y48720D03*
X1561607D03*
X1572756Y72847D03*
X1561756Y71839D03*
X1565866Y75340D03*
X1567776Y72847D03*
X1561756Y66847D03*
X1572756Y77839D03*
X1567776D03*
X1564517Y299432D03*
X1569592Y294816D03*
X1572283Y301816D03*
X1562995Y789522D03*
X1569518Y806684D03*
X1564267Y1253158D03*
X1573560Y1485895D03*
X1573550Y1492995D03*
X1568770D03*
X1566860Y1495595D03*
X1573550Y1498195D03*
X1568770D03*
X1572230Y1533000D03*
X1573597Y1543800D03*
Y1547420D03*
Y1551040D03*
X1564839Y1554561D03*
X1560871Y1622884D03*
X1572931D03*
X1567975D03*
X1561945Y1637876D03*
Y1632884D03*
X1566901Y1637876D03*
Y1632884D03*
X1560871Y1627876D03*
X1572931D03*
X1567975D03*
X1560871Y1654796D03*
X1561945Y1649788D03*
X1567975Y1654796D03*
X1572931D03*
X1566901Y1649788D03*
X1561945Y1644796D03*
X1566901D03*
X1560871Y1659788D03*
X1567975D03*
X1572931D03*
X1583915Y17045D03*
X1574722D03*
X1581947Y19541D03*
X1583915Y22037D03*
X1576730Y19541D03*
X1574722Y22037D03*
X1576842Y23981D03*
X1581798D03*
X1574842Y25977D03*
X1583798D03*
X1575780Y37106D03*
X1582867D03*
Y48720D03*
X1575780D03*
X1587866Y75340D03*
X1578776Y71839D03*
X1583756D03*
X1576866Y69340D03*
X1578776Y66847D03*
X1583756D03*
X1574546Y251294D03*
X1575370Y1252770D03*
X1581327Y1252858D03*
X1586835Y1271918D03*
X1583007Y1288958D03*
X1577913Y1341623D03*
X1575504Y1356103D03*
X1578336D03*
X1575470Y1483295D03*
X1580250D03*
X1575470Y1488495D03*
X1580250D03*
X1586960Y1505295D03*
X1574089Y1561731D03*
X1588363Y1583797D03*
X1584991Y1622884D03*
X1580035D03*
X1574005Y1637876D03*
Y1632884D03*
X1578961Y1637876D03*
Y1632884D03*
X1586065Y1637876D03*
Y1632884D03*
X1580035Y1627876D03*
X1584991D03*
X1574005Y1649788D03*
X1580035Y1654796D03*
X1578961Y1649788D03*
X1584991Y1654796D03*
X1586065Y1649788D03*
X1574005Y1644796D03*
X1578961D03*
X1586065D03*
X1580035Y1659788D03*
X1584991D03*
X1594965Y3001D03*
X1603072Y17045D03*
X1598092D03*
X1588895D03*
X1603072Y22037D03*
X1598092D03*
X1596121Y19541D03*
X1590903D03*
X1588895Y22037D03*
X1595972Y23981D03*
X1591016D03*
X1589016Y25977D03*
X1597972D03*
X1589953Y37106D03*
X1597040D03*
Y48720D03*
X1589953D03*
X1589776Y72847D03*
X1594756D03*
X1600776Y71842D03*
X1598866Y69343D03*
X1600776Y66850D03*
X1589776Y77839D03*
X1594756D03*
X1597562Y555463D03*
X1595036D03*
X1591962D03*
X1589436D03*
X1589557Y1252778D03*
X1590097Y1246768D03*
X1603507Y1306262D03*
X1601772Y1337293D03*
X1601959Y1351773D03*
X1599139Y1400464D03*
X1595570Y1492995D03*
X1600350D03*
X1602270Y1483295D03*
X1600360Y1485895D03*
X1602270Y1488495D03*
X1593660Y1495595D03*
X1595570Y1498195D03*
X1600350D03*
X1588870Y1502695D03*
X1593650D03*
X1588870Y1507895D03*
X1593650D03*
X1593087Y1583797D03*
X1597812Y1583897D03*
X1602536Y1583697D03*
X1597051Y1622884D03*
X1592095D03*
X1591021Y1637876D03*
Y1632884D03*
X1598125Y1637876D03*
X1603081D03*
X1598125Y1632884D03*
X1603081D03*
X1592095Y1627876D03*
X1597051D03*
X1592095Y1654796D03*
X1591021Y1649788D03*
X1597051Y1654796D03*
X1603081Y1649788D03*
X1598125D03*
X1591021Y1644796D03*
X1603081D03*
X1598125D03*
X1592095Y1659788D03*
X1597051D03*
X1616965Y3001D03*
X1605077Y19541D03*
X1604127Y37106D03*
Y48720D03*
X1609866Y75340D03*
X1611776Y72847D03*
X1616756D03*
X1605756Y71842D03*
Y66850D03*
X1611776Y77839D03*
X1616756D03*
X1608640Y640660D03*
X1607050Y1483295D03*
Y1488495D03*
X1613760Y1505295D03*
X1615670Y1502695D03*
Y1507895D03*
X1607261Y1583897D03*
X1611985D03*
X1616710Y1583697D03*
X1609111Y1622884D03*
X1604155D03*
X1616215D03*
X1610185Y1637876D03*
X1615141D03*
X1610185Y1632884D03*
X1615141D03*
X1604155Y1627876D03*
X1609111D03*
X1616215D03*
X1604155Y1654796D03*
X1616215D03*
X1609111D03*
X1615141Y1649788D03*
X1610185D03*
X1615141Y1644796D03*
X1610185D03*
X1604155Y1659788D03*
X1616215D03*
X1609111D03*
X1631987Y19541D03*
X1626882Y23981D03*
X1631838D03*
X1624882Y25977D03*
X1632906Y37106D03*
X1625819D03*
X1632906Y48720D03*
X1625819D03*
X1629662Y69343D03*
X1633070Y75340D03*
X1627756Y71842D03*
X1622776D03*
X1627756Y66850D03*
X1622776D03*
X1620862Y69343D03*
X1627410Y172008D03*
X1632500Y381500D03*
X1630927Y398002D03*
X1628046Y756765D03*
Y760265D03*
Y767265D03*
X1623496Y776910D03*
Y783603D03*
X1627896Y795315D03*
X1623496Y807028D03*
Y813721D03*
Y820414D03*
X1627896Y832126D03*
X1623496Y843839D03*
Y850532D03*
Y857225D03*
X1627896Y868937D03*
X1623496Y880650D03*
Y887343D03*
Y894036D03*
X1627896Y905749D03*
X1623496Y917461D03*
Y924154D03*
Y930847D03*
X1627896Y942560D03*
X1623496Y954272D03*
Y960965D03*
Y967658D03*
Y974351D03*
Y981044D03*
Y987736D03*
Y994429D03*
Y1004469D03*
Y1034587D03*
Y1041280D03*
Y1047973D03*
Y1054666D03*
Y1061359D03*
Y1071398D03*
X1627896Y1089804D03*
X1623496Y1078091D03*
Y1101516D03*
Y1108209D03*
Y1114902D03*
X1627896Y1126615D03*
X1623496Y1138327D03*
Y1145020D03*
X1627896Y1163426D03*
X1623496Y1151713D03*
Y1175138D03*
Y1181831D03*
Y1188524D03*
X1627896Y1200237D03*
X1623496Y1211949D03*
Y1218642D03*
X1627896Y1237048D03*
X1623496Y1225335D03*
Y1248760D03*
Y1255453D03*
X1627052Y1424716D03*
X1627160Y1485895D03*
X1629070Y1483295D03*
Y1488495D03*
X1622370Y1492995D03*
X1627150D03*
X1620460Y1495595D03*
X1622370Y1498195D03*
X1627150D03*
X1620450Y1502695D03*
Y1507895D03*
X1621434Y1583797D03*
X1626159Y1583897D03*
X1630883D03*
X1621171Y1622884D03*
X1628275D03*
X1622245Y1637876D03*
Y1632884D03*
X1627201Y1637876D03*
Y1632884D03*
X1621171Y1627876D03*
X1628275D03*
X1621171Y1654796D03*
X1622245Y1649788D03*
X1628275Y1654796D03*
X1627201Y1649788D03*
X1622245Y1644796D03*
X1627201D03*
X1621171Y1659788D03*
X1628275D03*
X1638965Y3001D03*
X1648128Y17045D03*
X1633954D03*
X1638934D03*
X1648128Y22037D03*
X1648011Y25977D03*
X1633954Y22037D03*
X1638934D03*
X1646160Y19541D03*
X1640943D03*
X1641055Y23981D03*
X1646011D03*
X1639055Y25977D03*
X1633838D03*
X1647079Y37106D03*
X1639993D03*
X1647079Y48720D03*
X1639993D03*
X1634980Y72847D03*
X1639960D03*
X1645980Y71839D03*
X1644070Y69340D03*
X1645980Y66847D03*
X1634980Y77839D03*
X1639960D03*
X1642240Y399603D03*
X1642135Y414202D03*
X1639800Y426982D03*
X1636800D03*
X1639800Y429982D03*
X1636800D03*
X1639800Y432982D03*
X1636800D03*
X1647110Y434177D03*
X1639800Y435982D03*
X1636800D03*
X1639800Y438982D03*
X1636800D03*
X1635088Y756765D03*
Y763765D03*
X1639638Y773563D03*
X1644038Y791969D03*
X1634188Y786949D03*
X1639638Y780256D03*
X1634188Y796988D03*
X1639638Y803681D03*
Y810374D03*
Y817067D03*
X1644038Y828780D03*
X1634188Y823760D03*
Y833799D03*
X1639638Y840492D03*
Y847185D03*
X1644038Y865591D03*
X1634188Y860571D03*
X1639638Y853878D03*
X1634188Y870610D03*
X1639638Y877303D03*
Y883996D03*
Y890689D03*
X1644038Y902402D03*
X1634188Y897382D03*
Y907422D03*
X1639638Y914114D03*
Y920807D03*
X1644038Y939213D03*
X1634188Y934193D03*
X1639638Y927500D03*
X1634188Y944233D03*
X1639638Y950925D03*
Y957618D03*
Y964311D03*
Y971004D03*
Y977697D03*
Y984390D03*
Y991083D03*
Y997776D03*
Y1004469D03*
Y1031240D03*
Y1037933D03*
Y1044626D03*
Y1051319D03*
Y1058012D03*
Y1068051D03*
Y1074744D03*
X1644038Y1086457D03*
X1634188Y1081437D03*
Y1091477D03*
X1639638Y1098170D03*
Y1104862D03*
X1634188Y1118248D03*
X1639638Y1111555D03*
X1644038Y1123268D03*
X1634188Y1128288D03*
X1639638Y1134981D03*
Y1141674D03*
Y1148366D03*
X1644038Y1160079D03*
X1634188Y1155059D03*
Y1165099D03*
X1639638Y1171792D03*
Y1178485D03*
X1634188Y1191870D03*
X1639638Y1185177D03*
X1644038Y1196890D03*
X1634188Y1201910D03*
X1639638Y1208603D03*
Y1215296D03*
Y1221988D03*
X1644038Y1233701D03*
X1634188Y1228681D03*
Y1238721D03*
X1639638Y1245414D03*
Y1252107D03*
X1641904Y1351467D03*
Y1348567D03*
X1633850Y1483295D03*
Y1488495D03*
X1647260Y1495595D03*
X1640560Y1505295D03*
X1647250Y1502695D03*
X1642470D03*
X1647250Y1507895D03*
X1642470D03*
X1640332Y1583897D03*
X1645056Y1583697D03*
X1635608Y1583897D03*
X1633231Y1622884D03*
X1645291D03*
X1640335D03*
X1634305Y1637876D03*
Y1632790D03*
X1639261Y1637876D03*
Y1632790D03*
X1646365Y1637876D03*
Y1632884D03*
X1633231Y1627876D03*
X1640335D03*
X1645291D03*
X1633231Y1654796D03*
X1634305Y1649788D03*
X1640335Y1654796D03*
X1639261Y1649788D03*
X1645291Y1654796D03*
X1646365Y1649788D03*
X1634305Y1644796D03*
X1639261D03*
X1646365D03*
X1633231Y1659788D03*
X1640335D03*
X1645291D03*
X1647700Y1674228D03*
X1648013Y1713684D03*
Y1728834D03*
X1660965Y3001D03*
X1653108Y17045D03*
X1655116Y19541D03*
X1653108Y22037D03*
X1654166Y37106D03*
Y48720D03*
X1650960Y66847D03*
X1655066Y75343D03*
X1662065Y72850D03*
X1656980D03*
X1650960Y71839D03*
X1662065Y77842D03*
X1656980D03*
X1652610Y394727D03*
X1659610D03*
X1652810Y407402D03*
X1661110Y434177D03*
X1657747Y756765D03*
Y760265D03*
Y767265D03*
X1653197Y776910D03*
Y783603D03*
X1657597Y795315D03*
X1653197Y807028D03*
Y813721D03*
Y820414D03*
X1657597Y832126D03*
X1653197Y843839D03*
Y850532D03*
Y857225D03*
X1657597Y868937D03*
X1653197Y880650D03*
Y887343D03*
Y894036D03*
X1657597Y905749D03*
X1653197Y917461D03*
Y924154D03*
Y930847D03*
X1657597Y942560D03*
X1653197Y954272D03*
Y960965D03*
Y967658D03*
Y974351D03*
Y981044D03*
Y987736D03*
Y994429D03*
Y1004469D03*
Y1034587D03*
Y1041280D03*
Y1047973D03*
Y1054666D03*
Y1061359D03*
Y1071398D03*
X1657597Y1089804D03*
X1653197Y1078091D03*
Y1101516D03*
Y1108209D03*
Y1114902D03*
X1657597Y1126615D03*
X1653197Y1138327D03*
Y1145020D03*
X1657597Y1163426D03*
X1653197Y1151713D03*
Y1175138D03*
Y1188524D03*
Y1181831D03*
X1657597Y1200237D03*
X1653197Y1211949D03*
Y1218642D03*
X1657597Y1237048D03*
X1653197Y1225335D03*
Y1248760D03*
Y1255453D03*
X1660594Y1298735D03*
X1651187D03*
X1660594Y1303935D03*
Y1306535D03*
Y1301335D03*
X1651187Y1303935D03*
Y1306535D03*
Y1301335D03*
X1650177Y1351467D03*
Y1348567D03*
X1658904Y1351467D03*
Y1348567D03*
X1662010Y1384570D03*
X1662766Y1377814D03*
X1660166D03*
X1662766Y1374707D03*
X1660166D03*
X1651301Y1378765D03*
X1662010Y1390170D03*
X1654774Y1402619D03*
X1648857Y1403424D03*
X1662465Y1444358D03*
X1653960Y1485895D03*
X1655870Y1483295D03*
X1660650D03*
X1655870Y1488495D03*
X1660650D03*
X1649170Y1492995D03*
X1653950D03*
X1649170Y1498195D03*
X1653950D03*
X1654505Y1583897D03*
X1659229Y1583797D03*
X1649780Y1583897D03*
X1651321Y1637876D03*
Y1632884D03*
Y1649788D03*
Y1644796D03*
X1653464Y1668416D03*
X1661101Y1671631D03*
X1651101Y1700478D03*
X1660541Y1704237D03*
X1677972Y25977D03*
X1676121Y19541D03*
X1675972Y23981D03*
X1671016D03*
X1669016Y25977D03*
X1677040Y37106D03*
X1669953D03*
X1677040Y48720D03*
X1669953D03*
X1677204Y75340D03*
X1672960Y71839D03*
X1667980Y66847D03*
X1672960D03*
X1667980Y71839D03*
X1666070Y69340D03*
X1663610Y394727D03*
X1664789Y756765D03*
Y763765D03*
X1669339Y773563D03*
X1673739Y791969D03*
X1663889Y786949D03*
X1669339Y780256D03*
X1663889Y796988D03*
X1669339Y803681D03*
Y810374D03*
Y817067D03*
X1673739Y828780D03*
X1663889Y823760D03*
Y833799D03*
X1669339Y840492D03*
Y847185D03*
X1673739Y865591D03*
X1663889Y860571D03*
X1669339Y853878D03*
X1663889Y870610D03*
X1669339Y877303D03*
Y883996D03*
Y890689D03*
X1673739Y902402D03*
X1663889Y897382D03*
Y907422D03*
X1669339Y914114D03*
Y920807D03*
X1673739Y939213D03*
X1663889Y934193D03*
X1669339Y927500D03*
X1663889Y944233D03*
X1669339Y950925D03*
Y957618D03*
Y964311D03*
Y971004D03*
Y977697D03*
Y984390D03*
Y991083D03*
Y997776D03*
Y1004469D03*
Y1031240D03*
Y1037933D03*
Y1044626D03*
Y1051319D03*
Y1058012D03*
Y1068051D03*
Y1074744D03*
X1673739Y1086457D03*
X1663889Y1081437D03*
Y1091477D03*
X1669339Y1098170D03*
Y1104862D03*
X1663889Y1118248D03*
X1669339Y1111555D03*
X1673739Y1123268D03*
X1663889Y1128288D03*
X1669339Y1134981D03*
Y1141674D03*
Y1148366D03*
X1673739Y1160079D03*
X1663889Y1155059D03*
Y1165099D03*
X1669339Y1171792D03*
Y1178485D03*
X1663889Y1191870D03*
X1669339Y1185177D03*
X1673739Y1196890D03*
X1663889Y1201910D03*
X1669339Y1208603D03*
Y1215296D03*
Y1221988D03*
X1673739Y1233701D03*
X1663889Y1228681D03*
Y1238721D03*
X1669339Y1245414D03*
Y1252107D03*
X1675187Y1298735D03*
Y1303935D03*
Y1306535D03*
Y1301335D03*
X1674831Y1351266D03*
Y1348366D03*
X1675901Y1377594D03*
Y1380551D03*
X1666870Y1384570D03*
X1664440D03*
X1675510Y1374723D03*
X1667966Y1374707D03*
X1670566D03*
X1665366Y1377814D03*
Y1380771D03*
Y1374707D03*
X1667966Y1377814D03*
Y1380771D03*
X1673066Y1374707D03*
X1666870Y1390170D03*
X1664440D03*
X1666919Y1402585D03*
X1671067Y1405418D03*
X1672277Y1407694D03*
X1674777D03*
X1672907Y1429928D03*
X1672273Y1420567D03*
X1666290Y1444391D03*
X1667360Y1485895D03*
X1669270Y1483295D03*
X1674050D03*
X1669270Y1488495D03*
X1674050D03*
X1673674Y1563575D03*
X1670248Y1581563D03*
X1670534Y1670149D03*
X1673245Y1673475D03*
X1664256Y1690794D03*
X1673132Y1690741D03*
X1665520Y1716877D03*
Y1732027D03*
X1682965Y3001D03*
X1692262Y17045D03*
X1678088D03*
X1683068D03*
X1692262Y22037D03*
X1692145Y25977D03*
X1678088Y22037D03*
X1683068D03*
X1690294Y19541D03*
X1685077D03*
X1690145Y23981D03*
X1685189D03*
X1683189Y25977D03*
X1684127Y37106D03*
X1691213D03*
Y48720D03*
X1684127D03*
X1679114Y72847D03*
X1688200Y69343D03*
X1690114Y66850D03*
Y71842D03*
X1684094Y72847D03*
X1679114Y77839D03*
X1684094D03*
X1687448Y756765D03*
Y760265D03*
X1682898Y776910D03*
X1687448Y767265D03*
X1682898Y783603D03*
X1687298Y795315D03*
X1682898Y807028D03*
Y820414D03*
Y813721D03*
X1687298Y832126D03*
X1682898Y850532D03*
Y843839D03*
Y857225D03*
X1687298Y868937D03*
X1682898Y880650D03*
Y894036D03*
Y887343D03*
X1687298Y905749D03*
X1682898Y917461D03*
Y924154D03*
Y930847D03*
X1687298Y942560D03*
X1682898Y954272D03*
Y967658D03*
Y960965D03*
Y981044D03*
Y974351D03*
Y994429D03*
Y987736D03*
Y1004469D03*
Y1041280D03*
Y1034587D03*
Y1054666D03*
Y1047973D03*
Y1061359D03*
Y1071398D03*
Y1078091D03*
X1687298Y1089804D03*
X1682898Y1101516D03*
Y1108209D03*
Y1114902D03*
X1687298Y1126615D03*
X1682898Y1138327D03*
Y1145020D03*
Y1151713D03*
X1687298Y1163426D03*
X1682898Y1175138D03*
Y1188524D03*
Y1181831D03*
X1687298Y1200237D03*
X1682898Y1211949D03*
Y1218642D03*
Y1225335D03*
X1687298Y1237048D03*
X1682898Y1248760D03*
Y1255453D03*
X1684708Y1298435D03*
Y1303635D03*
Y1306235D03*
Y1301035D03*
X1687233Y1351320D03*
X1679133Y1351420D03*
X1687233Y1348420D03*
X1679133Y1348520D03*
X1679180Y1372169D03*
X1681780D03*
X1679180Y1366969D03*
X1681780D03*
Y1369569D03*
X1679180D03*
X1683896Y1378765D03*
X1692948Y1377914D03*
Y1374807D03*
X1680530Y1374669D03*
X1685963Y1402187D03*
X1687621Y1404138D03*
X1684172Y1538135D03*
X1682561Y1552726D03*
X1691226Y1563526D03*
X1680558Y1555690D03*
X1691226Y1559526D03*
X1682494Y1568271D03*
Y1575125D03*
X1680491Y1578089D03*
Y1571235D03*
X1689880Y1572067D03*
X1679420Y1683597D03*
X1683013Y1713684D03*
X1680519Y1726825D03*
X1689383Y1729187D03*
X1704965Y3001D03*
X1697242Y17045D03*
X1699250Y19541D03*
X1697242Y22037D03*
X1698300Y37106D03*
X1705381Y37108D03*
X1698300Y48720D03*
X1705386D03*
X1701114Y72847D03*
X1706094D03*
X1699204Y75340D03*
X1695094Y66850D03*
Y71842D03*
X1706094Y77839D03*
X1701114D03*
X1694490Y756765D03*
Y763765D03*
X1699040Y773563D03*
X1703440Y791969D03*
X1699040Y780256D03*
X1693590Y786949D03*
X1699040Y803681D03*
X1693590Y796988D03*
X1699040Y817067D03*
Y810374D03*
X1693590Y823760D03*
X1703440Y828780D03*
X1693590Y833799D03*
X1699040Y847185D03*
Y840492D03*
Y853878D03*
X1693590Y860571D03*
X1703440Y865591D03*
X1693590Y870610D03*
X1699040Y877303D03*
Y883996D03*
Y890689D03*
X1693590Y907422D03*
X1703440Y902402D03*
X1693590Y897382D03*
X1699040Y914114D03*
Y920807D03*
X1693590Y934193D03*
X1699040Y927500D03*
X1703440Y939213D03*
X1693590Y944233D03*
X1699040Y950925D03*
Y964311D03*
Y971004D03*
Y957618D03*
Y977697D03*
Y984390D03*
Y997776D03*
Y991083D03*
Y1004469D03*
Y1044626D03*
Y1037933D03*
Y1031240D03*
Y1058012D03*
Y1051319D03*
Y1074744D03*
Y1068051D03*
X1703440Y1086457D03*
X1693590Y1081437D03*
Y1091477D03*
X1699040Y1104862D03*
Y1098170D03*
Y1111555D03*
X1693590Y1118248D03*
X1699040Y1134981D03*
X1703440Y1123268D03*
X1693590Y1128288D03*
X1699040Y1141674D03*
Y1148366D03*
X1693590Y1155059D03*
Y1165099D03*
X1703440Y1160079D03*
X1699040Y1171792D03*
Y1178485D03*
X1693590Y1191870D03*
X1699040Y1185177D03*
X1693590Y1201910D03*
X1703440Y1196890D03*
X1699040Y1208603D03*
Y1221988D03*
Y1215296D03*
X1693590Y1228681D03*
Y1238721D03*
X1703440Y1233701D03*
X1699040Y1245414D03*
Y1252107D03*
X1699087Y1298435D03*
Y1303635D03*
Y1306235D03*
Y1301035D03*
X1695533Y1351320D03*
Y1348420D03*
X1694792Y1384670D03*
X1700748Y1377914D03*
Y1380871D03*
Y1374807D03*
X1703348D03*
X1705848D03*
X1698148Y1377914D03*
X1695548D03*
X1698148Y1380871D03*
X1695548Y1374807D03*
X1698148D03*
X1699652Y1384670D03*
X1697222D03*
X1699652Y1390270D03*
X1694792D03*
X1697222D03*
X1699701Y1402685D03*
X1700520Y1716877D03*
X1702777Y1723593D03*
X1695166Y1717606D03*
X1720148Y22910D03*
X1710886Y82208D03*
X1715550Y102923D03*
X1721400Y374462D03*
X1718241Y652105D03*
X1717149Y756765D03*
Y760265D03*
X1712599Y776910D03*
X1717149Y767265D03*
X1712599Y783603D03*
Y807028D03*
X1716999Y795315D03*
X1712599Y820414D03*
Y813721D03*
X1716999Y832126D03*
X1712599Y850532D03*
Y843839D03*
Y857225D03*
X1716999Y868937D03*
X1712599Y880650D03*
Y894036D03*
Y887343D03*
X1716999Y905749D03*
X1712599Y917461D03*
Y924154D03*
Y930847D03*
X1716999Y942560D03*
X1712599Y954272D03*
Y967658D03*
Y960965D03*
Y981044D03*
Y974351D03*
Y994429D03*
Y987736D03*
Y1004469D03*
Y1041280D03*
Y1034587D03*
Y1054666D03*
Y1047973D03*
Y1061359D03*
Y1071398D03*
Y1078091D03*
X1716999Y1089804D03*
X1712599Y1101516D03*
Y1108209D03*
Y1114902D03*
X1716999Y1126615D03*
X1712599Y1138327D03*
Y1145020D03*
Y1151713D03*
X1716999Y1163426D03*
X1712599Y1175138D03*
Y1188524D03*
Y1181831D03*
X1716999Y1200237D03*
X1712599Y1218642D03*
Y1211949D03*
Y1225335D03*
X1716999Y1237048D03*
X1712599Y1248760D03*
Y1255453D03*
X1721754Y1299488D03*
X1708754Y1298388D03*
X1721847Y1307298D03*
X1721754Y1304688D03*
X1708754Y1300988D03*
X1721754Y1302088D03*
X1708754Y1303588D03*
Y1306188D03*
X1718813Y1348450D03*
Y1351350D03*
X1709533Y1351520D03*
Y1348620D03*
X1711962Y1367069D03*
X1714562D03*
X1711962Y1369669D03*
X1714562D03*
X1719902Y1368509D03*
Y1365909D03*
Y1363409D03*
X1708678Y1380621D03*
Y1377664D03*
X1716267Y1375178D03*
X1713312Y1374769D03*
X1708292Y1374823D03*
X1720210Y1435330D03*
X1719893Y1594940D03*
Y1612940D03*
Y1599740D03*
Y1603040D03*
Y1606340D03*
Y1609640D03*
X1722133Y1725340D03*
X1727111Y-38849D03*
Y-28849D03*
X1726965Y3001D03*
X1732286Y28208D03*
X1728786D03*
X1725286D03*
X1727336Y57024D03*
X1726596Y61784D03*
X1729836Y57024D03*
X1726596Y64284D03*
X1726814Y102968D03*
X1733344Y134953D03*
X1736474D03*
X1730364Y177588D03*
X1725400Y372062D03*
X1737260Y368132D03*
X1732660Y372692D03*
X1725500Y383662D03*
X1723259Y653641D03*
X1726334Y670345D03*
X1724191Y756765D03*
Y763765D03*
X1728741Y773563D03*
X1733141Y791969D03*
X1723291Y786949D03*
X1728741Y780256D03*
Y803681D03*
X1723291Y796988D03*
X1728741Y817067D03*
Y810374D03*
X1733141Y828780D03*
X1723291Y823760D03*
Y833799D03*
X1728741Y847185D03*
Y840492D03*
Y853878D03*
X1733141Y865591D03*
X1723291Y860571D03*
Y870610D03*
X1728741Y877303D03*
Y883996D03*
Y890689D03*
X1723291Y907422D03*
X1733141Y902402D03*
X1723291Y897382D03*
X1728741Y914114D03*
Y920807D03*
X1723291Y934193D03*
X1728741Y927500D03*
X1733141Y939213D03*
X1723291Y944233D03*
X1728741Y950925D03*
Y964311D03*
Y971004D03*
Y957618D03*
Y977697D03*
Y984390D03*
Y997776D03*
Y991083D03*
Y1004469D03*
Y1044626D03*
Y1037933D03*
Y1031240D03*
Y1058012D03*
Y1051319D03*
Y1074744D03*
Y1068051D03*
X1733141Y1086457D03*
X1723291Y1081437D03*
Y1091477D03*
X1728741Y1104862D03*
Y1098170D03*
Y1111555D03*
X1723291Y1118248D03*
X1728741Y1134981D03*
X1733141Y1123268D03*
X1723291Y1128288D03*
X1728741Y1141674D03*
Y1148366D03*
X1723291Y1155059D03*
X1733141Y1160079D03*
X1723291Y1165099D03*
X1728741Y1171792D03*
Y1178485D03*
X1723291Y1191870D03*
X1728741Y1185177D03*
X1723291Y1201910D03*
X1733141Y1196890D03*
X1728741Y1208603D03*
Y1221988D03*
Y1215296D03*
X1733141Y1233701D03*
X1723291Y1228681D03*
Y1238721D03*
X1728741Y1245414D03*
Y1252107D03*
X1732624Y1299718D03*
X1732717Y1307528D03*
X1732624Y1302318D03*
Y1304918D03*
X1735202Y1368279D03*
Y1365679D03*
Y1363179D03*
X1723917Y1380518D03*
Y1377178D03*
X1737126Y1403838D03*
Y1401238D03*
X1722810Y1435330D03*
X1737541Y1543707D03*
X1734575Y1562068D03*
X1724323Y1676965D03*
X1748965Y3001D03*
X1752008Y25146D03*
X1748116Y37058D03*
X1745451Y119585D03*
X1747448Y121413D03*
X1750325Y179827D03*
X1750851Y216427D03*
X1748325D03*
X1752461Y255337D03*
Y252337D03*
X1742652Y671494D03*
X1746850Y756765D03*
Y760265D03*
X1742300Y776910D03*
X1746850Y767265D03*
X1742300Y783603D03*
X1746700Y795315D03*
X1742300Y807028D03*
Y820414D03*
Y813721D03*
X1746700Y832126D03*
X1742300Y850532D03*
Y843839D03*
Y857225D03*
X1746700Y868937D03*
X1742300Y880650D03*
Y894036D03*
Y887343D03*
X1746700Y905749D03*
X1742300Y917461D03*
Y924154D03*
Y930847D03*
X1746700Y942560D03*
X1742300Y954272D03*
Y960965D03*
Y967658D03*
Y981044D03*
Y974351D03*
Y994429D03*
Y987736D03*
Y1004469D03*
Y1041280D03*
Y1034587D03*
Y1054666D03*
Y1047973D03*
Y1061359D03*
Y1071398D03*
Y1078091D03*
X1746700Y1089804D03*
X1742300Y1101516D03*
Y1108209D03*
Y1114902D03*
X1746700Y1126615D03*
X1742300Y1138327D03*
Y1145020D03*
Y1151713D03*
X1746700Y1163426D03*
X1742300Y1175138D03*
Y1188524D03*
Y1181831D03*
X1746700Y1200237D03*
X1742300Y1218642D03*
Y1211949D03*
Y1225335D03*
X1746700Y1237048D03*
X1742300Y1248760D03*
Y1255453D03*
X1743072Y1432211D03*
X1743188Y1543871D03*
Y1547871D03*
X1740587Y1547946D03*
X1737738Y1548021D03*
X1740400Y1543682D03*
X1752364Y1556323D03*
Y1559430D03*
X1744564Y1556323D03*
Y1559430D03*
X1749764Y1556323D03*
Y1559430D03*
X1747164Y1556323D03*
Y1559430D03*
X1752564Y1562537D03*
X1751518Y1566186D03*
X1740079Y1559505D03*
X1740188Y1556371D03*
X1746558Y1566186D03*
X1749038D03*
X1749964Y1562537D03*
X1751518Y1571786D03*
X1746558D03*
X1749038D03*
X1739640Y1713383D03*
Y1728533D03*
X1762420Y17031D03*
X1763840Y37790D03*
X1753398Y48720D03*
X1760485D03*
X1759666Y57708D03*
X1764366Y57508D03*
X1758047Y68637D03*
X1758539Y87153D03*
Y83653D03*
X1758534Y79743D03*
X1765034Y80443D03*
X1766244Y93673D03*
X1766911Y179890D03*
X1752851Y179827D03*
X1757385Y179890D03*
X1764385D03*
X1759911D03*
X1757951Y216427D03*
X1755425D03*
X1762485Y216490D03*
X1765011D03*
X1758859Y251544D03*
Y248544D03*
X1766399Y251361D03*
Y248361D03*
X1753892Y756765D03*
Y763765D03*
X1758442Y773563D03*
X1762842Y791969D03*
X1752992Y786949D03*
X1758442Y780256D03*
Y803681D03*
X1752992Y796988D03*
X1758442Y817067D03*
Y810374D03*
X1752992Y823760D03*
Y833799D03*
X1762842Y828780D03*
X1758442Y847185D03*
Y840492D03*
X1752992Y860571D03*
X1758442Y853878D03*
X1762842Y865591D03*
X1752992Y870610D03*
X1758442Y877303D03*
Y883996D03*
Y890689D03*
X1752992Y907422D03*
Y897382D03*
X1762842Y902402D03*
X1758442Y914114D03*
Y920807D03*
X1752992Y934193D03*
X1758442Y927500D03*
X1762842Y939213D03*
X1752992Y944233D03*
X1758442Y950925D03*
Y964311D03*
Y971004D03*
Y957618D03*
Y977697D03*
Y984390D03*
Y997776D03*
Y991083D03*
Y1004469D03*
Y1044626D03*
Y1037933D03*
Y1031240D03*
Y1058012D03*
Y1051319D03*
Y1074744D03*
Y1068051D03*
X1752992Y1081437D03*
X1762842Y1086457D03*
X1752992Y1091477D03*
X1758442Y1104862D03*
Y1098170D03*
X1752992Y1118248D03*
X1758442Y1111555D03*
Y1134981D03*
X1752992Y1128288D03*
X1762842Y1123268D03*
X1758442Y1141674D03*
Y1148366D03*
X1752992Y1155059D03*
Y1165099D03*
X1762842Y1160079D03*
X1758442Y1171792D03*
Y1178485D03*
X1752992Y1191870D03*
X1758442Y1185177D03*
X1752992Y1201910D03*
X1762842Y1196890D03*
X1758442Y1208603D03*
Y1221988D03*
Y1215296D03*
X1752992Y1228681D03*
Y1238721D03*
X1762842Y1233701D03*
X1758442Y1245414D03*
Y1252107D03*
X1758238Y1556238D03*
X1761108Y1556339D03*
Y1559446D03*
X1761079Y1562605D03*
X1755038Y1556238D03*
X1765709Y1556050D03*
X1754479Y1585905D03*
X1754763Y1641665D03*
X1752864Y1716383D03*
X1770965Y3001D03*
X1772886Y37430D03*
X1768134Y80543D03*
X1771385Y179890D03*
X1773911D03*
X1778500Y183790D03*
X1769585Y215090D03*
X1772111D03*
X1776585D03*
X1779111D03*
X1778874Y253799D03*
Y256799D03*
X1770520Y364148D03*
Y368148D03*
X1771236Y557224D03*
X1776550Y756765D03*
Y760265D03*
X1772000Y776910D03*
X1776550Y767265D03*
X1772000Y783603D03*
Y807028D03*
X1776400Y795315D03*
X1772000Y813721D03*
Y820414D03*
X1776400Y832126D03*
X1772000Y850532D03*
Y843839D03*
Y857225D03*
X1776400Y868937D03*
X1772000Y880650D03*
Y894036D03*
Y887343D03*
X1776400Y905749D03*
X1772000Y917461D03*
Y924154D03*
Y930847D03*
X1776400Y942560D03*
X1772000Y954272D03*
Y967658D03*
Y960965D03*
Y981044D03*
Y974351D03*
Y994429D03*
Y987736D03*
Y1004469D03*
Y1041280D03*
Y1034587D03*
Y1047973D03*
Y1054666D03*
Y1061359D03*
Y1071398D03*
Y1078091D03*
X1776400Y1089804D03*
X1772000Y1101516D03*
Y1108209D03*
Y1114902D03*
X1776400Y1126615D03*
X1772000Y1138327D03*
Y1145020D03*
Y1151713D03*
X1776400Y1163426D03*
X1772000Y1175138D03*
Y1188524D03*
Y1181831D03*
X1776400Y1200237D03*
X1772000Y1218642D03*
Y1211949D03*
Y1225335D03*
X1776400Y1237048D03*
X1772000Y1248760D03*
Y1255453D03*
X1776188Y1543871D03*
Y1546871D03*
X1769188D03*
Y1543871D03*
X1768688Y1552871D03*
Y1549871D03*
X1772688Y1543871D03*
Y1546871D03*
X1776113Y1541172D03*
X1769113D03*
X1772613D03*
X1780307Y1559430D03*
Y1556323D03*
X1775979Y1556805D03*
Y1559805D03*
X1782301Y1566186D03*
X1768209Y1556000D03*
X1769826Y1562559D03*
X1782301Y1571786D03*
X1792965Y3001D03*
X1796781Y46686D03*
X1785144Y86973D03*
Y89973D03*
X1783448Y212957D03*
X1795794Y253719D03*
X1787534Y253769D03*
X1795794Y256719D03*
X1787534Y256769D03*
X1795479Y408056D03*
X1795468Y421334D03*
X1783592Y756765D03*
X1788142Y773563D03*
X1792542Y791969D03*
X1782692Y786949D03*
X1788142Y780256D03*
X1782692Y796988D03*
X1788142Y803681D03*
Y817067D03*
Y810374D03*
X1782692Y823760D03*
Y833799D03*
X1792542Y828780D03*
X1788142Y847185D03*
Y840492D03*
Y853878D03*
X1792542Y865591D03*
X1782692Y860571D03*
Y870610D03*
X1788142Y877303D03*
Y883996D03*
Y890689D03*
X1782692Y907422D03*
Y897382D03*
X1792542Y902402D03*
X1788142Y914114D03*
Y920807D03*
X1782692Y934193D03*
X1788142Y927500D03*
X1792542Y939213D03*
X1782692Y944233D03*
X1788142Y950925D03*
Y964311D03*
Y971004D03*
Y957618D03*
Y977697D03*
Y984390D03*
Y997776D03*
Y991083D03*
Y1004469D03*
Y1044626D03*
Y1037933D03*
Y1031240D03*
Y1058012D03*
Y1051319D03*
Y1074744D03*
Y1068051D03*
X1782692Y1081437D03*
X1792542Y1086457D03*
X1782692Y1091477D03*
X1788142Y1098170D03*
Y1104862D03*
X1782692Y1118248D03*
X1788142Y1111555D03*
Y1134981D03*
X1782692Y1128288D03*
X1792542Y1123268D03*
X1788142Y1141674D03*
Y1148366D03*
X1782692Y1155059D03*
Y1165099D03*
X1792542Y1160079D03*
X1788142Y1171792D03*
Y1178485D03*
X1782692Y1191870D03*
X1788142Y1185177D03*
X1782692Y1201910D03*
X1792542Y1196890D03*
X1788142Y1208603D03*
Y1221988D03*
Y1215296D03*
X1782692Y1228681D03*
Y1238721D03*
X1792542Y1233701D03*
X1788142Y1245414D03*
Y1252107D03*
X1796838Y1556125D03*
X1788107Y1556323D03*
X1793833Y1556195D03*
X1790633D03*
X1788107Y1559430D03*
X1788307Y1562537D03*
X1787261Y1566186D03*
X1782907Y1559430D03*
Y1556323D03*
X1784781Y1566186D03*
X1785507Y1559430D03*
Y1556323D03*
X1785707Y1562537D03*
X1796257Y1561255D03*
Y1558755D03*
X1787261Y1571786D03*
X1784781D03*
X1788679Y1585805D03*
X1807515Y56461D03*
X1807546Y59443D03*
X1807296Y255033D03*
X1804174Y253739D03*
Y256739D03*
X1803129Y362293D03*
X1802929Y385293D03*
X1804688Y1545871D03*
Y1542371D03*
Y1552871D03*
Y1549371D03*
X1801688Y1545871D03*
Y1542371D03*
Y1552871D03*
Y1549371D03*
X1804688Y1555871D03*
X1801688D03*
X1804688Y1559371D03*
X1818615Y49379D03*
X1818155Y149325D03*
X1819529Y320321D03*
X1820307Y373829D03*
X1820656Y388051D03*
X1820144Y398052D03*
X1819374Y410432D03*
X1818874Y423932D03*
X1840615Y49379D03*
X1853692Y308447D03*
G54D40*
X311115Y1214093D03*
X310957Y1219126D03*
X388805Y1218420D03*
X388647Y1223453D03*
X386461Y1235718D03*
X386303Y1240751D03*
X1898799Y1810398D03*
X1908799D03*
X1931395Y572237D03*
X1921395D03*
X1942395Y1184617D03*
X1940886Y1810370D03*
X1963362Y572379D03*
X1952395Y1184617D03*
X1950886Y1810370D03*
X1973362Y572379D03*
X1984482Y1184589D03*
X1992856Y1810550D03*
X1982856D03*
X2005452Y572389D03*
X1994482Y1184589D03*
X2015452Y572389D03*
X2036452Y1184769D03*
X2026452D03*
X2047419Y572531D03*
X2057419D03*
X2078539Y1184741D03*
X2068539D03*
G54D56*
X828780Y1684890D03*
X818780D03*
X828780Y1694890D03*
X818780D03*
X828780Y1704890D03*
X818780D03*
X828780Y1714890D03*
X818780D03*
X853780Y1684890D03*
Y1694890D03*
Y1704890D03*
Y1714890D03*
X863780Y1684890D03*
Y1694890D03*
Y1704890D03*
Y1714890D03*
X888780Y1684890D03*
Y1694890D03*
Y1704890D03*
Y1714890D03*
X898780Y1684890D03*
Y1694890D03*
Y1704890D03*
Y1714890D03*
X918780Y1704890D03*
X958780Y1684890D03*
Y1694890D03*
Y1704890D03*
Y1714890D03*
X968780Y1684890D03*
Y1694890D03*
Y1704890D03*
Y1714890D03*
X993780Y1684890D03*
Y1694890D03*
Y1704890D03*
Y1714890D03*
X1003780Y1684890D03*
Y1694890D03*
Y1704890D03*
Y1714890D03*
X1028780Y1684890D03*
X1038780D03*
X1028780Y1694890D03*
X1038780D03*
X1028780Y1704890D03*
Y1714890D03*
X1038780Y1704890D03*
Y1714890D03*
G54D29*
X182947Y1507512D03*
X186530Y1521453D03*
X185688Y1519195D03*
X186860Y1514243D03*
X186579Y1536063D03*
X177579Y1528725D03*
Y1523810D03*
X183051Y1542425D03*
X185966Y1592380D03*
Y1624292D03*
X188254Y1507295D03*
X192979D03*
X197703D03*
X191254Y1521453D03*
X195979D03*
X200703D03*
X196309Y1514243D03*
X201033D03*
X191584D03*
X187081Y1528853D03*
X191805D03*
X196530D03*
X201254D03*
X196029Y1536063D03*
X200753D03*
X191304D03*
X197703Y1542641D03*
X188254D03*
X192979D03*
X198026Y1592380D03*
X193766D03*
X192006Y1602380D03*
X199786D03*
X193766Y1624292D03*
X198026D03*
X199786Y1614292D03*
X192006D03*
X202427Y1507295D03*
X207152D03*
X211876D03*
X216601D03*
X205427Y1521453D03*
X210152D03*
X214876D03*
X205758Y1514243D03*
X215206D03*
X210482D03*
X205978Y1528853D03*
X210703D03*
X215427D03*
X214926Y1536063D03*
X211876Y1542641D03*
X202427D03*
X207152D03*
X216601D03*
X210086Y1592380D03*
X205826D03*
X216126Y1602380D03*
X204066D03*
X211846D03*
X205826Y1624292D03*
X210086D03*
X216126Y1614292D03*
X211846D03*
X204066D03*
X221325Y1507295D03*
X226049D03*
X230774D03*
X219601Y1521453D03*
X224325D03*
X229049D03*
X219931Y1514243D03*
X224655D03*
X229380D03*
X220152Y1528853D03*
X224876D03*
X229600D03*
X224375Y1536063D03*
X226049Y1542641D03*
X230774D03*
X221325D03*
X229946Y1592380D03*
X217886D03*
X222146D03*
X223906Y1602380D03*
X228186D03*
X229946Y1624292D03*
X222146D03*
X217886D03*
X228186Y1614292D03*
X223906D03*
X235498Y1507295D03*
X240223D03*
X244947D03*
X243223Y1521453D03*
X238498D03*
X233774D03*
X234104Y1514243D03*
X238828D03*
X243553D03*
X243774Y1528853D03*
X239049D03*
X234325D03*
X238548Y1536063D03*
X240223Y1542641D03*
X235498D03*
X244947D03*
X242006Y1592380D03*
X234206D03*
X246266D03*
X235966Y1602380D03*
X240246D03*
X246266Y1624292D03*
X242006D03*
X234206D03*
X240246Y1614292D03*
X235966D03*
X241141Y1679320D03*
Y1683857D03*
X233267Y1675383D03*
Y1679920D03*
Y1684454D03*
X241141Y1688391D03*
Y1693493D03*
Y1698030D03*
X233267Y1689556D03*
Y1694093D03*
Y1698627D03*
X241141Y1702564D03*
Y1707666D03*
Y1712203D03*
Y1716737D03*
X233267Y1703729D03*
Y1708266D03*
Y1712800D03*
X241141Y1721840D03*
Y1726377D03*
Y1730911D03*
X233267Y1717903D03*
Y1722440D03*
Y1726974D03*
X259120Y1507295D03*
X249671D03*
X254396D03*
X257396Y1521453D03*
X252672D03*
X247947D03*
X248277Y1514243D03*
X257726D03*
X257947Y1528853D03*
X253223D03*
X248498D03*
X257446Y1536063D03*
X247997D03*
X254396Y1542641D03*
X259120D03*
X249671D03*
X258326Y1592380D03*
X254066D03*
X248026Y1602380D03*
X252306D03*
X260086D03*
X258326Y1624292D03*
X254066D03*
X248026Y1614292D03*
X252306D03*
X260086D03*
X256889Y1679320D03*
Y1683857D03*
X249015Y1684454D03*
Y1679920D03*
Y1675383D03*
X256889Y1688391D03*
Y1693493D03*
Y1698030D03*
X249015Y1698627D03*
Y1694093D03*
Y1689556D03*
X256889Y1702564D03*
Y1707666D03*
Y1712203D03*
Y1716737D03*
X249015Y1712800D03*
Y1708266D03*
Y1703729D03*
X256889Y1721840D03*
Y1726377D03*
Y1730911D03*
X249015Y1726974D03*
Y1722440D03*
Y1717903D03*
X262141Y1521453D03*
X262777Y1536063D03*
X270386Y1592380D03*
X266126D03*
X264366Y1602380D03*
X272146D03*
X270386Y1624292D03*
X266126D03*
X272146Y1614292D03*
X264366D03*
X272637Y1679320D03*
Y1683857D03*
X264763Y1684454D03*
Y1679920D03*
Y1675383D03*
X272637Y1688391D03*
Y1693493D03*
Y1698030D03*
X264763Y1698627D03*
Y1694093D03*
Y1689556D03*
X272637Y1702564D03*
Y1707666D03*
Y1712203D03*
Y1716737D03*
X264763Y1712800D03*
Y1708266D03*
Y1703729D03*
X272637Y1721840D03*
Y1726377D03*
Y1730911D03*
X264763Y1726974D03*
Y1722440D03*
Y1717903D03*
X290246Y1592380D03*
X278186D03*
X282446D03*
X276426Y1602380D03*
X284206D03*
X288486D03*
X290236Y1624292D03*
X282446D03*
X278186D03*
X288486Y1614292D03*
X284206D03*
X276426D03*
X288385Y1683857D03*
Y1679320D03*
X280511Y1684454D03*
Y1679920D03*
Y1675383D03*
X288385Y1688391D03*
Y1693494D03*
Y1698031D03*
X280511Y1698627D03*
Y1694093D03*
Y1689556D03*
X288385Y1712204D03*
Y1716738D03*
Y1702565D03*
Y1707667D03*
X280511Y1712800D03*
Y1708266D03*
Y1703729D03*
X288385Y1721840D03*
Y1726377D03*
Y1730911D03*
X280511Y1726974D03*
Y1722440D03*
Y1717903D03*
X305641Y1528725D03*
Y1523810D03*
X302306Y1592380D03*
X294506D03*
X296266Y1602380D03*
X300546D03*
X302306Y1624292D03*
X294516D03*
X300546Y1614292D03*
X296266D03*
X300196Y1675383D03*
Y1679920D03*
Y1684454D03*
Y1689556D03*
Y1694093D03*
Y1698627D03*
Y1703729D03*
Y1708266D03*
Y1712800D03*
Y1717903D03*
Y1722440D03*
Y1726974D03*
X309886Y1028056D03*
X315437Y1031245D03*
X317288Y1040812D03*
X309886D03*
X317288Y1034434D03*
X309886D03*
X315437Y1044001D03*
X309886Y1047190D03*
X311736Y1056757D03*
X309886Y1053568D03*
X315437Y1050379D03*
X317288Y1053568D03*
Y1059946D03*
X309886D03*
X313587D03*
X315437Y1063135D03*
X317288Y1072702D03*
X309886D03*
Y1066324D03*
X315437Y1069513D03*
X317288Y1079080D03*
X309886D03*
X315437Y1082269D03*
Y1088647D03*
X309886Y1085458D03*
Y1091836D03*
X317288D03*
X309886Y1104592D03*
X315437Y1101403D03*
X317288Y1098214D03*
X309886D03*
X315437Y1107781D03*
X309886Y1110970D03*
X317288D03*
X309886Y1117348D03*
X317288D03*
X309886Y1123726D03*
X315437Y1120537D03*
Y1126915D03*
X309886Y1130103D03*
X317288D03*
X309886Y1136481D03*
X315437Y1139670D03*
X317288Y1136481D03*
X309886Y1142859D03*
X317288Y1149237D03*
X309886D03*
X315437Y1146048D03*
X317288Y1155615D03*
X309886D03*
X313587D03*
X308036Y1158804D03*
X311736Y1165182D03*
X320988Y1155615D03*
Y1161993D03*
X311009Y1507514D03*
X316316Y1507295D03*
X321041D03*
X319316Y1521453D03*
X314592D03*
X313750Y1519195D03*
X314922Y1514243D03*
X319646D03*
X319867Y1528853D03*
X315143D03*
X319366Y1536063D03*
X314641D03*
X311113Y1542425D03*
X316316Y1542641D03*
X321041D03*
X318626Y1592380D03*
X306566D03*
X314366D03*
X308326Y1602380D03*
X312606D03*
X320386D03*
X314366Y1624292D03*
X318626D03*
X306566D03*
X320386Y1614292D03*
X312606D03*
X308326D03*
X315944Y1675383D03*
Y1679920D03*
Y1684454D03*
X308070Y1683857D03*
Y1679320D03*
X315944Y1689556D03*
Y1694093D03*
Y1698627D03*
X308070Y1698030D03*
Y1693493D03*
Y1688391D03*
X315944Y1703729D03*
Y1708266D03*
Y1712800D03*
X308070Y1716737D03*
Y1712203D03*
Y1707666D03*
Y1702564D03*
X315944Y1722440D03*
Y1726974D03*
X308070Y1730911D03*
Y1726377D03*
Y1721840D03*
X315944Y1717903D03*
X328390Y1028056D03*
X335791D03*
X322839Y1031245D03*
Y1037623D03*
Y1044001D03*
X328390Y1040812D03*
Y1034434D03*
X330240Y1031245D03*
Y1037623D03*
Y1044001D03*
X335791Y1040812D03*
Y1034434D03*
X328390Y1047190D03*
X322839Y1050379D03*
Y1056757D03*
X326539D03*
X328390Y1053568D03*
Y1059946D03*
X324689D03*
X330240Y1050379D03*
Y1056757D03*
X335791Y1047190D03*
Y1053568D03*
Y1059946D03*
X328390Y1072702D03*
X330240Y1069513D03*
X335791Y1072702D03*
Y1066324D03*
X322839Y1063135D03*
X330240D03*
X322839Y1069513D03*
X328390Y1066324D03*
X322839Y1075891D03*
X330240D03*
X328390Y1079080D03*
X322839Y1088647D03*
X328390Y1085458D03*
X330240Y1088647D03*
X322839Y1082269D03*
X330240D03*
X335791Y1079080D03*
Y1085458D03*
X328390Y1091836D03*
X322839Y1095025D03*
X330240D03*
X328390Y1104592D03*
Y1098214D03*
X322839Y1101403D03*
X330240D03*
X335791Y1091836D03*
Y1104592D03*
Y1098214D03*
X322839Y1107781D03*
X330240D03*
X328390Y1110970D03*
Y1117348D03*
X330240Y1114159D03*
X322839D03*
X335791Y1110970D03*
Y1117348D03*
X330240Y1126915D03*
X322839D03*
X328390Y1123726D03*
X330240Y1120537D03*
X322839D03*
Y1133293D03*
X330240D03*
X328390Y1130103D03*
X335791Y1123726D03*
X335792Y1130105D03*
X328390Y1142859D03*
X322839Y1139670D03*
X328390Y1136481D03*
X330240Y1139670D03*
X328390Y1149237D03*
X330240Y1146048D03*
X322839D03*
X335791Y1136481D03*
Y1142859D03*
Y1149237D03*
X328390Y1155615D03*
X330240Y1152426D03*
X322839D03*
X326539Y1158804D03*
X330240D03*
X333941D03*
X322839D03*
X328390Y1161993D03*
X330240Y1165182D03*
X335791Y1155615D03*
Y1161993D03*
X330489Y1507295D03*
X335214D03*
X325765D03*
X333489Y1521453D03*
X328765D03*
X324041D03*
X324371Y1514243D03*
X329095D03*
X333820D03*
X334040Y1528853D03*
X329316D03*
X324592D03*
X324091Y1536063D03*
X328815D03*
X325765Y1542641D03*
X330489D03*
X335214D03*
X330686Y1592380D03*
X326426D03*
X324666Y1602380D03*
X332446D03*
X326426Y1624292D03*
X330686D03*
X332446Y1614292D03*
X324666D03*
X331692Y1675383D03*
Y1679920D03*
Y1684454D03*
X323818Y1683857D03*
Y1679320D03*
X331692Y1689556D03*
Y1694093D03*
Y1698627D03*
X323818Y1698030D03*
Y1693493D03*
Y1688391D03*
X331692Y1703729D03*
Y1708266D03*
Y1712800D03*
X323818Y1716737D03*
Y1712203D03*
Y1707666D03*
Y1702564D03*
Y1721840D03*
X331692Y1717903D03*
Y1722440D03*
Y1726974D03*
X323818Y1730911D03*
Y1726377D03*
X348744Y1031245D03*
X341343D03*
X343193Y1040812D03*
X348744Y1037623D03*
X343193Y1034434D03*
X348744Y1044001D03*
X341343D03*
X350595Y1059946D03*
X337642Y1056757D03*
X348744D03*
X343193Y1053568D03*
X341343Y1050379D03*
X348744D03*
X343193Y1059946D03*
X339492D03*
X341343Y1063135D03*
X348744D03*
X341343Y1069513D03*
X343193Y1072702D03*
X348744Y1069513D03*
X343193Y1079080D03*
X348744Y1075891D03*
X341343Y1082269D03*
X348744D03*
X341343Y1088647D03*
X348744D03*
Y1095025D03*
X343193Y1091836D03*
X348744Y1101403D03*
X341343D03*
X343193Y1098214D03*
X341343Y1107781D03*
X348744D03*
X343193Y1110970D03*
Y1117348D03*
X348744Y1114159D03*
Y1120537D03*
X341343D03*
Y1126915D03*
X348744D03*
Y1133293D03*
X343193Y1130103D03*
X341343Y1139670D03*
X343193Y1136481D03*
X348744Y1139670D03*
X343193Y1149237D03*
X348744Y1146048D03*
X341343D03*
X348744Y1152426D03*
X337642Y1158804D03*
X341343D03*
X348744D03*
X339492Y1155615D03*
X343193D03*
X346894D03*
X337642Y1165182D03*
X343193Y1161993D03*
X346894D03*
X348744Y1165182D03*
X339938Y1507295D03*
X344663D03*
X349387D03*
X347663Y1521453D03*
X342938D03*
X338214D03*
X338544Y1514243D03*
X343268D03*
X347993D03*
X348214Y1528853D03*
X343489D03*
X338765D03*
X342988Y1536063D03*
X339938Y1542641D03*
X344663D03*
X349387D03*
X338486Y1592380D03*
X342746D03*
X350546D03*
X336726Y1602380D03*
X344506D03*
X348786D03*
X350546Y1624292D03*
X342746D03*
X338486D03*
X348786Y1614292D03*
X344506D03*
X336726D03*
X347440Y1675383D03*
Y1679920D03*
Y1684454D03*
X339566Y1683857D03*
Y1679320D03*
X347440Y1694093D03*
Y1698627D03*
X339566Y1698030D03*
Y1693493D03*
Y1688391D03*
X347440Y1689556D03*
Y1703729D03*
Y1708266D03*
Y1712800D03*
X339566Y1716737D03*
Y1712203D03*
Y1707666D03*
Y1702564D03*
X347440Y1717903D03*
Y1722440D03*
Y1726974D03*
X339566Y1730911D03*
Y1726377D03*
Y1721840D03*
X354295Y1028056D03*
X361697D03*
Y1040812D03*
X356146Y1044001D03*
X354295Y1040812D03*
Y1034434D03*
X356146Y1031245D03*
Y1037623D03*
X361697Y1034434D03*
X354295Y1047190D03*
X361697D03*
X354295Y1053568D03*
Y1059946D03*
X363547Y1056757D03*
X356146D03*
Y1050379D03*
X361697Y1053568D03*
X365398Y1059946D03*
X361697D03*
X352445Y1056757D03*
X356146Y1063135D03*
X354295Y1072702D03*
Y1066324D03*
X356146Y1069513D03*
X361697Y1066324D03*
Y1072702D03*
X356146Y1075891D03*
X354295Y1079080D03*
X361697D03*
X354295Y1085458D03*
X356146Y1088647D03*
X361697Y1085458D03*
X356146Y1082269D03*
X354295Y1091836D03*
X361697D03*
X356146Y1095025D03*
X354295Y1104592D03*
Y1098214D03*
X361697Y1104592D03*
X356146Y1101403D03*
X361697Y1098214D03*
X356146Y1107781D03*
X354295Y1110970D03*
X361697D03*
Y1117348D03*
X356146Y1114159D03*
X354295Y1117348D03*
Y1123726D03*
X356146Y1126915D03*
Y1120537D03*
X361697Y1123726D03*
X356146Y1133293D03*
X361697Y1130103D03*
X354296Y1130105D03*
X354295Y1136481D03*
X356146Y1139670D03*
X361697Y1136481D03*
X354295Y1142859D03*
X361697D03*
Y1149237D03*
X356146Y1146048D03*
X354295Y1149237D03*
X363547Y1165182D03*
X356146D03*
X361697Y1161993D03*
X363547Y1158804D03*
X356146D03*
X359847D03*
X352445D03*
X365398Y1155615D03*
X356146Y1152426D03*
X361697Y1155615D03*
X354295D03*
Y1161993D03*
X354111Y1507295D03*
X358836D03*
X363560D03*
X361836Y1521453D03*
X357111D03*
X352387D03*
X352717Y1514243D03*
X357442D03*
X362166D03*
X362387Y1528853D03*
X357662D03*
X352938D03*
X352437Y1536063D03*
X354111Y1542641D03*
X358836D03*
X363560D03*
X362606Y1592380D03*
X354806D03*
X356566Y1602380D03*
X360846D03*
X354806Y1624292D03*
X360846Y1614292D03*
X356566D03*
X362606Y1624292D03*
X355314Y1683857D03*
Y1679320D03*
Y1688391D03*
Y1698030D03*
Y1693493D03*
Y1716737D03*
Y1712203D03*
Y1707666D03*
Y1702564D03*
Y1730911D03*
Y1726377D03*
Y1721840D03*
X380201Y1028056D03*
X367248Y1031245D03*
Y1044001D03*
X369099Y1034434D03*
Y1040812D03*
X374650Y1031245D03*
X380201Y1040812D03*
Y1034434D03*
X374650Y1037623D03*
Y1044001D03*
X367248Y1050379D03*
X380201Y1047190D03*
X369099Y1053568D03*
Y1059946D03*
X380201Y1053568D03*
X378351Y1056757D03*
X374650Y1050379D03*
Y1056757D03*
X380201Y1059946D03*
X376500D03*
X367248Y1063135D03*
Y1069513D03*
X374650Y1063135D03*
X369099Y1072702D03*
X380201D03*
X374650Y1069513D03*
X367248Y1088647D03*
Y1082269D03*
X374650Y1075891D03*
X369099Y1079080D03*
X380201Y1085458D03*
X374650Y1088647D03*
Y1082269D03*
X367248Y1101403D03*
X369099Y1091836D03*
X374650Y1095025D03*
X369099Y1098214D03*
X380201Y1104592D03*
Y1098214D03*
X374650Y1101403D03*
X367248Y1107781D03*
X374650D03*
X369099Y1110970D03*
Y1117348D03*
X380201D03*
X374650Y1114159D03*
X367248Y1120537D03*
Y1126915D03*
X374650Y1120537D03*
Y1126915D03*
X380201Y1130103D03*
X374650Y1133293D03*
X369099Y1130103D03*
X367248Y1139670D03*
Y1146048D03*
X380201Y1142859D03*
X374650Y1139670D03*
X369099Y1136481D03*
Y1149237D03*
X374650Y1146048D03*
X380201Y1155615D03*
X369099D03*
X372799D03*
X374650Y1152426D03*
X378351Y1158804D03*
X374650D03*
X376500Y1161993D03*
X377523Y1222274D03*
X372730Y1216782D03*
X367697Y1216624D03*
X377733Y1507295D03*
X368285D03*
X373009D03*
X376009Y1521453D03*
X380734D03*
X366560D03*
X371285D03*
X376339Y1514243D03*
X366890D03*
X371615D03*
X376560Y1528853D03*
X367111D03*
X371836D03*
X376059Y1536063D03*
X366610D03*
X377733Y1542641D03*
X368285D03*
X373009D03*
X374666Y1592380D03*
X366866D03*
X380696Y1602380D03*
X368626Y1602286D03*
X372906Y1602380D03*
X374666Y1624292D03*
X380696Y1614292D03*
X372906D03*
X368626D03*
X366866Y1624292D03*
X387603Y1028056D03*
X395004D03*
X393154Y1044001D03*
X385752Y1031245D03*
Y1037623D03*
Y1044001D03*
X395004Y1040812D03*
X387603Y1034434D03*
Y1040812D03*
X395004Y1034434D03*
X393154Y1031245D03*
Y1037623D03*
X395004Y1047190D03*
X387603D03*
Y1053568D03*
X391303Y1059946D03*
X395004Y1053568D03*
X385752Y1050379D03*
X393154Y1056757D03*
Y1050379D03*
X382051Y1063135D03*
Y1069513D03*
X393154Y1063135D03*
X395004Y1066324D03*
X387603D03*
X383902D03*
X391303Y1072702D03*
Y1066324D03*
X393154Y1069513D03*
X385752D03*
Y1063135D03*
X389453Y1069513D03*
Y1063135D03*
X382051Y1075891D03*
Y1088647D03*
Y1082269D03*
X393154Y1075891D03*
X387603Y1079080D03*
X383902D03*
X391303D03*
X395004D03*
X393154Y1082269D03*
X391303Y1085458D03*
X393154Y1088647D03*
X385752Y1075891D03*
X389453D03*
X382051Y1095025D03*
X383902Y1091836D03*
X393154Y1095025D03*
X391303Y1091836D03*
X395004D03*
X387603D03*
X391303Y1098214D03*
Y1104592D03*
X395004D03*
X387603D03*
X383902D03*
X382051Y1107781D03*
Y1114159D03*
X383902Y1110970D03*
X387603D03*
X393154Y1107781D03*
X391303Y1110970D03*
X395004D03*
X391303Y1117348D03*
X393154Y1114159D03*
X391304Y1130105D03*
X382051Y1126915D03*
Y1120537D03*
Y1133293D03*
X383902Y1123726D03*
X387603D03*
X393154Y1126915D03*
X391303Y1123726D03*
X395004D03*
X393154Y1120537D03*
Y1133293D03*
X382051Y1139670D03*
Y1146048D03*
X393154Y1139670D03*
X395004Y1136481D03*
X391303D03*
X383902D03*
X387603D03*
X391303Y1142859D03*
X393154Y1146048D03*
X395004Y1149237D03*
X383902D03*
X387603D03*
X389453Y1158804D03*
X391303Y1155615D03*
X395004D03*
X383902D03*
X387603D03*
Y1161993D03*
X382458Y1507295D03*
X387182D03*
X390203Y1521453D03*
X385458D03*
X385788Y1514243D03*
X381285Y1528853D03*
X386009D03*
X385508Y1536063D03*
X390839D03*
X382458Y1542641D03*
X387182D03*
X398705Y1028056D03*
X409795Y1028064D03*
X398705Y1034434D03*
X402406Y1040812D03*
X400555Y1031245D03*
Y1037623D03*
Y1044001D03*
X409795Y1034442D03*
Y1040820D03*
X402406Y1047190D03*
X409807D03*
X402406Y1053568D03*
X407957Y1056757D03*
X402406Y1059946D03*
X409807Y1053568D03*
X400555Y1056757D03*
Y1050379D03*
X407957D03*
X398705Y1066324D03*
X404256Y1063135D03*
X402406Y1072702D03*
X404256Y1069513D03*
X406107Y1066324D03*
X409807D03*
X402406D03*
X396855Y1069513D03*
Y1063135D03*
X407957Y1069513D03*
Y1063135D03*
X400555Y1069513D03*
Y1063135D03*
X398705Y1079080D03*
X404256Y1075891D03*
X406107Y1079080D03*
X409807D03*
X402406D03*
X404256Y1088647D03*
X402406Y1085458D03*
X404256Y1082269D03*
X396855Y1075891D03*
X407957D03*
X400555D03*
X398705Y1091836D03*
Y1104592D03*
X404256Y1095025D03*
X406107Y1091836D03*
X409807D03*
X402406D03*
Y1098214D03*
Y1104592D03*
X398705Y1110970D03*
X404256Y1107781D03*
X406107Y1110970D03*
X409807D03*
X402406D03*
X404256Y1114159D03*
X402406Y1117348D03*
X398705Y1123726D03*
X406107D03*
X409807D03*
X404256Y1120537D03*
X402406Y1123726D03*
X404256Y1126915D03*
Y1133293D03*
X402406Y1130103D03*
X398705Y1136481D03*
Y1149237D03*
X402406Y1142859D03*
X404256Y1139670D03*
X406107Y1136481D03*
X409807D03*
X402406D03*
X404256Y1146048D03*
X406107Y1149237D03*
X409807D03*
X398705Y1155615D03*
Y1161993D03*
X406107Y1155615D03*
X409807D03*
X402406D03*
X400555Y1158804D03*
X409807Y1161993D03*
X400555Y1165182D03*
X424598Y1040820D03*
X417197D03*
X413508Y1059946D03*
X417209Y1047190D03*
X424610D03*
Y1053568D03*
X422760Y1056757D03*
X424610Y1059946D03*
X417209Y1053568D03*
X415358Y1056757D03*
Y1050379D03*
X422760D03*
X413508Y1072702D03*
Y1066324D03*
X415358Y1063135D03*
X424610Y1072702D03*
Y1066324D03*
X420910D03*
X417209D03*
X415358Y1069513D03*
X419059Y1063135D03*
Y1069513D03*
X422760Y1063135D03*
X411658Y1069513D03*
Y1063135D03*
X422760Y1069513D03*
X413508Y1079080D03*
Y1085458D03*
X415358Y1075891D03*
X420910Y1079080D03*
X424610D03*
X417209D03*
X424610Y1085458D03*
X415358Y1088647D03*
Y1082269D03*
X419059Y1075891D03*
X422760D03*
X411658D03*
X413508Y1091836D03*
Y1098214D03*
Y1104592D03*
X415358Y1095025D03*
X420910Y1091836D03*
X424610D03*
X417209D03*
X420910Y1104592D03*
X424610D03*
Y1098214D03*
X417209Y1104592D03*
X415358Y1101403D03*
X413508Y1110970D03*
Y1117348D03*
X415358Y1107781D03*
X424610Y1110970D03*
X420910D03*
X417209D03*
X424610Y1117348D03*
X415358Y1114159D03*
Y1120537D03*
Y1126915D03*
X424610Y1123726D03*
X420910D03*
X417209D03*
X415358Y1133293D03*
X413508Y1123726D03*
Y1130103D03*
X424611Y1130105D03*
X413508Y1142859D03*
Y1136481D03*
X424610Y1142859D03*
Y1136481D03*
X420910D03*
X415358Y1139670D03*
X417209Y1136481D03*
X420910Y1149237D03*
X417209D03*
X415358Y1146048D03*
X413508Y1155615D03*
X411658Y1158804D03*
X424610Y1155615D03*
X420910D03*
X417209D03*
X422760Y1158804D03*
Y1165182D03*
X420910Y1161993D03*
X430162Y1056757D03*
Y1050379D03*
X432012Y1047190D03*
Y1053568D03*
X435713Y1059946D03*
X428311D03*
X432012D03*
X426461Y1063135D03*
X430162D03*
X426461Y1069513D03*
X433862Y1063135D03*
X435713Y1072702D03*
Y1066324D03*
X428311Y1072702D03*
Y1066324D03*
X432012Y1072702D03*
Y1066324D03*
X430162Y1075891D03*
X426461D03*
X430162Y1088647D03*
X426461D03*
Y1082269D03*
X433862Y1075891D03*
X435713Y1079080D03*
Y1085458D03*
X433862Y1088647D03*
X428311Y1079080D03*
X432012D03*
X426461Y1095025D03*
X430162Y1101403D03*
X426461D03*
X435713Y1091836D03*
Y1098214D03*
Y1104592D03*
X433862Y1101403D03*
X430162Y1107781D03*
X426461D03*
Y1114159D03*
X433862Y1107781D03*
X435713Y1110970D03*
Y1117348D03*
X426461Y1126915D03*
X430162Y1120537D03*
X426461D03*
X430162Y1133293D03*
X426461D03*
X435713Y1123726D03*
X433862Y1120537D03*
X435713Y1130103D03*
X433862Y1133293D03*
X426461Y1139670D03*
Y1146048D03*
X428311Y1149237D03*
X435713Y1136481D03*
Y1142859D03*
Y1149237D03*
X432012D03*
X430162Y1158804D03*
X435713Y1155615D03*
Y1161993D03*
X454204Y1040820D03*
X446790Y1047190D03*
Y1053568D03*
Y1059946D03*
X454192Y1047190D03*
X448641Y1056757D03*
X454192Y1053568D03*
X448641Y1050379D03*
X454192Y1059946D03*
X450491D03*
X446790Y1066324D03*
Y1072702D03*
X452341Y1063135D03*
X448641D03*
X454192Y1066324D03*
Y1072702D03*
X450491Y1066324D03*
Y1072702D03*
X446790Y1079080D03*
Y1085458D03*
X452341Y1075891D03*
X448641D03*
X452341Y1088647D03*
X448641D03*
X454192Y1079080D03*
X450491D03*
X446790Y1091836D03*
Y1098214D03*
Y1104592D03*
X452341Y1101403D03*
X448641D03*
X446790Y1110970D03*
Y1117348D03*
X452341Y1107781D03*
X448641D03*
X446790Y1123726D03*
Y1130103D03*
X448641Y1120537D03*
X452341D03*
Y1133293D03*
X448641D03*
X446790Y1136481D03*
Y1142859D03*
Y1149237D03*
X454192D03*
X450491D03*
X446790Y1155615D03*
Y1161993D03*
X454192Y1155615D03*
X447120Y1507512D03*
X452427Y1507295D03*
X450703Y1521453D03*
X451033Y1514243D03*
X449861Y1519195D03*
X451254Y1528853D03*
X450752Y1536063D03*
X441752Y1523810D03*
Y1528725D03*
X452427Y1542641D03*
X447224Y1542425D03*
X450139Y1592380D03*
Y1624292D03*
X469007Y1040820D03*
X461606D03*
X461593Y1047190D03*
Y1053568D03*
X456042Y1056757D03*
X457893Y1059946D03*
X456042Y1050379D03*
X468995Y1047190D03*
Y1053568D03*
Y1059946D03*
X463444Y1056757D03*
Y1050379D03*
X456042Y1063135D03*
Y1069513D03*
X457893Y1072702D03*
Y1066324D03*
X461593D03*
X467145Y1063135D03*
X468995Y1072702D03*
Y1066324D03*
X467145Y1069513D03*
X465294Y1066324D03*
X463444Y1063135D03*
Y1069513D03*
X459743Y1063135D03*
Y1069513D03*
X456042Y1075891D03*
X461593Y1079080D03*
X457893D03*
X456042Y1088647D03*
X457893Y1085458D03*
X456042Y1082269D03*
X467145Y1075891D03*
X468995Y1079080D03*
X465294D03*
X468995Y1085458D03*
X467145Y1088647D03*
Y1082269D03*
X463444Y1075891D03*
X459743D03*
X457893Y1091836D03*
X461593D03*
X456042Y1095025D03*
X457893Y1098214D03*
X456042Y1101403D03*
X457893Y1104592D03*
X461593D03*
X467145Y1095025D03*
X468995Y1091836D03*
X465294D03*
X468995Y1104592D03*
X465294D03*
X468995Y1098214D03*
X467145Y1101403D03*
X456042Y1107781D03*
X457893Y1110970D03*
X461593D03*
X457893Y1117348D03*
X456042Y1114159D03*
X468995Y1110970D03*
X465294D03*
X467145Y1107781D03*
Y1114159D03*
X468995Y1117348D03*
X456042Y1126915D03*
X461593Y1123726D03*
X457893D03*
X456042Y1120537D03*
Y1133293D03*
X468995Y1123726D03*
X467145Y1120537D03*
X465294Y1123726D03*
X467145Y1126915D03*
X468995Y1130103D03*
X467145Y1133293D03*
X457893Y1130104D03*
X456042Y1139670D03*
X461593Y1136481D03*
X457893D03*
Y1142859D03*
X456042Y1146048D03*
X461593Y1149237D03*
X468995Y1142859D03*
X467145Y1139670D03*
X468995Y1136481D03*
X465294D03*
X467145Y1146048D03*
X465294Y1149237D03*
X459743Y1158804D03*
Y1152426D03*
X465294Y1155615D03*
X457152Y1507295D03*
X461876D03*
X466600D03*
X469600Y1521453D03*
X464876D03*
X460152D03*
X455427D03*
X455757Y1514243D03*
X460482D03*
X465206D03*
X469931D03*
X470151Y1528853D03*
X465427D03*
X460703D03*
X455978D03*
X464926Y1536063D03*
X460202D03*
X455477D03*
X466600Y1542641D03*
X457152D03*
X461876D03*
X469999Y1592380D03*
X457939D03*
X462199D03*
X463959Y1602380D03*
X456179D03*
X468239D03*
X457939Y1624292D03*
X463959Y1614292D03*
X456179D03*
X468239D03*
X469999Y1624292D03*
X462199D03*
X480097Y1028056D03*
X478247Y1037623D03*
Y1044001D03*
X480097Y1034434D03*
X483798Y1040812D03*
X481948Y1031245D03*
X476400Y1040820D03*
X476397Y1047190D03*
Y1053568D03*
X470845Y1056757D03*
X478247D03*
X470845Y1050379D03*
X478247D03*
X483798Y1047190D03*
Y1053568D03*
X480097Y1059946D03*
X478247Y1063135D03*
X472696Y1066324D03*
X476397D03*
X478247Y1069513D03*
X483798Y1066324D03*
X480097Y1072702D03*
Y1066324D03*
X474546Y1063135D03*
Y1069513D03*
X481948Y1063135D03*
Y1069513D03*
X470845Y1063135D03*
Y1069513D03*
X478247Y1075891D03*
X476397Y1079080D03*
X472696D03*
X478247Y1088647D03*
Y1082269D03*
X483798Y1079080D03*
X480097D03*
Y1085458D03*
X474546Y1075891D03*
X481948D03*
X470845D03*
X480097Y1104592D03*
X483798D03*
X480097Y1098214D03*
X478247Y1095025D03*
X472696Y1091836D03*
X476397D03*
X480097D03*
X483798D03*
X472696Y1110970D03*
X476397D03*
X478247Y1107781D03*
Y1114159D03*
X483798Y1110970D03*
X480097D03*
Y1117348D03*
X476397Y1123726D03*
X472696D03*
X478247Y1120537D03*
Y1126915D03*
Y1133293D03*
X483798Y1123726D03*
X480097D03*
Y1130103D03*
X478247Y1139670D03*
X476397Y1136481D03*
X472696D03*
X476397Y1149237D03*
X472696D03*
X478247Y1146048D03*
X483798Y1136481D03*
X480097D03*
Y1142859D03*
X483798Y1149237D03*
X476397Y1155615D03*
X474546Y1152426D03*
X470845Y1158804D03*
X481948D03*
X471325Y1507295D03*
X476049D03*
X480774D03*
X483774Y1521453D03*
X479049D03*
X474325D03*
X474655Y1514243D03*
X479379D03*
X484104D03*
X484325Y1528853D03*
X479600D03*
X474876D03*
X479099Y1536063D03*
X476049Y1542641D03*
X471325D03*
X480774D03*
X482059Y1592380D03*
X474259D03*
X476019Y1602380D03*
X480299D03*
X482059Y1624292D03*
X476019Y1614292D03*
X474259Y1624292D03*
X480299Y1614292D03*
X494901Y1028056D03*
X487499D03*
X485649Y1044001D03*
X494901Y1034434D03*
X491200Y1040812D03*
X487499Y1034434D03*
X489349Y1031245D03*
X493050Y1037623D03*
X485649D03*
X493050Y1044001D03*
X496751Y1031245D03*
X498601Y1040812D03*
X491200Y1047190D03*
X493050Y1056757D03*
X491200Y1059946D03*
Y1053568D03*
X485649Y1056757D03*
X493050Y1050379D03*
X485649D03*
X498601Y1047190D03*
Y1053568D03*
X489349Y1063135D03*
X494901Y1066324D03*
X491200D03*
X487499D03*
X491200Y1072702D03*
X489349Y1069513D03*
X498601Y1066324D03*
X485649Y1063135D03*
Y1069513D03*
X496751Y1063135D03*
Y1069513D03*
X493050Y1063135D03*
Y1069513D03*
X489349Y1082269D03*
X498601Y1079080D03*
X494901D03*
X489349Y1075891D03*
X487499Y1079080D03*
X491200D03*
Y1085458D03*
X489349Y1088647D03*
X485649Y1075891D03*
X496751D03*
X493050D03*
X494901Y1091836D03*
X487499D03*
X491200D03*
X489349Y1095025D03*
X494901Y1104592D03*
X491200Y1098214D03*
Y1104592D03*
X487499D03*
X498601Y1091836D03*
Y1104592D03*
X496751Y1101403D03*
X491200Y1110970D03*
X489349Y1114159D03*
X491200Y1117348D03*
X498601Y1110970D03*
X494901D03*
X489349Y1107781D03*
X487499Y1110970D03*
X494901Y1123726D03*
X489349Y1126915D03*
X491200Y1123726D03*
X487499D03*
X489349Y1120537D03*
X491200Y1130103D03*
X489349Y1133293D03*
X498601Y1123726D03*
X494901Y1136481D03*
X489349Y1139670D03*
X491200Y1136481D03*
X487499D03*
X491200Y1142859D03*
X494901Y1149237D03*
X489349Y1146048D03*
X487499Y1149237D03*
X498601Y1136481D03*
Y1149237D03*
X487499Y1155615D03*
X485649Y1152426D03*
X493050Y1158804D03*
X498601Y1155615D03*
X496751Y1152426D03*
X485498Y1507295D03*
X490222D03*
X499671D03*
X494947D03*
X497947Y1521453D03*
X493222D03*
X488498D03*
X488828Y1514243D03*
X493553D03*
X498277D03*
X498498Y1528853D03*
X493773D03*
X489049D03*
X488548Y1536063D03*
X494947Y1542641D03*
X485498D03*
X490222D03*
X499671D03*
X498379Y1592380D03*
X486319D03*
X494119D03*
X488079Y1602380D03*
X492359D03*
X498379Y1624292D03*
X488079Y1614292D03*
X486319Y1624292D03*
X494119D03*
X492359Y1614292D03*
X497440Y1684454D03*
Y1679920D03*
Y1675383D03*
Y1698627D03*
Y1694093D03*
Y1689556D03*
Y1712800D03*
Y1708266D03*
Y1703729D03*
Y1726974D03*
Y1722440D03*
Y1717903D03*
X502302Y1028056D03*
X513405D03*
X507853Y1037623D03*
X500452D03*
X502302Y1034434D03*
X507853Y1044001D03*
X500452D03*
X507853Y1031245D03*
X513405Y1034434D03*
Y1040812D03*
X507853Y1056757D03*
Y1050379D03*
X500452Y1056757D03*
X504153D03*
X500452Y1050379D03*
X502302Y1059946D03*
X506003D03*
X513405Y1053568D03*
Y1059946D03*
X507853Y1063135D03*
X500452D03*
X507853Y1069513D03*
X500452D03*
X502302Y1072702D03*
X513405D03*
X507853Y1075891D03*
X500452D03*
X507853Y1088647D03*
X500452D03*
X502302Y1085458D03*
X507853Y1082269D03*
X500452D03*
X513405Y1079080D03*
X507853Y1095025D03*
X500452D03*
X502302Y1098214D03*
X507853Y1101403D03*
X502302Y1104592D03*
X513405Y1091836D03*
Y1098214D03*
X507853Y1107781D03*
X500452D03*
X507853Y1114159D03*
X502302Y1117348D03*
X500452Y1114159D03*
X513405Y1110970D03*
Y1117348D03*
X507853Y1120537D03*
X500452D03*
X507853Y1126915D03*
X500452D03*
X507853Y1133293D03*
X500452D03*
X502302Y1130103D03*
X513405Y1130104D03*
X507853Y1139670D03*
X500452D03*
X502302Y1142859D03*
X507853Y1146048D03*
X500452D03*
X513405Y1136481D03*
Y1149237D03*
X511554Y1165182D03*
X509704Y1155615D03*
X507853Y1152426D03*
X502302Y1155615D03*
X507853Y1158804D03*
X504153D03*
X513405Y1155615D03*
X504396Y1507295D03*
X509120D03*
X513844D03*
X512120Y1521453D03*
X507396D03*
X502671D03*
X503001Y1514243D03*
X507726D03*
X512450D03*
X512671Y1528853D03*
X507947D03*
X503222D03*
X512170Y1536063D03*
X502721D03*
X513844Y1542641D03*
X504396D03*
X509120D03*
X510439Y1592380D03*
X506179D03*
X512199Y1602380D03*
X500139D03*
X504419D03*
X512199Y1614292D03*
X500139D03*
X506179Y1624292D03*
X510439D03*
X504419Y1614292D03*
X505314Y1679320D03*
Y1683857D03*
X513188Y1684454D03*
Y1679920D03*
Y1675383D03*
X505314Y1688391D03*
Y1693493D03*
Y1698030D03*
X513188Y1698627D03*
Y1694093D03*
Y1689556D03*
X505314Y1707666D03*
Y1712203D03*
X513188Y1712800D03*
Y1708266D03*
Y1703729D03*
X505314Y1716737D03*
Y1702564D03*
Y1721840D03*
Y1726377D03*
Y1730911D03*
X513188Y1726974D03*
Y1722440D03*
Y1717903D03*
X520806Y1028056D03*
X528208D03*
X526357Y1037623D03*
Y1044001D03*
Y1031245D03*
X515255D03*
X520806Y1040812D03*
Y1034434D03*
X515255Y1044001D03*
X528208Y1040812D03*
Y1034434D03*
X520806Y1047190D03*
X526357Y1050379D03*
Y1056757D03*
X520806Y1053568D03*
X515255Y1050379D03*
X518956Y1056757D03*
X520806Y1059946D03*
X517105D03*
X528208Y1047190D03*
Y1053568D03*
Y1059946D03*
X526357Y1063135D03*
X515255D03*
X526357Y1069513D03*
X520806Y1066324D03*
Y1072702D03*
X515255Y1069513D03*
X528208Y1066324D03*
Y1072702D03*
X526357Y1075891D03*
X520806Y1079080D03*
X526357Y1088647D03*
Y1082269D03*
X520806Y1085458D03*
X515255Y1088647D03*
Y1082269D03*
X528208Y1079080D03*
Y1085458D03*
X526357Y1095025D03*
X520806Y1091836D03*
X526357Y1101403D03*
X520806Y1104592D03*
Y1098214D03*
X515255Y1101403D03*
X528208Y1091836D03*
Y1104592D03*
Y1098214D03*
X526357Y1107781D03*
X520806Y1110970D03*
X515255Y1107781D03*
X526357Y1114159D03*
X520806Y1117348D03*
X528208Y1110970D03*
Y1117348D03*
Y1130104D03*
X526357Y1120537D03*
Y1126915D03*
X520806Y1123726D03*
X515255Y1120537D03*
Y1126915D03*
X526357Y1133293D03*
X520806Y1130103D03*
X528208Y1123726D03*
X515255Y1139670D03*
X520806Y1142859D03*
X526357Y1139670D03*
X520806Y1136481D03*
X526357Y1146048D03*
X520806Y1149237D03*
X515255Y1146048D03*
X528208Y1136481D03*
Y1142859D03*
Y1149237D03*
X526357Y1152426D03*
Y1158804D03*
X520806Y1155615D03*
X517105D03*
X522657Y1158804D03*
X515255D03*
X517105Y1161993D03*
X528208Y1155615D03*
X518569Y1507295D03*
X523293D03*
X526314Y1521453D03*
X521569D03*
X516845D03*
X521899Y1514243D03*
X522120Y1528853D03*
X517396D03*
X521619Y1536063D03*
X526950D03*
X523293Y1542641D03*
X518569D03*
X518239Y1592380D03*
X522499D03*
X524259Y1602380D03*
X528539D03*
X516479D03*
X524259Y1614292D03*
X518239Y1624292D03*
X522499D03*
X528539Y1614292D03*
X516479D03*
X521062Y1679320D03*
Y1683857D03*
X528936Y1684454D03*
Y1679920D03*
Y1675383D03*
X521062Y1688391D03*
Y1693493D03*
Y1698030D03*
X528936Y1698627D03*
Y1694093D03*
Y1689556D03*
X521062Y1716737D03*
Y1702564D03*
Y1707666D03*
Y1712203D03*
X528936Y1712800D03*
Y1708266D03*
Y1703729D03*
X521062Y1721840D03*
Y1726377D03*
Y1730911D03*
X528936Y1726974D03*
Y1722440D03*
Y1717903D03*
X539310Y1028056D03*
X541160Y1031245D03*
X533759D03*
X539310Y1034434D03*
Y1040812D03*
X533759Y1037623D03*
X541160Y1044001D03*
X533759D03*
X543011Y1059946D03*
X530058Y1056757D03*
X541160Y1050379D03*
X539310Y1053568D03*
X533759Y1050379D03*
Y1056757D03*
X539310Y1059946D03*
X531908D03*
X541160Y1063135D03*
X533759D03*
X541160Y1069513D03*
X539310Y1072702D03*
X533759Y1069513D03*
Y1075891D03*
X539310Y1079080D03*
X541160Y1088647D03*
X533759D03*
X541160Y1082269D03*
X533759D03*
X539310Y1091836D03*
X533759Y1095025D03*
X539310Y1098214D03*
X541160Y1101403D03*
X533759D03*
X541160Y1107781D03*
X533759D03*
X539310Y1110970D03*
Y1117348D03*
X533759Y1114159D03*
X541160Y1120537D03*
X533759D03*
X541160Y1126915D03*
X533759D03*
X539310Y1130103D03*
X533759Y1133293D03*
X541160Y1139670D03*
X539310Y1136481D03*
X533759Y1139670D03*
Y1146048D03*
X541160D03*
X539310Y1149237D03*
X543011Y1155615D03*
X533759Y1158804D03*
X530058D03*
X539310Y1155615D03*
X535609D03*
X533759Y1152426D03*
X543011Y1161993D03*
X542359Y1592380D03*
X530299D03*
X534559D03*
X536319Y1602380D03*
X540599D03*
X542359Y1624292D03*
X536319Y1614292D03*
X530299Y1624292D03*
X534559D03*
X540599Y1614292D03*
X536810Y1679320D03*
Y1683857D03*
X544684Y1684454D03*
Y1679920D03*
Y1675383D03*
X536810Y1688391D03*
Y1693493D03*
Y1698030D03*
X544684Y1698627D03*
Y1694093D03*
Y1689556D03*
X536810Y1716737D03*
Y1702564D03*
Y1707666D03*
Y1712203D03*
X544684Y1712800D03*
Y1708266D03*
Y1703729D03*
X536810Y1721840D03*
Y1726377D03*
Y1730911D03*
X544684Y1726974D03*
Y1722440D03*
Y1717903D03*
X554113Y1028056D03*
X546712D03*
Y1040812D03*
Y1034434D03*
X552263Y1031245D03*
X554113Y1040812D03*
X552263Y1037623D03*
X554113Y1034434D03*
X552263Y1044001D03*
X559664Y1031245D03*
Y1037623D03*
Y1044001D03*
X546712Y1047190D03*
X554113D03*
X544861Y1056757D03*
X546712Y1053568D03*
Y1059946D03*
X552263Y1056757D03*
X555964D03*
X554113Y1053568D03*
X552263Y1050379D03*
X554113Y1059946D03*
X557814D03*
X559664Y1050379D03*
Y1056757D03*
X552263Y1063135D03*
X546712Y1072702D03*
Y1066324D03*
X552263Y1069513D03*
X554113Y1066324D03*
Y1072702D03*
X559664Y1063135D03*
Y1069513D03*
X552263Y1075891D03*
X546712Y1079080D03*
X554113D03*
X546712Y1085458D03*
X552263Y1088647D03*
X554113Y1085458D03*
X552263Y1082269D03*
X559664Y1075891D03*
Y1088647D03*
Y1082269D03*
X546712Y1091836D03*
X554113D03*
X552263Y1095025D03*
Y1101403D03*
X554113Y1098214D03*
X546712Y1104592D03*
Y1098214D03*
X554113Y1104592D03*
X559664Y1095025D03*
Y1101403D03*
X552263Y1107781D03*
X554113Y1110970D03*
X546712D03*
X554113Y1117348D03*
X552263Y1114159D03*
X546712Y1117348D03*
X559664Y1107781D03*
Y1114159D03*
X546712Y1123726D03*
X554113D03*
X552263Y1120537D03*
Y1126915D03*
Y1133293D03*
X554113Y1130103D03*
X559664Y1120537D03*
Y1126915D03*
Y1133293D03*
X546712Y1130104D03*
X552263Y1139670D03*
X554113Y1136481D03*
X546712D03*
X554113Y1142859D03*
X546712D03*
Y1149237D03*
X552263Y1146048D03*
X554113Y1149237D03*
X559664Y1139670D03*
Y1146048D03*
X555964Y1165182D03*
X554113Y1155615D03*
X552263Y1152426D03*
X555964Y1158804D03*
X552263D03*
X548562D03*
X546712Y1155615D03*
X554113Y1161993D03*
X559664Y1152426D03*
Y1158804D03*
X558679Y1592380D03*
X546619D03*
X554419D03*
X548379Y1602380D03*
X552659D03*
X558679Y1624292D03*
X548379Y1614292D03*
X546619Y1624292D03*
X554419D03*
X552659Y1614292D03*
X552558Y1679320D03*
Y1683857D03*
Y1688391D03*
Y1693493D03*
Y1698030D03*
Y1716737D03*
Y1702564D03*
Y1707666D03*
Y1712203D03*
Y1721840D03*
Y1726377D03*
Y1730911D03*
X565216Y1028056D03*
X572617D03*
X567066Y1031245D03*
X565215Y1034434D03*
Y1040812D03*
X572617Y1034434D03*
Y1040812D03*
X567066Y1044001D03*
X565215Y1059946D03*
X572617Y1047190D03*
X567066Y1050379D03*
X572617Y1053568D03*
X570767Y1056757D03*
X565215Y1053568D03*
X572617Y1059946D03*
X568916D03*
X567066Y1063135D03*
X572617Y1066324D03*
Y1072702D03*
X567066Y1069513D03*
X565215Y1072702D03*
Y1079080D03*
X572617D03*
X567066Y1088647D03*
X572617Y1085458D03*
X567066Y1082269D03*
X572617Y1091836D03*
X565215D03*
X572617Y1104592D03*
Y1098214D03*
X567066Y1101403D03*
X565215Y1098214D03*
X567066Y1107781D03*
X572617Y1110970D03*
X565215D03*
X572617Y1117348D03*
X565215D03*
X572617Y1123726D03*
X567066Y1120537D03*
Y1126915D03*
X572617Y1130103D03*
X565215D03*
X572617Y1136481D03*
X565215Y1149237D03*
X572617D03*
X567066Y1146048D03*
X572617Y1142859D03*
X567066Y1139670D03*
X565215Y1136481D03*
X574467Y1158804D03*
X565215Y1155615D03*
X568916D03*
X572617D03*
X561515D03*
X565215Y1161993D03*
X569814Y1523810D03*
Y1528725D03*
X570739Y1592380D03*
X566479D03*
X572499Y1602380D03*
X560439D03*
X564719D03*
X572499Y1614292D03*
X570739Y1624292D03*
X560439Y1614292D03*
X566479Y1624292D03*
X564719Y1614292D03*
X572243Y1683857D03*
X564369Y1684454D03*
Y1679920D03*
Y1675383D03*
X572243Y1679320D03*
X564369Y1694093D03*
Y1689556D03*
X572243Y1688391D03*
Y1693493D03*
Y1698030D03*
X564369Y1698627D03*
X572243Y1702564D03*
Y1707666D03*
Y1712203D03*
X564369Y1712800D03*
Y1708266D03*
Y1703729D03*
X572243Y1716737D03*
Y1726377D03*
Y1730911D03*
X564369Y1726974D03*
Y1722440D03*
Y1717903D03*
X572243Y1721840D03*
X577728Y906182D03*
Y912560D03*
Y918938D03*
Y925316D03*
Y931694D03*
Y938072D03*
Y944450D03*
Y950828D03*
Y957206D03*
Y963584D03*
Y969962D03*
Y976340D03*
Y982718D03*
Y989096D03*
Y995474D03*
Y1008230D03*
Y1001852D03*
X578909Y1030198D03*
Y1036576D03*
Y1042954D03*
Y1049332D03*
Y1055710D03*
Y1062088D03*
Y1074844D03*
Y1068466D03*
Y1087600D03*
Y1081222D03*
Y1093978D03*
Y1100356D03*
Y1106734D03*
Y1113112D03*
Y1119490D03*
Y1125868D03*
Y1132246D03*
Y1138623D03*
Y1145001D03*
Y1151379D03*
X578168Y1158804D03*
X575182Y1507514D03*
X580489Y1507295D03*
X585214D03*
X588214Y1521453D03*
X583489D03*
X578765D03*
X579095Y1514243D03*
X583819D03*
X588544D03*
X577923Y1519195D03*
X588765Y1528853D03*
X584040D03*
X579316D03*
X588264Y1536063D03*
X583539D03*
X578814D03*
X585214Y1542641D03*
X580489D03*
X575286Y1542425D03*
X578539Y1592380D03*
X582799D03*
X584559Y1602380D03*
X588839D03*
X576779D03*
X584559Y1614292D03*
X582799Y1624292D03*
X578539D03*
X588839Y1614292D03*
X576779D03*
X587991Y1679320D03*
Y1683857D03*
X580117Y1684454D03*
Y1679920D03*
Y1675383D03*
X587991Y1688391D03*
Y1693493D03*
Y1698030D03*
X580117Y1698627D03*
Y1694093D03*
Y1689556D03*
X587991Y1716737D03*
Y1702564D03*
Y1707666D03*
Y1712203D03*
X580117Y1712800D03*
Y1708266D03*
Y1703729D03*
X587991Y1721840D03*
Y1726377D03*
Y1730911D03*
X580117Y1726974D03*
Y1722440D03*
Y1717903D03*
X589938Y1507295D03*
X594662D03*
X599387D03*
X604111D03*
X602387Y1521453D03*
X597662D03*
X592938D03*
X593268Y1514243D03*
X597993D03*
X602717D03*
X602938Y1528853D03*
X598213D03*
X593489D03*
X592988Y1536063D03*
X589938Y1542641D03*
X604111D03*
X599387D03*
X594662D03*
X602659Y1592380D03*
X590599D03*
X594859D03*
X596619Y1602380D03*
X600899D03*
X602659Y1624292D03*
X596619Y1614292D03*
X594859Y1624292D03*
X590599D03*
X600899Y1614292D03*
X603739Y1679320D03*
Y1683857D03*
X595865Y1684454D03*
Y1679920D03*
Y1675383D03*
X603739Y1688391D03*
Y1693493D03*
Y1698030D03*
X595865Y1698627D03*
Y1694093D03*
Y1689556D03*
X603739Y1716737D03*
Y1702564D03*
Y1707666D03*
Y1712203D03*
X595865Y1712800D03*
Y1708266D03*
Y1703729D03*
X603739Y1721840D03*
Y1726377D03*
Y1730911D03*
X595865Y1726974D03*
Y1722440D03*
Y1717903D03*
X608836Y1507295D03*
X613560D03*
X618284D03*
X616560Y1521453D03*
X611836D03*
X607111D03*
X607441Y1514243D03*
X612166D03*
X616890D03*
X617111Y1528853D03*
X612387D03*
X607662D03*
X607161Y1536063D03*
X616610D03*
X613560Y1542641D03*
X618284D03*
X608836D03*
X618979Y1592380D03*
X614719D03*
X606919D03*
X608679Y1602380D03*
X612959D03*
X618979Y1624292D03*
X608679Y1614292D03*
X606919Y1624292D03*
X614719D03*
X612959Y1614292D03*
X611613Y1684454D03*
Y1679920D03*
Y1675383D03*
Y1698627D03*
Y1694093D03*
Y1689556D03*
Y1712800D03*
Y1708266D03*
Y1703729D03*
Y1726974D03*
Y1722440D03*
Y1717903D03*
X623009Y1507295D03*
X627733D03*
X632458D03*
X630733Y1521453D03*
X626009D03*
X621284D03*
X621615Y1514243D03*
X626339D03*
X631063D03*
X631284Y1528853D03*
X626560D03*
X621835D03*
X630783Y1536063D03*
X632458Y1542641D03*
X627733D03*
X623009D03*
X631039Y1592380D03*
X626779D03*
X632799Y1602286D03*
X620739Y1602380D03*
X625019D03*
X631039Y1624292D03*
X632799Y1614292D03*
X626779Y1624292D03*
X620739Y1614292D03*
X625019D03*
X619487Y1679320D03*
Y1683857D03*
Y1688391D03*
Y1693493D03*
Y1698030D03*
Y1716737D03*
Y1702564D03*
Y1707666D03*
Y1712203D03*
Y1721840D03*
Y1726377D03*
Y1730911D03*
X637182Y1507295D03*
X641906D03*
X646631D03*
X644907Y1521453D03*
X640182D03*
X635458D03*
X635788Y1514243D03*
X640512D03*
X645458Y1528853D03*
X640733D03*
X636009D03*
X640232Y1536063D03*
X646631Y1542641D03*
X641906D03*
X637182D03*
X638839Y1592380D03*
X644869Y1602380D03*
X637079D03*
X644869Y1614292D03*
X638839Y1624292D03*
X637079Y1614292D03*
X651355Y1507295D03*
X654376Y1521453D03*
X649631D03*
X649961Y1514243D03*
X650182Y1528853D03*
X649681Y1536063D03*
X655012D03*
X651355Y1542641D03*
X1185452Y1556810D03*
Y1561725D03*
X1190820Y1540512D03*
X1194733Y1547243D03*
X1196127Y1540295D03*
X1199457Y1547243D03*
X1193561Y1552195D03*
X1199127Y1554453D03*
X1194403D03*
X1199678Y1561853D03*
X1194954D03*
X1199177Y1569063D03*
X1196127Y1575641D03*
X1194452Y1569063D03*
X1190924Y1575425D03*
X1193839Y1625380D03*
X1199879Y1635380D03*
Y1647292D03*
X1193839Y1657292D03*
X1200852Y1540295D03*
X1204182Y1547243D03*
X1205576Y1540295D03*
X1208906Y1547243D03*
X1210300Y1540295D03*
X1213631Y1547243D03*
X1215025Y1540295D03*
X1213300Y1554453D03*
X1208576D03*
X1203852D03*
X1213851Y1561853D03*
X1209127D03*
X1204403D03*
X1210300Y1575641D03*
X1208626Y1569063D03*
X1203902D03*
X1200852Y1575641D03*
X1205576D03*
X1215025D03*
X1205899Y1625380D03*
X1201639D03*
X1213699D03*
X1207659Y1635380D03*
X1211939D03*
X1207659Y1647292D03*
X1211939D03*
X1201639Y1657292D03*
X1205899D03*
X1213699D03*
X1218355Y1547243D03*
X1219749Y1540295D03*
X1223079Y1547243D03*
X1227804D03*
X1229198Y1540295D03*
X1224474D03*
X1227474Y1554453D03*
X1222749D03*
X1218025D03*
X1228025Y1561853D03*
X1223300D03*
X1218576D03*
X1222799Y1569063D03*
X1219749Y1575641D03*
X1224474D03*
X1229198D03*
X1217959Y1625380D03*
X1225759D03*
X1230019D03*
X1223999Y1635380D03*
X1219719D03*
X1223999Y1647292D03*
X1219719D03*
X1217959Y1657292D03*
X1230019D03*
X1225759D03*
X1232528Y1547243D03*
X1233922Y1540295D03*
X1237253Y1547243D03*
X1241977D03*
X1243371Y1540295D03*
X1238647D03*
X1241647Y1554453D03*
X1236922D03*
X1232198D03*
X1242198Y1561853D03*
X1237473D03*
X1232749D03*
X1238647Y1575641D03*
X1232248Y1569063D03*
X1233922Y1575641D03*
X1243371D03*
X1237819Y1625380D03*
X1242079D03*
X1231779Y1635380D03*
X1236059D03*
X1243839D03*
X1236059Y1647292D03*
X1231779D03*
X1243839D03*
X1237819Y1657292D03*
X1242079D03*
X1241140Y1684454D03*
Y1679920D03*
Y1675383D03*
Y1698627D03*
Y1694093D03*
Y1689556D03*
Y1712800D03*
Y1708266D03*
Y1703729D03*
Y1726974D03*
Y1722440D03*
Y1717903D03*
X1246701Y1547243D03*
X1248096Y1540295D03*
X1251426Y1547243D03*
X1252820Y1540295D03*
X1256150Y1547243D03*
X1257544Y1540295D03*
X1255820Y1554453D03*
X1251096D03*
X1246371D03*
X1256371Y1561853D03*
X1251647D03*
X1246922D03*
X1257544Y1575641D03*
X1255870Y1569063D03*
X1246421D03*
X1248096Y1575641D03*
X1252820D03*
X1249879Y1625380D03*
X1254139D03*
X1248119Y1635380D03*
X1255899D03*
X1260179D03*
X1248119Y1647292D03*
X1255899D03*
X1260179D03*
X1254139Y1657292D03*
X1249879D03*
X1249014Y1679320D03*
Y1683857D03*
X1256888Y1684454D03*
Y1679920D03*
Y1675383D03*
X1249014Y1688391D03*
Y1693493D03*
Y1698030D03*
X1256888Y1698627D03*
Y1694093D03*
Y1689556D03*
Y1703729D03*
X1249014Y1716737D03*
Y1702564D03*
Y1707666D03*
Y1712203D03*
X1256888Y1712800D03*
Y1708266D03*
X1249014Y1721840D03*
Y1726377D03*
Y1730911D03*
X1256888Y1726974D03*
Y1722440D03*
Y1717903D03*
X1262269Y1540295D03*
X1265599Y1547243D03*
X1266993Y1540295D03*
X1270014Y1554453D03*
X1265269D03*
X1260545D03*
X1265820Y1561853D03*
X1261096D03*
X1270650Y1569063D03*
X1266993Y1575641D03*
X1265319Y1569063D03*
X1262269Y1575641D03*
X1266199Y1625380D03*
X1261939D03*
X1273999D03*
X1267959Y1635380D03*
X1272239D03*
X1267959Y1647292D03*
X1272239D03*
X1266199Y1657292D03*
X1261939D03*
X1273999D03*
X1264762Y1679320D03*
Y1683857D03*
X1272636Y1684454D03*
Y1679920D03*
Y1675383D03*
X1264762Y1688391D03*
Y1693493D03*
Y1698030D03*
X1272636Y1698627D03*
Y1694093D03*
Y1689556D03*
X1264762Y1716737D03*
Y1702564D03*
Y1707666D03*
Y1712203D03*
X1272636Y1712800D03*
Y1708266D03*
Y1703729D03*
X1264762Y1721840D03*
Y1726377D03*
Y1730911D03*
X1272636Y1726974D03*
Y1722440D03*
Y1717903D03*
X1286028Y1028055D03*
Y1034433D03*
Y1040811D03*
Y1047189D03*
Y1053567D03*
X1287878Y1056756D03*
X1289729Y1059945D03*
X1286028D03*
Y1066323D03*
Y1072701D03*
Y1079079D03*
Y1085457D03*
Y1091835D03*
Y1098213D03*
Y1104591D03*
Y1110969D03*
Y1117347D03*
Y1123725D03*
Y1130102D03*
Y1136480D03*
Y1142858D03*
Y1149236D03*
X1289729Y1155614D03*
X1286028D03*
X1284178Y1158803D03*
X1287878Y1165181D03*
X1278259Y1625380D03*
X1286059D03*
X1280019Y1635380D03*
X1284299D03*
X1280019Y1647292D03*
X1284299D03*
X1278259Y1657292D03*
X1286059D03*
X1280510Y1679320D03*
Y1683857D03*
X1288384Y1684454D03*
Y1679920D03*
Y1675383D03*
X1280510Y1688391D03*
Y1693493D03*
Y1698030D03*
X1288384Y1698627D03*
Y1694093D03*
Y1689556D03*
X1280510Y1716737D03*
Y1702564D03*
Y1707666D03*
Y1712203D03*
X1288384Y1712800D03*
Y1708266D03*
Y1703729D03*
X1280510Y1721840D03*
Y1726377D03*
Y1730911D03*
X1288384Y1726974D03*
Y1722440D03*
Y1717903D03*
X1304532Y1028055D03*
X1293430Y1034433D03*
Y1040811D03*
X1298981Y1044000D03*
Y1037622D03*
X1304532Y1034433D03*
Y1040811D03*
X1298981Y1031244D03*
X1291579D03*
Y1044000D03*
X1304532Y1047189D03*
X1291579Y1050378D03*
X1293430Y1053567D03*
Y1059945D03*
X1304532Y1053567D03*
X1298981Y1050378D03*
X1302681Y1056756D03*
X1298981D03*
X1300831Y1059945D03*
X1304532D03*
X1298981Y1063134D03*
X1291579D03*
Y1069512D03*
X1293430Y1072701D03*
X1304532D03*
Y1066323D03*
X1298981Y1069512D03*
Y1075890D03*
X1293430Y1079079D03*
X1304532D03*
Y1085457D03*
X1298981Y1088646D03*
X1291579Y1082268D03*
X1298981D03*
X1291579Y1088646D03*
X1293430Y1091835D03*
X1304532D03*
X1298981Y1095024D03*
X1293430Y1098213D03*
X1298981Y1101402D03*
X1304532Y1098213D03*
Y1104591D03*
X1291579Y1101402D03*
X1298981Y1107780D03*
X1291579D03*
X1293430Y1110969D03*
X1304532D03*
X1293430Y1117347D03*
X1298981Y1114158D03*
X1304532Y1117347D03*
X1291579Y1120536D03*
X1298981D03*
X1304532Y1123725D03*
X1291579Y1126914D03*
X1298981D03*
X1304532Y1130102D03*
X1298981Y1133292D03*
X1293430Y1130102D03*
X1304532Y1136480D03*
X1298981Y1139669D03*
X1291579D03*
X1293430Y1136480D03*
X1304532Y1142858D03*
X1291579Y1146047D03*
X1293430Y1149236D03*
X1298981Y1146047D03*
X1304532Y1149236D03*
X1293430Y1155614D03*
X1304532D03*
X1298981Y1152425D03*
X1297130Y1155614D03*
X1302681Y1158803D03*
X1298981D03*
X1304532Y1161992D03*
X1297130D03*
X1298119Y1625380D03*
X1290319D03*
X1302379D03*
X1292079Y1635380D03*
X1296359D03*
X1304139D03*
X1296359Y1647292D03*
X1292079D03*
X1304139D03*
X1298119Y1657292D03*
X1290319D03*
X1302379D03*
X1296258Y1679320D03*
Y1683857D03*
Y1688391D03*
Y1693493D03*
Y1698030D03*
Y1716737D03*
Y1702564D03*
Y1707666D03*
Y1712203D03*
Y1721840D03*
Y1726377D03*
Y1730911D03*
X1311933Y1028055D03*
X1306382Y1044000D03*
Y1037622D03*
Y1031244D03*
X1319335Y1034433D03*
X1311933Y1040811D03*
X1319335D03*
X1317485Y1031244D03*
Y1044000D03*
X1311933Y1034433D03*
X1306382Y1050378D03*
Y1056756D03*
X1311933Y1047189D03*
X1313784Y1056756D03*
X1311933Y1059945D03*
X1315634D03*
X1319335D03*
X1317485Y1050378D03*
X1319335Y1053567D03*
X1311933D03*
X1306382Y1063134D03*
Y1069512D03*
X1317485Y1063134D03*
X1319335Y1072701D03*
X1317485Y1069512D03*
X1311933Y1066323D03*
Y1072701D03*
X1306382Y1075890D03*
Y1088646D03*
Y1082268D03*
X1319335Y1079079D03*
X1311933D03*
Y1085457D03*
X1317485Y1088646D03*
Y1082268D03*
X1306382Y1095024D03*
Y1101402D03*
X1319335Y1091835D03*
X1311933D03*
Y1098213D03*
X1319335D03*
X1317485Y1101402D03*
X1311933Y1104591D03*
X1306382Y1107780D03*
Y1114158D03*
X1317485Y1107780D03*
X1319335Y1110969D03*
X1311933D03*
Y1117347D03*
X1319335D03*
X1306382Y1120536D03*
Y1126914D03*
Y1133292D03*
X1317485Y1120536D03*
X1311933Y1123725D03*
X1317485Y1126914D03*
X1319335Y1130102D03*
X1311933Y1130103D03*
X1306382Y1139669D03*
Y1146047D03*
X1319335Y1136480D03*
X1317485Y1139669D03*
X1311933Y1136480D03*
Y1142858D03*
X1317485Y1146047D03*
X1319335Y1149236D03*
X1311933D03*
X1317485Y1158803D03*
X1313784D03*
X1319335Y1161992D03*
X1311933D03*
X1306382Y1165181D03*
X1313784D03*
X1306382Y1152425D03*
Y1158803D03*
X1319335Y1155614D03*
X1315634D03*
X1311933D03*
X1310083Y1158803D03*
X1318882Y1540514D03*
X1313514Y1556810D03*
Y1561725D03*
X1318986Y1575425D03*
X1310179Y1625380D03*
X1314439D03*
X1308419Y1635380D03*
X1316199D03*
X1308419Y1647292D03*
X1316199D03*
X1310179Y1657292D03*
X1314439D03*
X1315943Y1679320D03*
Y1683857D03*
X1308069Y1684454D03*
Y1679920D03*
Y1675383D03*
X1315943Y1688391D03*
Y1693493D03*
Y1698030D03*
X1308069Y1698627D03*
Y1694093D03*
Y1689556D03*
X1315943Y1716737D03*
Y1702564D03*
Y1707666D03*
Y1712203D03*
X1308069Y1712800D03*
Y1708266D03*
Y1703729D03*
X1315943Y1721840D03*
Y1726377D03*
Y1730911D03*
X1308069Y1726974D03*
Y1722440D03*
Y1717903D03*
X1330437Y1028055D03*
X1324886Y1031244D03*
X1332288D03*
X1324886Y1044000D03*
Y1037622D03*
X1332288Y1044000D03*
X1330437Y1034433D03*
X1332288Y1037622D03*
X1330437Y1040811D03*
Y1047189D03*
X1324886Y1050378D03*
Y1056756D03*
X1332288Y1050378D03*
X1330437Y1053567D03*
X1328587Y1056756D03*
X1332288D03*
X1326737Y1059945D03*
X1330437D03*
X1332288Y1063134D03*
X1324886D03*
Y1069512D03*
X1330437Y1066323D03*
X1332288Y1069512D03*
X1330437Y1072701D03*
X1324886Y1075890D03*
X1332288D03*
X1330437Y1079079D03*
X1324886Y1088646D03*
X1330437Y1085457D03*
X1332288Y1088646D03*
X1324886Y1082268D03*
X1332288D03*
X1330437Y1091835D03*
X1324886Y1095024D03*
X1332288D03*
X1324886Y1101402D03*
X1330437Y1098213D03*
X1332288Y1101402D03*
X1330437Y1104591D03*
X1324886Y1107780D03*
X1332288D03*
X1330437Y1110969D03*
X1324886Y1114158D03*
X1332288D03*
X1330437Y1117347D03*
X1324886Y1120536D03*
X1332288D03*
X1330437Y1123725D03*
X1324886Y1126914D03*
X1332288D03*
X1324886Y1133292D03*
X1332288D03*
X1330439Y1130102D03*
X1324886Y1139669D03*
X1330437Y1136480D03*
X1332288Y1139669D03*
X1330437Y1142858D03*
X1332288Y1146047D03*
X1330437Y1149236D03*
X1324886Y1146047D03*
X1332288Y1165181D03*
X1323036Y1155614D03*
Y1161992D03*
X1332288Y1152425D03*
X1330437Y1155614D03*
X1324886Y1152425D03*
X1332288Y1158803D03*
X1328587D03*
X1324886D03*
X1330437Y1161992D03*
X1324886Y1165181D03*
X1322795Y1547243D03*
X1324189Y1540295D03*
X1327519Y1547243D03*
X1328914Y1540295D03*
X1332244Y1547243D03*
X1333638Y1540295D03*
X1321623Y1552195D03*
X1331914Y1554453D03*
X1327189D03*
X1322465D03*
X1332465Y1561853D03*
X1327740D03*
X1323016D03*
X1333638Y1575641D03*
X1331964Y1569063D03*
X1328914Y1575641D03*
X1327239Y1569063D03*
X1324189Y1575641D03*
X1322514Y1569063D03*
X1326499Y1625380D03*
X1322239D03*
X1334299D03*
X1320479Y1635380D03*
X1328259D03*
X1332539D03*
X1328259Y1647292D03*
X1320479D03*
X1332539D03*
X1322239Y1657292D03*
X1326499D03*
X1334299D03*
X1331691Y1679320D03*
Y1683857D03*
X1323817Y1684454D03*
Y1679920D03*
Y1675383D03*
X1331691Y1688391D03*
Y1693493D03*
Y1698030D03*
X1323817Y1698627D03*
Y1694093D03*
Y1689556D03*
X1331691Y1716737D03*
Y1702564D03*
Y1707666D03*
Y1712203D03*
X1323817Y1712800D03*
Y1708266D03*
Y1703729D03*
X1331691Y1721840D03*
Y1726377D03*
Y1730911D03*
X1323817Y1726974D03*
Y1722440D03*
Y1717903D03*
X1337839Y1028055D03*
Y1040811D03*
Y1034433D03*
X1343390Y1031244D03*
Y1044000D03*
X1345241Y1040811D03*
Y1034433D03*
X1337839Y1047189D03*
Y1053567D03*
Y1059945D03*
X1339689Y1056756D03*
X1343390Y1050378D03*
X1345241Y1053567D03*
X1341540Y1059945D03*
X1345241D03*
X1337839Y1072701D03*
Y1066323D03*
X1343390Y1063134D03*
Y1069512D03*
X1345241Y1072701D03*
X1337839Y1079079D03*
Y1085457D03*
X1345241Y1079079D03*
X1343390Y1088646D03*
Y1082268D03*
X1337839Y1091835D03*
Y1098213D03*
Y1104591D03*
X1345241Y1091835D03*
X1343390Y1101402D03*
X1345241Y1098213D03*
X1337839Y1110969D03*
Y1117347D03*
X1343390Y1107780D03*
X1345241Y1110969D03*
Y1117347D03*
X1337839Y1123725D03*
Y1130102D03*
X1343390Y1120536D03*
Y1126914D03*
X1345241Y1130102D03*
X1337839Y1136480D03*
Y1142858D03*
Y1149236D03*
X1343390Y1139669D03*
X1345241Y1136480D03*
Y1149236D03*
X1343390Y1146047D03*
X1337839Y1155614D03*
X1335989Y1158803D03*
X1337839Y1161992D03*
X1341540Y1155614D03*
X1339689Y1158803D03*
X1348941Y1155614D03*
X1345241D03*
X1339689Y1165181D03*
X1336968Y1547243D03*
X1338362Y1540295D03*
X1341693Y1547243D03*
X1343087Y1540295D03*
X1346417Y1547243D03*
X1347811Y1540295D03*
X1346087Y1554453D03*
X1341362D03*
X1336638D03*
X1346638Y1561853D03*
X1341913D03*
X1337189D03*
X1347811Y1575641D03*
X1343087D03*
X1338362D03*
X1336688Y1569063D03*
X1338559Y1625380D03*
X1346359D03*
X1340319Y1635380D03*
X1344599D03*
X1340319Y1647292D03*
X1344599D03*
X1338559Y1657292D03*
X1346359D03*
X1347439Y1679320D03*
Y1683857D03*
X1339565Y1684454D03*
Y1679920D03*
Y1675383D03*
X1347439Y1688391D03*
Y1693493D03*
Y1698030D03*
X1339565Y1698627D03*
Y1694093D03*
Y1689556D03*
X1347439Y1716737D03*
Y1702564D03*
Y1707666D03*
Y1712203D03*
X1339565Y1712800D03*
Y1708266D03*
Y1703729D03*
X1347439Y1721840D03*
Y1726377D03*
Y1730911D03*
X1339565Y1726974D03*
Y1722440D03*
Y1717903D03*
X1356343Y1028055D03*
X1363745D03*
X1350792Y1031244D03*
Y1044000D03*
Y1037622D03*
X1356343Y1034433D03*
Y1040811D03*
X1363745Y1034433D03*
Y1040811D03*
X1361894Y1044000D03*
Y1037622D03*
Y1031244D03*
X1354493Y1056756D03*
X1350792D03*
Y1050378D03*
X1352642Y1059945D03*
X1356343Y1047189D03*
X1363745D03*
X1356343Y1053567D03*
X1361894Y1050378D03*
X1356343Y1059945D03*
X1363745Y1053567D03*
X1350792Y1063134D03*
Y1069512D03*
X1358193Y1063134D03*
X1356343Y1072701D03*
X1363745Y1066323D03*
X1358193Y1069512D03*
X1360044Y1066323D03*
X1361894Y1069512D03*
Y1063134D03*
X1350792Y1075890D03*
Y1082268D03*
Y1088646D03*
X1358193Y1075890D03*
X1363745Y1079079D03*
X1360044D03*
X1356343Y1085457D03*
X1358193Y1088646D03*
Y1082268D03*
X1361894Y1075890D03*
X1350792Y1095024D03*
Y1101402D03*
X1356343Y1104591D03*
X1363745Y1091835D03*
X1360044D03*
X1358193Y1095024D03*
X1356343Y1098213D03*
X1363745Y1104591D03*
X1360044D03*
X1350792Y1107780D03*
Y1114158D03*
X1358193Y1107780D03*
X1360044Y1110969D03*
X1363745D03*
X1356343Y1117347D03*
X1358193Y1114158D03*
X1350792Y1120536D03*
Y1126914D03*
Y1133292D03*
X1358193Y1126914D03*
X1363745Y1123725D03*
X1360044D03*
X1358193Y1120536D03*
X1356343Y1130102D03*
X1358193Y1133292D03*
X1350792Y1139669D03*
Y1146047D03*
X1358193Y1139669D03*
X1363745Y1136480D03*
X1360044D03*
X1356343Y1142858D03*
X1363745Y1149236D03*
X1360044D03*
X1358193Y1146047D03*
X1354493Y1158803D03*
X1350792Y1152425D03*
Y1158803D03*
X1352642Y1161992D03*
X1356343Y1155614D03*
X1363745D03*
X1360044D03*
X1363745Y1161992D03*
X1351141Y1547243D03*
X1352536Y1540295D03*
X1355866Y1547243D03*
X1357260Y1540295D03*
X1360590Y1547243D03*
X1361984Y1540295D03*
X1360260Y1554453D03*
X1355536D03*
X1350811D03*
X1360811Y1561853D03*
X1356087D03*
X1351362D03*
X1361984Y1575641D03*
X1360310Y1569063D03*
X1352536Y1575641D03*
X1350861Y1569063D03*
X1357260Y1575641D03*
X1350619Y1625380D03*
X1358419D03*
X1362679D03*
X1352379Y1635380D03*
X1356659D03*
X1364439D03*
X1356659Y1647292D03*
X1352379D03*
X1364439D03*
X1358419Y1657292D03*
X1350619D03*
X1362679D03*
X1363187Y1679320D03*
Y1683857D03*
X1355313Y1684454D03*
Y1679920D03*
Y1675383D03*
Y1694093D03*
Y1689556D03*
X1363187Y1688391D03*
Y1693493D03*
Y1698030D03*
X1355313Y1698627D03*
X1363187Y1716737D03*
Y1702564D03*
Y1707666D03*
Y1712203D03*
X1355313Y1712800D03*
Y1708266D03*
Y1703729D03*
X1363187Y1726377D03*
Y1730911D03*
X1355313Y1726974D03*
Y1722440D03*
Y1717903D03*
X1363187Y1721840D03*
X1371146Y1028055D03*
X1374847D03*
X1369296Y1044000D03*
Y1037622D03*
Y1031244D03*
X1371146Y1034433D03*
X1376697Y1037622D03*
X1378548Y1040811D03*
X1371146D03*
X1374847Y1034433D03*
X1376697Y1031244D03*
Y1044000D03*
X1378548Y1053567D03*
X1376697Y1050378D03*
X1367445Y1059945D03*
X1369296Y1056756D03*
Y1050378D03*
X1371146Y1047189D03*
X1378548D03*
X1376697Y1056756D03*
X1371146Y1053567D03*
X1378548Y1059945D03*
X1369296Y1063134D03*
Y1069512D03*
X1367445Y1066323D03*
Y1072701D03*
X1371146Y1066323D03*
X1378548D03*
X1374847D03*
X1378548Y1072701D03*
X1372997Y1069512D03*
Y1063134D03*
X1365595Y1069512D03*
Y1063134D03*
X1376697Y1069512D03*
Y1063134D03*
X1369296Y1075890D03*
X1367445Y1079079D03*
X1369296Y1088646D03*
X1367445Y1085457D03*
X1369296Y1082268D03*
X1371146Y1079079D03*
X1378548D03*
X1374847D03*
X1378548Y1085457D03*
X1372997Y1075890D03*
X1365595D03*
X1376697D03*
X1367445Y1091835D03*
X1369296Y1095024D03*
X1367445Y1104591D03*
Y1098213D03*
X1371146Y1091835D03*
X1378548D03*
X1374847D03*
X1371146Y1104591D03*
X1374847D03*
X1378548Y1098213D03*
Y1104591D03*
X1369296Y1107780D03*
X1367445Y1110969D03*
X1369296Y1114158D03*
X1367445Y1117347D03*
X1371146Y1110969D03*
X1378548D03*
X1374847D03*
X1378548Y1117347D03*
X1367445Y1130103D03*
X1369296Y1126914D03*
Y1120536D03*
X1367445Y1123725D03*
X1369296Y1133292D03*
X1374847Y1123725D03*
X1371146D03*
X1378548D03*
Y1130102D03*
X1369296Y1139669D03*
X1367445Y1136480D03*
Y1142858D03*
X1369296Y1146047D03*
X1374847Y1136480D03*
X1371146D03*
X1378548D03*
Y1142858D03*
X1371146Y1149236D03*
X1374847D03*
X1367445Y1155614D03*
X1365595Y1158803D03*
X1371146Y1155614D03*
X1378548D03*
X1374847D03*
X1376697Y1158803D03*
Y1165181D03*
X1374847Y1161992D03*
X1365315Y1547243D03*
X1366709Y1540295D03*
X1370039Y1547243D03*
X1371433Y1540295D03*
X1374763Y1547243D03*
X1376158Y1540295D03*
X1379488Y1547243D03*
X1379158Y1554453D03*
X1374433D03*
X1369709D03*
X1364984D03*
X1374984Y1561853D03*
X1370260D03*
X1365535D03*
X1371433Y1575641D03*
X1366709D03*
X1376158D03*
X1374483Y1569063D03*
X1370479Y1625380D03*
X1374740D03*
X1368719Y1635380D03*
X1376499Y1635286D03*
X1368719Y1647292D03*
X1376499D03*
X1370479Y1657292D03*
X1374739D03*
X1385937Y1028063D03*
Y1034441D03*
X1393339Y1040819D03*
X1385937D03*
X1385949Y1047189D03*
Y1053567D03*
X1384099Y1056756D03*
Y1050378D03*
X1393351Y1047189D03*
Y1053567D03*
X1389650Y1059945D03*
X1391500Y1056756D03*
Y1050378D03*
X1389650Y1066323D03*
X1391500Y1069512D03*
X1389650Y1072701D03*
X1380398Y1063134D03*
X1385949Y1066323D03*
X1382249D03*
X1380398Y1069512D03*
X1391500Y1063134D03*
X1393351Y1066323D03*
X1384099Y1069512D03*
Y1063134D03*
X1387800Y1069512D03*
Y1063134D03*
X1380398Y1075890D03*
X1385949Y1079079D03*
X1382249D03*
X1380398Y1088646D03*
Y1082268D03*
X1391500Y1075890D03*
X1393351Y1079079D03*
X1389650D03*
X1391500Y1088646D03*
X1389650Y1085457D03*
X1391500Y1082268D03*
X1384099Y1075890D03*
X1387800D03*
X1385949Y1091835D03*
X1382249D03*
X1380398Y1095024D03*
X1393351Y1091835D03*
X1389650D03*
X1391500Y1095024D03*
Y1101402D03*
X1389650Y1098213D03*
X1393351Y1104591D03*
X1389650D03*
X1385949Y1110969D03*
X1382249D03*
X1380398Y1107780D03*
Y1114158D03*
X1393351Y1110969D03*
X1389650D03*
X1391500Y1107780D03*
X1389650Y1117347D03*
X1391500Y1114158D03*
X1385949Y1123725D03*
X1382249D03*
X1380398Y1120536D03*
Y1126914D03*
Y1133292D03*
X1393351Y1123725D03*
X1389650D03*
X1391500Y1120536D03*
Y1126914D03*
Y1133292D03*
X1389650Y1130102D03*
X1380398Y1139669D03*
X1385949Y1136480D03*
X1382249D03*
X1385949Y1149236D03*
X1382249D03*
X1380398Y1146047D03*
X1391500Y1139669D03*
X1393351Y1136480D03*
X1389650D03*
Y1142858D03*
X1393351Y1149236D03*
X1391500Y1146047D03*
X1385949Y1155614D03*
X1382249D03*
X1385949Y1161992D03*
X1387800Y1158803D03*
X1393351Y1155614D03*
X1389650D03*
X1380882Y1540295D03*
X1384212Y1547243D03*
X1385606Y1540295D03*
X1390331D03*
X1393661Y1547243D03*
X1393331Y1554453D03*
X1388607D03*
X1383882D03*
X1393882Y1561853D03*
X1389158D03*
X1384433D03*
X1379709D03*
X1385606Y1575641D03*
X1383932Y1569063D03*
X1380882Y1575641D03*
X1390331D03*
X1393381Y1569063D03*
X1382539Y1625380D03*
X1388569Y1635380D03*
X1380779D03*
Y1647292D03*
X1388569D03*
X1382539Y1657292D03*
X1400740Y1040819D03*
X1400752Y1047189D03*
X1398902Y1056756D03*
X1400752Y1053567D03*
Y1059945D03*
X1398902Y1050378D03*
X1408154Y1047189D03*
Y1053567D03*
X1406304Y1056756D03*
Y1050378D03*
X1404453Y1059945D03*
X1408154D03*
X1402603Y1063134D03*
Y1069512D03*
X1397052Y1066323D03*
X1400752D03*
Y1072701D03*
X1406304Y1063134D03*
X1395201D03*
X1404453Y1072701D03*
Y1066323D03*
X1395201Y1069512D03*
X1398902Y1063134D03*
X1408154Y1072701D03*
Y1066323D03*
X1398902Y1069512D03*
X1402603Y1075890D03*
X1400752Y1079079D03*
X1397052D03*
X1402603Y1088646D03*
Y1082268D03*
X1400752Y1085457D03*
X1406304Y1075890D03*
Y1088646D03*
X1395201Y1075890D03*
X1404453Y1079079D03*
X1398902Y1075890D03*
X1408154Y1079079D03*
X1402603Y1095024D03*
X1400752Y1091835D03*
X1397052D03*
X1402603Y1101402D03*
X1400752Y1104591D03*
X1397052D03*
X1400752Y1098213D03*
X1406304Y1101402D03*
X1402603Y1107780D03*
X1397052Y1110969D03*
X1400752D03*
X1402603Y1114158D03*
X1400752Y1117347D03*
X1406304Y1107780D03*
X1402603Y1120536D03*
Y1126914D03*
X1397052Y1123725D03*
X1400752D03*
X1402603Y1133292D03*
X1406304Y1120536D03*
Y1133292D03*
X1400752Y1130103D03*
X1402603Y1139669D03*
X1397052Y1136480D03*
X1400752D03*
Y1142858D03*
X1402603Y1146047D03*
X1397052Y1149236D03*
X1408154D03*
X1404453D03*
X1398902Y1158803D03*
X1397052Y1155614D03*
X1400752D03*
X1397052Y1161992D03*
X1398902Y1165181D03*
X1406304Y1158803D03*
X1395055Y1540295D03*
X1398076Y1554453D03*
X1395055Y1575641D03*
X1398712Y1569063D03*
X1411855Y1059945D03*
X1422932Y1047189D03*
Y1059945D03*
Y1053567D03*
X1410004Y1063134D03*
X1411855Y1066323D03*
Y1072701D03*
X1422932D03*
Y1066323D03*
X1410004Y1075890D03*
X1411855Y1079079D03*
Y1085457D03*
X1410004Y1088646D03*
X1422932Y1079079D03*
Y1085457D03*
Y1091835D03*
Y1104591D03*
Y1098213D03*
X1411855Y1091835D03*
Y1104591D03*
Y1098213D03*
X1410004Y1101402D03*
Y1107780D03*
X1411855Y1110969D03*
Y1117347D03*
X1422932Y1110969D03*
Y1117347D03*
X1411855Y1123725D03*
X1410004Y1120536D03*
X1411855Y1130102D03*
X1410004Y1133292D03*
X1422932Y1123725D03*
Y1130102D03*
X1411855Y1136480D03*
Y1142858D03*
Y1149236D03*
X1422932Y1136480D03*
Y1142858D03*
Y1149236D03*
X1411855Y1155614D03*
Y1161992D03*
X1422932Y1155614D03*
Y1161992D03*
X1430346Y1040819D03*
X1437748D03*
X1430334Y1047189D03*
X1424783Y1056756D03*
X1434035Y1059945D03*
X1432184Y1056756D03*
X1430334Y1053567D03*
X1424783Y1050378D03*
X1432184D03*
X1437735Y1047189D03*
Y1053567D03*
X1430334Y1059945D03*
X1426633D03*
X1432184Y1063134D03*
X1428483D03*
X1424783D03*
X1432184Y1069512D03*
X1434035Y1072701D03*
Y1066323D03*
X1437735D03*
X1430334D03*
Y1072701D03*
X1426633Y1066323D03*
Y1072701D03*
X1435885Y1063134D03*
Y1069512D03*
X1437735Y1079079D03*
X1428483Y1075890D03*
X1432184D03*
X1424783D03*
X1434035Y1079079D03*
X1424783Y1088646D03*
X1432184Y1082268D03*
X1428483Y1088646D03*
X1432184D03*
X1434035Y1085457D03*
X1430334Y1079079D03*
X1426633D03*
X1435885Y1075890D03*
X1432184Y1095024D03*
X1434035Y1091835D03*
Y1104591D03*
X1428483Y1101402D03*
X1432184D03*
X1434035Y1098213D03*
X1424783Y1101402D03*
X1437735Y1091835D03*
Y1104591D03*
X1428483Y1107780D03*
X1432184D03*
X1424783D03*
X1434035Y1110969D03*
Y1117347D03*
X1432184Y1114158D03*
X1437735Y1110969D03*
X1432184Y1126914D03*
Y1120536D03*
X1428483D03*
X1424783D03*
X1434035Y1123725D03*
X1424783Y1133292D03*
X1428483D03*
X1432184D03*
X1437735Y1123725D03*
X1434035Y1130103D03*
X1432184Y1139669D03*
X1434035Y1136480D03*
Y1142858D03*
X1430334Y1149236D03*
X1432184Y1146047D03*
X1426633Y1149236D03*
X1437735Y1136480D03*
Y1149236D03*
X1430333Y1155614D03*
X1435885Y1158803D03*
Y1152425D03*
X1452542Y1040819D03*
X1445149D03*
X1445137Y1047189D03*
X1446987Y1056756D03*
X1445137Y1059945D03*
X1439586Y1056756D03*
X1445137Y1053567D03*
X1439586Y1050378D03*
X1446987D03*
X1452539Y1047189D03*
Y1053567D03*
X1443287Y1063134D03*
X1445137Y1072701D03*
X1443287Y1069512D03*
X1448838Y1066323D03*
X1445137D03*
X1441436D03*
X1452539D03*
X1439586Y1063134D03*
Y1069512D03*
X1450688Y1063134D03*
Y1069512D03*
X1446987Y1063134D03*
Y1069512D03*
X1445137Y1079079D03*
X1448838D03*
X1441436D03*
X1443287Y1075890D03*
Y1088646D03*
X1445137Y1085457D03*
X1443287Y1082268D03*
X1452539Y1079079D03*
X1439586Y1075890D03*
X1450688D03*
X1446987D03*
X1441436Y1091835D03*
X1448838D03*
X1445137D03*
X1443287Y1095024D03*
X1445137Y1104591D03*
X1443287Y1101402D03*
X1445137Y1098213D03*
X1441436Y1104591D03*
X1452539Y1091835D03*
X1441436Y1110969D03*
X1448838D03*
X1445137D03*
X1443287Y1107780D03*
X1445137Y1117347D03*
X1443287Y1114158D03*
X1452539Y1110969D03*
X1445137Y1123725D03*
X1448838D03*
X1443287Y1120536D03*
X1441436Y1123725D03*
X1443287Y1126914D03*
Y1133292D03*
X1445137Y1130102D03*
X1452539Y1123725D03*
X1448838Y1149236D03*
X1443287Y1146047D03*
X1441436Y1149236D03*
X1452539Y1136480D03*
Y1149236D03*
X1445137Y1142858D03*
X1443287Y1139669D03*
X1445137Y1136480D03*
X1448838D03*
X1441436D03*
X1446987Y1158803D03*
X1450688Y1152425D03*
X1441436Y1155614D03*
X1449626Y1556810D03*
Y1561725D03*
X1463641Y1028055D03*
X1456239D03*
X1459940Y1040811D03*
X1458090Y1031244D03*
X1463641Y1034433D03*
X1456239D03*
X1465491Y1031244D03*
X1454389Y1037622D03*
X1467342Y1040811D03*
X1454389Y1044000D03*
X1461791Y1037622D03*
Y1044000D03*
X1459940Y1047189D03*
X1456239Y1059945D03*
X1459940Y1053567D03*
X1454389Y1056756D03*
X1461791D03*
X1454389Y1050378D03*
X1461791D03*
X1467342Y1047189D03*
Y1059945D03*
Y1053567D03*
X1465491Y1063134D03*
X1454389D03*
X1456239Y1072701D03*
X1459940Y1066323D03*
X1463641D03*
X1465491Y1069512D03*
X1454389D03*
X1456239Y1066323D03*
X1467342Y1072701D03*
Y1066323D03*
X1461791Y1063134D03*
Y1069512D03*
X1458090Y1063134D03*
Y1069512D03*
X1459940Y1079079D03*
X1463641D03*
X1456239D03*
X1465491Y1075890D03*
X1454389D03*
X1465491Y1088646D03*
X1454389D03*
X1456239Y1085457D03*
X1465491Y1082268D03*
X1454389D03*
X1467342Y1079079D03*
Y1085457D03*
X1461791Y1075890D03*
X1458090D03*
X1456239Y1098213D03*
X1467342Y1091835D03*
Y1104591D03*
Y1098213D03*
X1463641Y1091835D03*
X1459940D03*
X1456239D03*
X1465491Y1095024D03*
X1454389D03*
X1459940Y1104591D03*
X1463641D03*
X1456239D03*
X1465491Y1107780D03*
X1454389D03*
X1463641Y1110969D03*
X1459940D03*
X1456239D03*
Y1117347D03*
X1454389Y1114158D03*
X1465491D03*
X1467342Y1110969D03*
Y1117347D03*
X1454389Y1120536D03*
X1465491Y1126914D03*
X1454389D03*
X1459940Y1123725D03*
X1463641D03*
X1465491Y1120536D03*
X1456239Y1123725D03*
X1454389Y1133292D03*
X1456239Y1130102D03*
X1465491Y1133292D03*
X1467342Y1123725D03*
Y1130102D03*
X1456239Y1142858D03*
X1465491Y1139669D03*
X1459940Y1136480D03*
X1463641D03*
X1454389Y1139669D03*
X1456239Y1136480D03*
X1465491Y1146047D03*
X1459940Y1149236D03*
X1463641D03*
X1454389Y1146047D03*
X1467342Y1136480D03*
Y1142858D03*
X1463641Y1155614D03*
X1461791Y1152425D03*
X1458090Y1158803D03*
X1454994Y1540512D03*
X1458907Y1547243D03*
X1460301Y1540295D03*
X1463631Y1547243D03*
X1465026Y1540295D03*
X1468356Y1547243D03*
X1457735Y1552195D03*
X1468026Y1554453D03*
X1463301D03*
X1458577D03*
X1468577Y1561853D03*
X1463852D03*
X1459128D03*
X1455098Y1575425D03*
X1468076Y1569063D03*
X1463351D03*
X1460301Y1575641D03*
X1458626Y1569063D03*
X1465026Y1575641D03*
X1458013Y1625380D03*
X1465813D03*
X1464053Y1635380D03*
Y1647292D03*
X1465813Y1657292D03*
X1458013D03*
X1478444Y1028055D03*
X1471043D03*
X1472893Y1031244D03*
X1469192Y1037622D03*
Y1044000D03*
X1478444Y1034433D03*
X1476594Y1037622D03*
X1474743Y1040811D03*
X1476594Y1044000D03*
X1471043Y1034433D03*
X1474743Y1047189D03*
X1480295Y1056756D03*
X1482145Y1059945D03*
X1469192Y1050378D03*
X1476594D03*
Y1056756D03*
X1474743Y1053567D03*
X1478444Y1059945D03*
X1469192Y1056756D03*
X1476594Y1063134D03*
X1478444Y1072701D03*
X1476594Y1069512D03*
X1474743Y1066323D03*
X1471043D03*
X1472893Y1063134D03*
Y1069512D03*
X1469192Y1063134D03*
Y1069512D03*
X1476594Y1075890D03*
X1474743Y1079079D03*
X1471043D03*
X1478444Y1085457D03*
X1476594Y1088646D03*
Y1082268D03*
X1472893Y1075890D03*
X1469192D03*
X1474743Y1091835D03*
X1471043D03*
X1476594Y1095024D03*
X1478444Y1098213D03*
Y1104591D03*
X1474743D03*
X1471043D03*
X1472893Y1101402D03*
X1476594Y1107780D03*
X1474743Y1110969D03*
X1471043D03*
X1476594Y1114158D03*
X1478444Y1117347D03*
X1476594Y1126914D03*
Y1120536D03*
X1474743Y1123725D03*
X1471043D03*
X1478444Y1130102D03*
X1476594Y1133292D03*
Y1139669D03*
X1474743Y1136480D03*
X1471043D03*
X1478444Y1142858D03*
X1476594Y1146047D03*
X1474743Y1149236D03*
X1471043D03*
X1474743Y1155614D03*
X1478444D03*
X1472893Y1152425D03*
X1480295Y1158803D03*
X1469192D03*
X1469750Y1540295D03*
X1473080Y1547243D03*
X1474474Y1540295D03*
X1477805Y1547243D03*
X1479199Y1540295D03*
X1482529Y1547243D03*
X1483923Y1540295D03*
X1482199Y1554453D03*
X1477474D03*
X1472750D03*
X1482750Y1561853D03*
X1478025D03*
X1473301D03*
X1469750Y1575641D03*
X1483923D03*
X1474474D03*
X1472800Y1569063D03*
X1479199Y1575641D03*
X1470073Y1625380D03*
X1482133D03*
X1477873D03*
X1471833Y1635380D03*
X1483893D03*
X1476113D03*
X1471833Y1647292D03*
X1483893D03*
X1476113D03*
X1470073Y1657292D03*
X1477873D03*
X1482133D03*
X1489547Y1028055D03*
X1496948D03*
X1483995Y1031244D03*
Y1037622D03*
Y1044000D03*
X1491397Y1031244D03*
X1489547Y1040811D03*
Y1034433D03*
X1491397Y1044000D03*
X1496948Y1034433D03*
Y1040811D03*
Y1047189D03*
X1483995Y1050378D03*
Y1056756D03*
X1489547Y1053567D03*
X1495098Y1056756D03*
X1491397Y1050378D03*
X1489547Y1059945D03*
X1493247D03*
X1496948Y1053567D03*
Y1059945D03*
X1483995Y1063134D03*
X1491397D03*
X1483995Y1069512D03*
X1489547Y1072701D03*
X1491397Y1069512D03*
X1496948Y1072701D03*
Y1066323D03*
X1483995Y1075890D03*
X1489547Y1079079D03*
X1496948D03*
X1483995Y1088646D03*
X1491397D03*
X1496948Y1085457D03*
X1483995Y1082268D03*
X1491397D03*
X1489547Y1091835D03*
X1496948D03*
X1483995Y1095024D03*
Y1101402D03*
X1489547Y1098213D03*
X1491397Y1101402D03*
X1496948Y1098213D03*
Y1104591D03*
X1489547Y1110969D03*
X1496948D03*
X1483995Y1107780D03*
X1491397D03*
X1483995Y1114158D03*
X1489547Y1117347D03*
X1496948D03*
X1483995Y1120536D03*
X1491397D03*
X1496948Y1123725D03*
X1483995Y1126914D03*
X1491397D03*
X1483995Y1133292D03*
X1496948Y1130102D03*
X1489547Y1130103D03*
X1483995Y1139669D03*
X1489547Y1136480D03*
X1491397Y1139669D03*
X1496948Y1136480D03*
Y1142858D03*
X1483995Y1146047D03*
X1489547Y1149236D03*
X1491397Y1146047D03*
X1496948Y1149236D03*
X1487696Y1165181D03*
X1498799Y1158803D03*
X1483995Y1152425D03*
X1485846Y1155614D03*
X1489547D03*
X1493247D03*
X1496948D03*
X1483995Y1158803D03*
X1491397D03*
X1493247Y1161992D03*
X1495111Y1165289D03*
X1491410D03*
X1498812D03*
X1488648Y1540295D03*
X1487253Y1547243D03*
X1491978D03*
X1493372Y1540295D03*
X1496702Y1547243D03*
X1498096Y1540295D03*
X1496372Y1554453D03*
X1491648D03*
X1486923D03*
X1496923Y1561853D03*
X1492199D03*
X1487474D03*
X1488648Y1575641D03*
X1493372D03*
X1498096D03*
X1496422Y1569063D03*
X1486973D03*
X1489933Y1625380D03*
X1494193D03*
X1495953Y1635380D03*
X1488173D03*
X1495953Y1647292D03*
X1488173D03*
X1494193Y1657292D03*
X1489933D03*
X1504350Y1028055D03*
X1502499Y1031244D03*
X1509901D03*
X1504350Y1040811D03*
X1502499Y1037622D03*
X1504350Y1034433D03*
X1502499Y1044000D03*
X1509901Y1037622D03*
Y1044000D03*
X1504350Y1047189D03*
Y1053567D03*
X1502499Y1050378D03*
X1509901Y1056756D03*
Y1050378D03*
X1504350Y1059945D03*
X1508050D03*
X1506200Y1056756D03*
X1502499D03*
Y1063134D03*
X1509901D03*
X1502499Y1069512D03*
X1504350Y1072701D03*
Y1066323D03*
X1509901Y1069512D03*
X1502499Y1075890D03*
X1509901D03*
X1504350Y1079079D03*
Y1085457D03*
X1502499Y1088646D03*
X1509901D03*
X1502499Y1082268D03*
X1509901D03*
X1504350Y1091835D03*
X1502499Y1095024D03*
X1509901D03*
X1504350Y1098213D03*
X1502499Y1101402D03*
X1509901D03*
X1504350Y1104591D03*
X1502499Y1107780D03*
X1509901D03*
X1504350Y1110969D03*
X1509901Y1114158D03*
X1504350Y1117347D03*
X1502499Y1114158D03*
Y1120536D03*
X1504350Y1123725D03*
X1509901Y1120536D03*
X1502499Y1126914D03*
X1509901D03*
Y1133292D03*
X1502499D03*
X1504350Y1130103D03*
X1502499Y1139669D03*
X1504350Y1136480D03*
X1509901Y1139669D03*
X1504350Y1142858D03*
Y1149236D03*
X1502499Y1146047D03*
X1509901D03*
X1504350Y1155614D03*
X1502499Y1152425D03*
X1509901D03*
X1511751Y1155614D03*
X1502499Y1158803D03*
X1506200D03*
X1509901D03*
X1509914Y1165289D03*
X1506213D03*
X1502821Y1540295D03*
X1501427Y1547243D03*
X1506151D03*
X1507545Y1540295D03*
X1510875Y1547243D03*
X1512270Y1540295D03*
X1510545Y1554453D03*
X1505821D03*
X1501096D03*
X1511096Y1561853D03*
X1506372D03*
X1501647D03*
X1507545Y1575641D03*
X1512270D03*
X1510595Y1569063D03*
X1502821Y1575641D03*
X1501993Y1625380D03*
X1506253D03*
X1508013Y1635380D03*
X1500233D03*
X1512293D03*
X1508013Y1647292D03*
X1500233D03*
X1512293D03*
X1501993Y1657292D03*
X1506253D03*
X1513187Y1679320D03*
Y1683857D03*
X1505313Y1684454D03*
Y1679920D03*
Y1675383D03*
X1513187Y1688391D03*
Y1693493D03*
Y1698030D03*
X1505313Y1698627D03*
Y1694093D03*
Y1689556D03*
X1513187Y1716737D03*
Y1702564D03*
Y1707666D03*
Y1712203D03*
X1505313Y1712800D03*
Y1708266D03*
Y1703729D03*
X1513187Y1721840D03*
Y1726377D03*
Y1730911D03*
X1505313Y1726974D03*
Y1722440D03*
Y1717903D03*
X1522854Y1028055D03*
X1515452D03*
X1522854Y1034433D03*
Y1040811D03*
X1517302Y1044000D03*
X1528405Y1037622D03*
Y1044000D03*
X1515452Y1040811D03*
Y1034433D03*
X1517302Y1031244D03*
X1528405D03*
X1515452Y1053567D03*
Y1059945D03*
X1522854Y1047189D03*
Y1053567D03*
X1521003Y1056756D03*
X1517302Y1050378D03*
X1522854Y1059945D03*
X1519153D03*
X1528405Y1050378D03*
Y1056756D03*
X1517302Y1063134D03*
X1528405D03*
X1515452Y1072701D03*
X1522854Y1066323D03*
Y1072701D03*
X1517302Y1069512D03*
X1528405D03*
Y1075890D03*
X1515452Y1079079D03*
X1522854D03*
X1517302Y1082268D03*
X1528405D03*
X1522854Y1085457D03*
X1517302Y1088646D03*
X1528405D03*
X1515452Y1091835D03*
X1522854D03*
X1528405Y1095024D03*
X1522854Y1104591D03*
X1528405Y1101402D03*
X1515452Y1098213D03*
X1522854D03*
X1517302Y1101402D03*
Y1107780D03*
X1528405D03*
X1522854Y1110969D03*
X1515452D03*
X1522854Y1117347D03*
X1528405Y1114158D03*
X1515452Y1117347D03*
X1522854Y1123725D03*
X1517302Y1120536D03*
X1528405D03*
X1517302Y1126914D03*
X1528405D03*
Y1133292D03*
X1515452Y1130102D03*
X1522854Y1130103D03*
Y1142858D03*
Y1136480D03*
X1517302Y1139669D03*
X1528405D03*
X1515452Y1136480D03*
X1528405Y1146047D03*
X1515452Y1149236D03*
X1522854D03*
X1517302Y1146047D03*
X1528405Y1152425D03*
X1524704Y1158803D03*
X1528405D03*
X1515452Y1155614D03*
X1519153D03*
X1522854D03*
X1519153Y1161992D03*
X1521718Y1540295D03*
X1515600Y1547243D03*
X1516994Y1540295D03*
X1520324Y1547243D03*
X1526443Y1540295D03*
X1524719Y1554453D03*
X1519994D03*
X1515270D03*
X1525270Y1561853D03*
X1520545D03*
X1515821D03*
X1516994Y1575641D03*
X1526443D03*
X1521718D03*
X1520044Y1569063D03*
X1514053Y1625380D03*
X1518313D03*
X1526113D03*
X1520073Y1635380D03*
X1524353D03*
X1520073Y1647292D03*
X1524353D03*
X1518313Y1657292D03*
X1514053D03*
X1526113D03*
X1521061Y1684454D03*
Y1679920D03*
Y1675383D03*
Y1698627D03*
Y1694093D03*
Y1689556D03*
Y1712800D03*
Y1708266D03*
Y1703729D03*
Y1726974D03*
Y1722440D03*
Y1717903D03*
X1530255Y1028055D03*
X1541358D03*
X1530255Y1034433D03*
Y1040811D03*
X1541357D03*
Y1034433D03*
X1543208Y1031244D03*
Y1044000D03*
X1535806Y1031244D03*
Y1037622D03*
Y1044000D03*
X1530255Y1047189D03*
Y1053567D03*
Y1059945D03*
X1541357Y1053567D03*
Y1059945D03*
X1543208Y1050378D03*
X1532106Y1056756D03*
X1535806D03*
Y1050378D03*
X1533956Y1059945D03*
X1530255Y1066323D03*
Y1072701D03*
X1543208Y1063134D03*
X1535806D03*
X1543208Y1069512D03*
X1541357Y1072701D03*
X1535806Y1069512D03*
X1530255Y1079079D03*
Y1085457D03*
X1535806Y1075890D03*
X1541357Y1079079D03*
X1543208Y1082268D03*
Y1088646D03*
X1535806D03*
Y1082268D03*
X1530255Y1098213D03*
Y1104591D03*
X1541357Y1091835D03*
X1535806Y1095024D03*
X1543208Y1101402D03*
X1541357Y1098213D03*
X1535806Y1101402D03*
X1530255Y1091835D03*
Y1110969D03*
Y1117347D03*
X1543208Y1107780D03*
X1535806D03*
X1541357Y1110969D03*
Y1117347D03*
X1535806Y1114158D03*
X1530255Y1123725D03*
Y1130102D03*
X1543208Y1120536D03*
X1535806D03*
X1543208Y1126914D03*
X1535806D03*
X1541357Y1130102D03*
X1535806Y1133292D03*
X1530255Y1142858D03*
Y1136480D03*
Y1149236D03*
X1541357Y1136480D03*
X1543208Y1139669D03*
X1535806D03*
X1543208Y1146047D03*
X1541357Y1149236D03*
X1535806Y1146047D03*
X1530255Y1155614D03*
X1537657D03*
X1541357D03*
X1535806Y1152425D03*
X1532106Y1158803D03*
X1535806D03*
X1541357Y1161992D03*
X1532106Y1165181D03*
X1531167Y1540295D03*
X1529773Y1547243D03*
X1534188Y1554453D03*
X1529443D03*
X1529994Y1561853D03*
X1534824Y1569063D03*
X1531167Y1575641D03*
X1529493Y1569063D03*
X1530373Y1625380D03*
X1542433D03*
X1538173D03*
X1532133Y1635380D03*
X1536413D03*
X1532133Y1647292D03*
X1536413D03*
X1530373Y1657292D03*
X1542433D03*
X1538173D03*
X1528935Y1679320D03*
Y1683857D03*
X1536809Y1684454D03*
Y1679920D03*
Y1675383D03*
X1528935Y1688391D03*
Y1693493D03*
Y1698030D03*
X1536809Y1698627D03*
Y1694093D03*
Y1689556D03*
X1528935Y1712203D03*
X1536809Y1712800D03*
Y1708266D03*
Y1703729D03*
X1528935Y1716737D03*
Y1702564D03*
Y1707666D03*
Y1721840D03*
Y1726377D03*
Y1730911D03*
X1536809Y1726974D03*
Y1722440D03*
Y1717903D03*
X1553870Y906181D03*
Y912559D03*
Y918937D03*
Y925315D03*
Y931693D03*
Y938071D03*
Y944449D03*
Y950827D03*
Y957205D03*
Y963583D03*
Y969961D03*
Y976339D03*
Y982717D03*
Y989095D03*
Y995473D03*
Y1008229D03*
Y1001851D03*
X1548759Y1028055D03*
X1555051Y1030197D03*
X1548759Y1040811D03*
Y1034433D03*
X1555051Y1042953D03*
Y1036575D03*
X1546909Y1056756D03*
X1545058Y1059945D03*
X1548759Y1047189D03*
X1555051Y1049331D03*
X1548759Y1053567D03*
Y1059945D03*
X1555051Y1055709D03*
Y1062087D03*
X1548759Y1072701D03*
Y1066323D03*
X1555051Y1068465D03*
Y1074843D03*
X1548759Y1079079D03*
X1555051Y1081221D03*
X1548759Y1085457D03*
X1555051Y1087599D03*
X1548759Y1091835D03*
X1555051Y1093977D03*
X1548759Y1098213D03*
Y1104591D03*
X1555051Y1100355D03*
Y1106733D03*
X1548759Y1110969D03*
X1555051Y1113111D03*
X1548759Y1117347D03*
X1555051Y1119489D03*
Y1132245D03*
X1548759Y1123725D03*
X1555051Y1125867D03*
X1548759Y1130102D03*
Y1136480D03*
X1555051Y1138622D03*
X1548759Y1142858D03*
X1555051Y1145000D03*
X1548759Y1149236D03*
X1545058Y1155614D03*
X1548759D03*
X1555051Y1151378D03*
X1550609Y1158803D03*
X1554310D03*
X1550233Y1625380D03*
X1554493D03*
X1544193Y1635380D03*
X1556253D03*
X1548473D03*
X1544193Y1647292D03*
X1556253D03*
X1548473D03*
X1554493Y1657292D03*
X1550233D03*
X1544683Y1679320D03*
Y1683857D03*
X1552557Y1684454D03*
Y1679920D03*
Y1675383D03*
X1544683Y1688391D03*
Y1693493D03*
Y1698030D03*
X1552557Y1698627D03*
Y1694093D03*
Y1689556D03*
X1544683Y1716737D03*
Y1702564D03*
Y1707666D03*
Y1712203D03*
X1552557Y1712800D03*
Y1708266D03*
Y1703729D03*
X1544683Y1721840D03*
Y1726377D03*
Y1730911D03*
X1552557Y1726974D03*
Y1722440D03*
Y1717903D03*
X1562293Y1625380D03*
X1566553D03*
X1568313Y1635380D03*
X1560533D03*
X1572593D03*
X1568313Y1647292D03*
X1560533D03*
X1572593D03*
X1562293Y1657292D03*
X1566553D03*
X1572243Y1684454D03*
Y1679920D03*
Y1675383D03*
X1560431Y1679320D03*
Y1683857D03*
X1572243Y1698627D03*
Y1694093D03*
Y1689556D03*
X1560431Y1688391D03*
Y1693493D03*
Y1698030D03*
X1572243Y1712800D03*
Y1708266D03*
Y1703729D03*
X1560431Y1716737D03*
Y1702564D03*
Y1707666D03*
Y1712203D03*
X1572243Y1726974D03*
Y1722440D03*
Y1717903D03*
X1560431Y1721840D03*
Y1726377D03*
Y1730911D03*
X1583056Y1540514D03*
X1586969Y1547243D03*
X1585797Y1552195D03*
X1586639Y1554453D03*
X1587190Y1561853D03*
X1577688Y1556810D03*
Y1561725D03*
X1586688Y1569063D03*
X1583160Y1575425D03*
X1574353Y1625380D03*
X1578613D03*
X1586413D03*
X1580373Y1635380D03*
X1584653D03*
X1580373Y1647292D03*
X1584653D03*
X1574353Y1657292D03*
X1578613D03*
X1586413D03*
X1580117Y1679320D03*
Y1683857D03*
X1587991Y1684454D03*
Y1679920D03*
Y1675383D03*
X1580117Y1688391D03*
Y1693493D03*
Y1698030D03*
X1587991Y1698627D03*
Y1694093D03*
Y1689556D03*
X1580117Y1716737D03*
Y1702564D03*
Y1707666D03*
Y1712203D03*
X1587991Y1712800D03*
Y1708266D03*
Y1703729D03*
X1580117Y1721840D03*
Y1726377D03*
Y1730911D03*
X1587991Y1726974D03*
Y1722440D03*
Y1717903D03*
X1588363Y1540295D03*
X1591693Y1547243D03*
X1593088Y1540295D03*
X1596418Y1547243D03*
X1597812Y1540295D03*
X1601142Y1547243D03*
X1602536Y1540295D03*
X1600812Y1554453D03*
X1596088D03*
X1591363D03*
X1601363Y1561853D03*
X1596639D03*
X1591914D03*
X1602536Y1575641D03*
X1600862Y1569063D03*
X1597812Y1575641D03*
X1596138Y1569063D03*
X1593088Y1575641D03*
X1591413Y1569063D03*
X1588363Y1575641D03*
X1590673Y1625380D03*
X1602733D03*
X1598473D03*
X1592433Y1635380D03*
X1596713D03*
X1592433Y1647292D03*
X1596713D03*
X1590673Y1657292D03*
X1598473D03*
X1602733D03*
X1595865Y1679320D03*
Y1683857D03*
Y1688391D03*
Y1693493D03*
Y1698030D03*
Y1716737D03*
Y1702564D03*
Y1707666D03*
Y1712203D03*
Y1721840D03*
Y1726377D03*
Y1730911D03*
X1605867Y1547243D03*
X1607261Y1540295D03*
X1610591Y1547243D03*
X1611985Y1540295D03*
X1615315Y1547243D03*
X1616710Y1540295D03*
X1614985Y1554453D03*
X1610261D03*
X1605536D03*
X1615536Y1561853D03*
X1610812D03*
X1606087D03*
X1616710Y1575641D03*
X1615035Y1569063D03*
X1611985Y1575641D03*
X1607261D03*
X1610533Y1625380D03*
X1614793D03*
X1604493Y1635380D03*
X1616553D03*
X1608773D03*
X1604493Y1647292D03*
X1616553D03*
X1608773D03*
X1614793Y1657292D03*
X1610533D03*
X1611613Y1679320D03*
Y1683857D03*
X1603739Y1684454D03*
Y1679920D03*
Y1675383D03*
X1611613Y1688391D03*
Y1693493D03*
Y1698030D03*
X1603739Y1698627D03*
Y1694093D03*
Y1689556D03*
X1611613Y1702564D03*
Y1707666D03*
Y1712203D03*
X1603739Y1712800D03*
Y1708266D03*
Y1703729D03*
X1611613Y1716737D03*
Y1721840D03*
Y1726377D03*
Y1730911D03*
X1603739Y1726974D03*
Y1722440D03*
Y1717903D03*
X1620040Y1547243D03*
X1621434Y1540295D03*
X1624764Y1547243D03*
X1626158Y1540295D03*
X1629489Y1547243D03*
X1630883Y1540295D03*
X1629158Y1554453D03*
X1624434D03*
X1619710D03*
X1629709Y1561853D03*
X1624985D03*
X1620261D03*
X1630883Y1575641D03*
X1626158D03*
X1624484Y1569063D03*
X1621434Y1575641D03*
X1622593Y1625380D03*
X1626853D03*
X1628613Y1635380D03*
X1620833D03*
X1632893D03*
X1628613Y1647292D03*
X1620833D03*
X1632893D03*
X1622593Y1657292D03*
X1626853D03*
X1627361Y1679320D03*
Y1683857D03*
X1619487Y1684454D03*
Y1679920D03*
Y1675383D03*
X1627361Y1688391D03*
Y1693493D03*
Y1698030D03*
X1619487Y1698627D03*
Y1694093D03*
Y1689556D03*
Y1708266D03*
Y1703729D03*
X1627361Y1716737D03*
Y1702564D03*
Y1707666D03*
Y1712203D03*
X1619487Y1712800D03*
X1627361Y1721840D03*
Y1726377D03*
Y1730911D03*
X1619487Y1726974D03*
Y1722440D03*
Y1717903D03*
X1634213Y1547243D03*
X1635607Y1540295D03*
X1638937Y1547243D03*
X1640332Y1540295D03*
X1643662Y1547243D03*
X1645056Y1540295D03*
X1643332Y1554453D03*
X1638607D03*
X1633883D03*
X1643883Y1561853D03*
X1639158D03*
X1634434D03*
X1645056Y1575641D03*
X1640332D03*
X1638657Y1569063D03*
X1635607Y1575641D03*
X1634653Y1625380D03*
X1638923D03*
X1646713D03*
X1640673Y1635286D03*
X1644953Y1635380D03*
X1640673Y1647292D03*
X1644953D03*
X1634653Y1657292D03*
X1638913D03*
X1646713D03*
X1648386Y1547243D03*
X1649780Y1540295D03*
X1654505D03*
X1657835Y1547243D03*
X1659229Y1540295D03*
X1662250Y1554453D03*
X1657505D03*
X1652781D03*
X1648056D03*
X1658056Y1561853D03*
X1653332D03*
X1648607D03*
X1649780Y1575641D03*
X1648106Y1569063D03*
X1654505Y1575641D03*
X1657555Y1569063D03*
X1659229Y1575641D03*
X1652743Y1635380D03*
Y1647292D03*
X1662886Y1569063D03*
G54D38*
X274913Y1019214D03*
X320189Y838505D03*
Y1199923D03*
X561133Y838505D03*
Y1199923D03*
X606409Y1019214D03*
X841240Y1420331D03*
X1016240D03*
X1251055Y1019213D03*
X1296331Y838504D03*
Y1199922D03*
X1537275Y838504D03*
Y1199922D03*
X1582551Y1019213D03*
G54D45*
X393287Y-28508D03*
Y-18508D03*
X731757Y-20090D03*
X735010Y-20104D03*
X728717Y-18895D03*
X734995Y-17589D03*
X731742Y-17575D03*
X735041Y-14717D03*
X735026Y-12202D03*
X734996Y-7172D03*
X728718Y-8478D03*
X735011Y-9687D03*
X731743Y-7158D03*
X731758Y-9673D03*
X844766Y-24648D03*
Y5352D03*
Y15352D03*
X1180124Y-35569D03*
X1183149Y-34249D03*
X1183164Y-36764D03*
X1183139Y-26179D03*
X1180099Y-14984D03*
X1183124Y-13664D03*
X1183139Y-16179D03*
X1183124Y-23664D03*
X1180099Y-24984D03*
X1183139Y-6179D03*
X1183124Y-3664D03*
X1180099Y-4984D03*
Y15016D03*
X1183124Y16336D03*
X1183139Y13821D03*
X1180099Y5016D03*
X1183124Y6336D03*
X1183139Y3821D03*
X1183140Y24187D03*
X1183125Y26702D03*
X1180100Y25382D03*
X1186402Y-34263D03*
X1186417Y-36778D03*
X1186448Y-31442D03*
X1186433Y-28927D03*
X1186392Y-26193D03*
X1186377Y-13678D03*
X1186392Y-16193D03*
X1186377Y-23678D03*
X1186392Y-6193D03*
X1186377Y-3678D03*
Y16322D03*
X1186392Y13807D03*
X1186377Y6322D03*
X1186392Y3807D03*
X1186423Y19143D03*
X1186408Y21658D03*
X1186393Y24173D03*
X1186378Y26688D03*
X1248286Y-34648D03*
Y-4648D03*
Y5352D03*
X1438983Y-35569D03*
X1438959Y25382D03*
X1445292Y-28927D03*
X1445307Y-31442D03*
X1442023Y-36764D03*
X1442008Y-34249D03*
X1445276Y-36778D03*
X1445261Y-34263D03*
X1441909Y-19948D03*
X1445171D03*
X1441909Y-9948D03*
X1445171D03*
X1441909Y52D03*
X1445171D03*
X1441909Y10052D03*
X1445171D03*
X1445237Y26688D03*
X1445252Y24173D03*
X1441984Y26702D03*
X1441999Y24187D03*
X1445267Y21658D03*
X1445282Y19143D03*
X1541580Y-38849D03*
Y-28849D03*
X1735374Y-27916D03*
X1732349Y-29236D03*
X1735389Y-30431D03*
X1735390Y-20014D03*
X1735375Y-17499D03*
X1732350Y-18819D03*
X1738627Y-27930D03*
X1738642Y-30445D03*
X1738643Y-20028D03*
X1738628Y-17513D03*
X1738673Y-25058D03*
X1738658Y-22543D03*
G54D80*
X1900275Y-39973D03*
X1910275D03*
X1931395Y572237D03*
X1921395D03*
X1929766Y1198160D03*
X1919766D03*
X1942395Y-39783D03*
X1952395D03*
X1963362Y572379D03*
X1961856Y1198170D03*
X1973362Y572379D03*
X1971856Y1198170D03*
X1984482Y-39811D03*
X1994482D03*
X2005452Y572389D03*
X2003823Y1198312D03*
X2015452Y572389D03*
X2013823Y1198312D03*
X2036452Y-39631D03*
X2026452D03*
X2047419Y572531D03*
X2057419D03*
G54D21*
X57646Y12480D03*
X137272D03*
X186622D03*
X266858D03*
X315598D03*
X502528Y33267D03*
X582154D03*
X631504D03*
X711740D03*
X760480D03*
X1532055Y12480D03*
X1611681D03*
X1661031D03*
X1741267D03*
X1790007D03*
G54D42*
X326731Y663237D03*
X363731D03*
X754645Y1436735D03*
X1166535Y1422322D03*
X1291146Y1385558D03*
X1320516D03*
X1487677Y649988D03*
X1524437Y650208D03*
X1701285Y208455D03*
X1700840Y1434362D03*
X1731660Y208455D03*
X1770442Y294777D03*
X1800002D03*
G54D63*
X1077638Y133866D03*
G54D26*
X77394Y734588D03*
Y1021399D03*
Y1277698D03*
X107095Y734588D03*
Y1021399D03*
Y1277698D03*
X136795Y734588D03*
Y1021399D03*
Y1277698D03*
X166496Y734588D03*
Y1021399D03*
Y1277698D03*
X196197Y734588D03*
Y1021399D03*
Y1277698D03*
X225898Y734588D03*
Y1021399D03*
Y1277698D03*
X655425Y734588D03*
Y1021399D03*
Y1277698D03*
X685126Y734588D03*
Y1021399D03*
Y1277698D03*
X714827Y734588D03*
Y1021399D03*
Y1277698D03*
X744528Y734588D03*
Y1021399D03*
Y1277698D03*
X774229Y734588D03*
Y1021399D03*
Y1277698D03*
X803929Y734588D03*
Y1021399D03*
Y1277698D03*
X1053536Y734587D03*
Y1021398D03*
Y1277697D03*
X1083237Y734587D03*
Y1021398D03*
Y1277697D03*
X1112937Y734587D03*
Y1021398D03*
Y1277697D03*
X1142638Y734587D03*
Y1021398D03*
Y1277697D03*
X1172339Y734587D03*
Y1021398D03*
Y1277697D03*
X1202040Y734587D03*
Y1021398D03*
Y1277697D03*
X1631567Y734587D03*
Y1021398D03*
Y1277697D03*
X1661268Y734587D03*
Y1021398D03*
Y1277697D03*
X1690969Y734587D03*
Y1021398D03*
Y1277697D03*
X1720670Y734587D03*
Y1021398D03*
Y1277697D03*
X1750371Y734587D03*
Y1021398D03*
Y1277697D03*
X1780071Y734587D03*
Y1021398D03*
Y1277697D03*
G54D57*
X887519Y1528191D03*
G54D70*
X1299439Y112812D03*
G54D71*
X1454797Y87432D03*
G54D72*
X1550377Y581353D03*
G54D49*
X549016Y274272D03*
G54D58*
X900197Y175177D03*
X944685Y155197D03*
G54D79*
X1864706Y1722195D03*
X1887340Y424013D03*
X1887240Y796658D03*
X1887579Y1171532D03*
G54D77*
X1865648Y796913D03*
X1866790Y1171255D03*
X1886177Y1722507D03*
X2076128Y424013D03*
%LPC*%
G75*
G54D84*
G01X-476840Y-884638D02*
Y2768362D01*
X5911000D01*
Y-884638D01*
X-476840D01*
G01X8000Y-625138D02*
Y-630138D01*
G01X6543Y-625138D02*
X9457D01*
G01X14367Y-630138D02*
X11833D01*
Y-625138D01*
X14367D01*
G01X13353Y-627555D02*
X11833D01*
G01X16933Y-625138D02*
Y-630138D01*
X19467D01*
G01X23300Y-630305D02*
X23173Y-630221D01*
Y-630055D01*
X23300Y-629971D01*
X23427Y-630055D01*
Y-630221D01*
X23300Y-630305D01*
G01Y-628055D02*
X23173Y-627971D01*
Y-627805D01*
X23300Y-627721D01*
X23427Y-627805D01*
Y-627971D01*
X23300Y-628055D01*
G01X28083Y-631805D02*
X27450Y-630971D01*
X27133Y-630138D01*
Y-626805D01*
X27450Y-625971D01*
X28083Y-625138D01*
G01X33500D02*
X32993Y-625305D01*
X32613Y-625721D01*
X32360Y-626221D01*
X32170Y-626888D01*
X32107Y-627638D01*
X32170Y-628388D01*
X32360Y-629055D01*
X32613Y-629555D01*
X32993Y-629971D01*
X33500Y-630138D01*
X34007Y-629971D01*
X34387Y-629555D01*
X34640Y-629055D01*
X34830Y-628388D01*
X34893Y-627638D01*
X34830Y-626888D01*
X34640Y-626221D01*
X34387Y-625721D01*
X34007Y-625305D01*
X33500Y-625138D01*
G01X37207Y-629138D02*
X37587Y-629721D01*
X38093Y-630055D01*
X38663Y-630138D01*
X39170Y-630055D01*
X39677Y-629638D01*
X39993Y-629138D01*
X40057Y-628638D01*
X39930Y-628055D01*
X39487Y-627638D01*
X39043Y-627471D01*
X38473D01*
G01X39043D02*
X39423Y-627221D01*
X39740Y-626805D01*
X39867Y-626305D01*
X39740Y-625805D01*
X39423Y-625388D01*
X38853Y-625138D01*
X38283Y-625221D01*
X37713Y-625555D01*
G01X44017Y-631805D02*
X44650Y-630971D01*
X44967Y-630138D01*
Y-626805D01*
X44650Y-625971D01*
X44017Y-625138D01*
G01X47407Y-629138D02*
X47787Y-629721D01*
X48293Y-630055D01*
X48863Y-630138D01*
X49370Y-630055D01*
X49877Y-629638D01*
X50193Y-629138D01*
X50257Y-628638D01*
X50130Y-628055D01*
X49687Y-627638D01*
X49243Y-627471D01*
X48673D01*
G01X49243D02*
X49623Y-627221D01*
X49940Y-626805D01*
X50067Y-626305D01*
X49940Y-625805D01*
X49623Y-625388D01*
X49053Y-625138D01*
X48483Y-625221D01*
X47913Y-625555D01*
G01X52697Y-625971D02*
X53077Y-625471D01*
X53520Y-625221D01*
X54027Y-625138D01*
X54660Y-625305D01*
X55103Y-625721D01*
X55230Y-626221D01*
X55167Y-626721D01*
X54913Y-627138D01*
X53647Y-627971D01*
X53077Y-628555D01*
X52697Y-629388D01*
X52570Y-630138D01*
X55230D01*
G01X58873D02*
X59000Y-629055D01*
X59190Y-628138D01*
X59443Y-627305D01*
X59760Y-626388D01*
X60267Y-625138D01*
X57733D01*
G01X63277Y-628471D02*
X64923D01*
G01X67997Y-625971D02*
X68377Y-625471D01*
X68820Y-625221D01*
X69327Y-625138D01*
X69960Y-625305D01*
X70403Y-625721D01*
X70530Y-626221D01*
X70467Y-626721D01*
X70213Y-627138D01*
X68947Y-627971D01*
X68377Y-628555D01*
X67997Y-629388D01*
X67870Y-630138D01*
X70530D01*
G01X72907Y-629138D02*
X73287Y-629721D01*
X73793Y-630055D01*
X74363Y-630138D01*
X74870Y-630055D01*
X75377Y-629638D01*
X75693Y-629138D01*
X75757Y-628638D01*
X75630Y-628055D01*
X75187Y-627638D01*
X74743Y-627471D01*
X74173D01*
G01X74743D02*
X75123Y-627221D01*
X75440Y-626805D01*
X75567Y-626305D01*
X75440Y-625805D01*
X75123Y-625388D01*
X74553Y-625138D01*
X73983Y-625221D01*
X73413Y-625555D01*
G01X80160Y-630138D02*
Y-625138D01*
X77817Y-628721D01*
X80983D01*
G01X83107Y-629388D02*
X83487Y-629805D01*
X83930Y-630055D01*
X84500Y-630138D01*
X85070Y-629971D01*
X85513Y-629638D01*
X85830Y-629055D01*
X85893Y-628388D01*
X85767Y-627721D01*
X85450Y-627305D01*
X85007Y-626971D01*
X84563Y-626888D01*
X84120Y-626971D01*
X83550Y-627305D01*
X83740Y-625138D01*
X85450D01*
G01X93497Y-630138D02*
Y-625138D01*
X95903D01*
G01X95017Y-627555D02*
X93497D01*
G01X98217Y-630138D02*
X99800Y-625138D01*
X101383Y-630138D01*
G01X100813Y-628388D02*
X98787D01*
G01X103570Y-630138D02*
X106230Y-625138D01*
G01X103570D02*
X106230Y-630138D01*
G01X110000Y-630305D02*
X109873Y-630221D01*
Y-630055D01*
X110000Y-629971D01*
X110127Y-630055D01*
Y-630221D01*
X110000Y-630305D01*
G01Y-628055D02*
X109873Y-627971D01*
Y-627805D01*
X110000Y-627721D01*
X110127Y-627805D01*
Y-627971D01*
X110000Y-628055D01*
G01X114783Y-631805D02*
X114150Y-630971D01*
X113833Y-630138D01*
Y-626805D01*
X114150Y-625971D01*
X114783Y-625138D01*
G01X120200D02*
X119693Y-625305D01*
X119313Y-625721D01*
X119060Y-626221D01*
X118870Y-626888D01*
X118807Y-627638D01*
X118870Y-628388D01*
X119060Y-629055D01*
X119313Y-629555D01*
X119693Y-629971D01*
X120200Y-630138D01*
X120707Y-629971D01*
X121087Y-629555D01*
X121340Y-629055D01*
X121530Y-628388D01*
X121593Y-627638D01*
X121530Y-626888D01*
X121340Y-626221D01*
X121087Y-625721D01*
X120707Y-625305D01*
X120200Y-625138D01*
G01X123907Y-629138D02*
X124287Y-629721D01*
X124793Y-630055D01*
X125363Y-630138D01*
X125870Y-630055D01*
X126377Y-629638D01*
X126693Y-629138D01*
X126757Y-628638D01*
X126630Y-628055D01*
X126187Y-627638D01*
X125743Y-627471D01*
X125173D01*
G01X125743D02*
X126123Y-627221D01*
X126440Y-626805D01*
X126567Y-626305D01*
X126440Y-625805D01*
X126123Y-625388D01*
X125553Y-625138D01*
X124983Y-625221D01*
X124413Y-625555D01*
G01X130717Y-631805D02*
X131350Y-630971D01*
X131667Y-630138D01*
Y-626805D01*
X131350Y-625971D01*
X130717Y-625138D01*
G01X134107Y-629138D02*
X134487Y-629721D01*
X134993Y-630055D01*
X135563Y-630138D01*
X136070Y-630055D01*
X136577Y-629638D01*
X136893Y-629138D01*
X136957Y-628638D01*
X136830Y-628055D01*
X136387Y-627638D01*
X135943Y-627471D01*
X135373D01*
G01X135943D02*
X136323Y-627221D01*
X136640Y-626805D01*
X136767Y-626305D01*
X136640Y-625805D01*
X136323Y-625388D01*
X135753Y-625138D01*
X135183Y-625221D01*
X134613Y-625555D01*
G01X139523Y-629555D02*
X139967Y-629971D01*
X140473Y-630138D01*
X140980Y-629971D01*
X141423Y-629471D01*
X141740Y-628721D01*
X141867Y-627971D01*
Y-627055D01*
X141740Y-626305D01*
X141423Y-625638D01*
X141043Y-625305D01*
X140600Y-625138D01*
X140093Y-625305D01*
X139713Y-625638D01*
X139460Y-626138D01*
X139333Y-626805D01*
X139460Y-627388D01*
X139777Y-627971D01*
X140157Y-628305D01*
X140600Y-628388D01*
X141107Y-628221D01*
X141487Y-627805D01*
X141867Y-627055D01*
G01X145573Y-630138D02*
X145700Y-629055D01*
X145890Y-628138D01*
X146143Y-627305D01*
X146460Y-626388D01*
X146967Y-625138D01*
X144433D01*
G01X149977Y-628471D02*
X151623D01*
G01X154507Y-629138D02*
X154887Y-629721D01*
X155393Y-630055D01*
X155963Y-630138D01*
X156470Y-630055D01*
X156977Y-629638D01*
X157293Y-629138D01*
X157357Y-628638D01*
X157230Y-628055D01*
X156787Y-627638D01*
X156343Y-627471D01*
X155773D01*
G01X156343D02*
X156723Y-627221D01*
X157040Y-626805D01*
X157167Y-626305D01*
X157040Y-625805D01*
X156723Y-625388D01*
X156153Y-625138D01*
X155583Y-625221D01*
X155013Y-625555D01*
G01X159797Y-628055D02*
X160240Y-627471D01*
X160620Y-627138D01*
X161127Y-626971D01*
X161570Y-627138D01*
X161887Y-627471D01*
X162140Y-627971D01*
X162203Y-628555D01*
X162140Y-629055D01*
X161887Y-629555D01*
X161507Y-629971D01*
X161063Y-630138D01*
X160557Y-629971D01*
X160113Y-629471D01*
X159860Y-628721D01*
X159797Y-627888D01*
X159923Y-626805D01*
X160113Y-626221D01*
X160430Y-625638D01*
X160873Y-625221D01*
X161317Y-625138D01*
X161760Y-625305D01*
X162077Y-625721D01*
G01X166100Y-630138D02*
Y-625138D01*
X165340Y-626138D01*
G01Y-630138D02*
X166860D01*
G01X171960D02*
Y-625138D01*
X169617Y-628721D01*
X172783D01*
G01X-4000Y-560138D02*
Y-635138D01*
X496000D01*
Y-560138D01*
X-4000D01*
G01X191000D02*
Y-635138D01*
G01Y-610138D02*
X294000D01*
Y-585138D01*
G01X191000D02*
X294000D01*
G01X296000Y-560138D02*
Y-635138D01*
G01X294000Y-560138D02*
Y-635138D01*
G01X301507Y-620138D02*
Y-615138D01*
X302773D01*
X303280Y-615388D01*
X303660Y-615721D01*
X303977Y-616221D01*
X304230Y-616805D01*
X304293Y-617638D01*
X304230Y-618471D01*
X303977Y-619055D01*
X303660Y-619555D01*
X303280Y-619888D01*
X302773Y-620138D01*
X301507D01*
G01X306417D02*
X308000Y-615138D01*
X309583Y-620138D01*
G01X309013Y-618388D02*
X306987D01*
G01X313100Y-615138D02*
Y-620138D01*
G01X311643Y-615138D02*
X314557D01*
G01X319467Y-620138D02*
X316933D01*
Y-615138D01*
X319467D01*
G01X318453Y-617555D02*
X316933D01*
G01X323300Y-620305D02*
X323173Y-620221D01*
Y-620055D01*
X323300Y-619971D01*
X323427Y-620055D01*
Y-620221D01*
X323300Y-620305D01*
G01Y-618055D02*
X323173Y-617971D01*
Y-617805D01*
X323300Y-617721D01*
X323427Y-617805D01*
Y-617971D01*
X323300Y-618055D01*
G01X296000Y-610138D02*
X496000D01*
G01X301633Y-595138D02*
Y-590138D01*
X303153D01*
X303660Y-590388D01*
X304040Y-590971D01*
X304167Y-591638D01*
X304040Y-592305D01*
X303723Y-592805D01*
X303153Y-593055D01*
X301633D01*
G01X306860Y-595305D02*
X309140Y-590138D01*
G01X311643Y-595138D02*
Y-590138D01*
X314557Y-595138D01*
Y-590138D01*
G01X318200Y-595305D02*
X318073Y-595221D01*
Y-595055D01*
X318200Y-594971D01*
X318327Y-595055D01*
Y-595221D01*
X318200Y-595305D01*
G01Y-593055D02*
X318073Y-592971D01*
Y-592805D01*
X318200Y-592721D01*
X318327Y-592805D01*
Y-592971D01*
X318200Y-593055D01*
G01X296000Y-585138D02*
X496000D01*
G01X301633Y-570138D02*
Y-565138D01*
X303153D01*
X303660Y-565388D01*
X304040Y-565971D01*
X304167Y-566638D01*
X304040Y-567305D01*
X303723Y-567805D01*
X303153Y-568055D01*
X301633D01*
G01X306733Y-570138D02*
Y-565138D01*
X308317D01*
X308823Y-565388D01*
X309140Y-565721D01*
X309267Y-566388D01*
X309140Y-567055D01*
X308760Y-567471D01*
X308317Y-567721D01*
X306733D01*
G01X308317D02*
X309267Y-570138D01*
G01X313100D02*
X312593Y-570055D01*
X312150Y-569721D01*
X311770Y-569221D01*
X311517Y-568638D01*
X311390Y-567971D01*
Y-567305D01*
X311517Y-566638D01*
X311770Y-566055D01*
X312150Y-565555D01*
X312593Y-565221D01*
X313100Y-565138D01*
X313607Y-565221D01*
X314050Y-565555D01*
X314430Y-566055D01*
X314683Y-566638D01*
X314810Y-567305D01*
Y-567971D01*
X314683Y-568638D01*
X314430Y-569221D01*
X314050Y-569721D01*
X313607Y-570055D01*
X313100Y-570138D01*
G01X316933Y-569138D02*
X317250Y-569638D01*
X317630Y-569971D01*
X318073Y-570138D01*
X318580Y-569971D01*
X318960Y-569638D01*
X319340Y-569138D01*
X319467Y-568471D01*
Y-565138D01*
G01X324567Y-570138D02*
X322033D01*
Y-565138D01*
X324567D01*
G01X323553Y-567555D02*
X322033D01*
G01X329793Y-565555D02*
X329413Y-565305D01*
X328970Y-565138D01*
X328463D01*
X327893Y-565388D01*
X327450Y-565805D01*
X327133Y-566305D01*
X326880Y-567138D01*
X326817Y-567888D01*
X326943Y-568638D01*
X327133Y-569138D01*
X327513Y-569638D01*
X327957Y-569971D01*
X328400Y-570138D01*
X328843D01*
X329287Y-569971D01*
X329667Y-569721D01*
X329983Y-569388D01*
G01X333500Y-565138D02*
Y-570138D01*
G01X332043Y-565138D02*
X334957D01*
G01X338600Y-570305D02*
X338473Y-570221D01*
Y-570055D01*
X338600Y-569971D01*
X338727Y-570055D01*
Y-570221D01*
X338600Y-570305D01*
G01Y-568055D02*
X338473Y-567971D01*
Y-567805D01*
X338600Y-567721D01*
X338727Y-567805D01*
Y-567971D01*
X338600Y-568055D01*
G01X411000Y-610138D02*
Y-635138D01*
G01X413633Y-612638D02*
Y-617638D01*
X416167D01*
G01X419240Y-612638D02*
X420760D01*
G01X420000D02*
Y-617638D01*
G01X419240D02*
X420760D01*
G01X425607Y-614971D02*
X425860Y-614721D01*
X426050Y-614305D01*
X426177Y-613721D01*
X426050Y-613221D01*
X425797Y-612888D01*
X425353Y-612638D01*
X423643D01*
Y-617638D01*
X425733D01*
X426177Y-617305D01*
X426430Y-616805D01*
X426557Y-616221D01*
X426430Y-615638D01*
X426050Y-615138D01*
X425607Y-614971D01*
X423643D01*
G01X430200Y-617805D02*
X430073Y-617721D01*
Y-617555D01*
X430200Y-617471D01*
X430327Y-617555D01*
Y-617721D01*
X430200Y-617805D01*
G01Y-615555D02*
X430073Y-615471D01*
Y-615305D01*
X430200Y-615221D01*
X430327Y-615305D01*
Y-615471D01*
X430200Y-615555D01*
G01X454000Y-610138D02*
Y-635138D01*
G01Y-585138D02*
Y-610138D01*
G01X459013Y-637305D02*
X459120Y-637180D01*
X459200Y-636971D01*
X459253Y-636680D01*
X459200Y-636430D01*
X459093Y-636263D01*
X458907Y-636138D01*
X458187D01*
Y-638638D01*
X459067D01*
X459253Y-638471D01*
X459360Y-638221D01*
X459413Y-637930D01*
X459360Y-637638D01*
X459200Y-637388D01*
X459013Y-637305D01*
X458187D01*
G01X461480Y-638638D02*
Y-636971D01*
G01Y-637263D02*
X461373Y-637096D01*
X461213Y-637013D01*
X461027Y-636971D01*
X460840Y-637055D01*
X460680Y-637221D01*
X460573Y-637471D01*
X460520Y-637805D01*
X460573Y-638138D01*
X460680Y-638388D01*
X460840Y-638555D01*
X461027Y-638638D01*
X461213Y-638596D01*
X461373Y-638471D01*
X461480Y-638305D01*
G01X462800Y-638346D02*
X462933Y-638513D01*
X463120Y-638638D01*
X463280D01*
X463440Y-638555D01*
X463547Y-638430D01*
X463600Y-638263D01*
X463573Y-638013D01*
X463467Y-637888D01*
X462987Y-637638D01*
X462880Y-637346D01*
X462933Y-637138D01*
X463040Y-637013D01*
X463200Y-636971D01*
X463360Y-637013D01*
X463520Y-637138D01*
G01X465000Y-637513D02*
X465853D01*
X465773Y-637221D01*
X465640Y-637055D01*
X465453Y-636971D01*
X465267Y-637013D01*
X465107Y-637138D01*
X465000Y-637430D01*
X464947Y-637680D01*
Y-637930D01*
X465000Y-638180D01*
X465133Y-638430D01*
X465293Y-638596D01*
X465480Y-638638D01*
X465667Y-638555D01*
X465853Y-638305D01*
G01X467120Y-638638D02*
Y-636138D01*
G01Y-637388D02*
X467253Y-637138D01*
X467413Y-637013D01*
X467573Y-636971D01*
X467813Y-637055D01*
X467973Y-637221D01*
X468080Y-637513D01*
Y-637846D01*
X468027Y-638180D01*
X467920Y-638430D01*
X467733Y-638596D01*
X467573Y-638638D01*
X467413Y-638596D01*
X467253Y-638471D01*
X467120Y-638263D01*
G01X469800Y-638638D02*
X469640Y-638596D01*
X469480Y-638430D01*
X469373Y-638138D01*
X469320Y-637805D01*
X469373Y-637471D01*
X469480Y-637180D01*
X469640Y-637013D01*
X469800Y-636971D01*
X469960Y-637013D01*
X470120Y-637180D01*
X470227Y-637471D01*
X470253Y-637805D01*
X470227Y-638138D01*
X470120Y-638430D01*
X469960Y-638596D01*
X469800Y-638638D01*
G01X472480D02*
Y-636971D01*
G01Y-637263D02*
X472373Y-637096D01*
X472213Y-637013D01*
X472027Y-636971D01*
X471840Y-637055D01*
X471680Y-637221D01*
X471573Y-637471D01*
X471520Y-637805D01*
X471573Y-638138D01*
X471680Y-638388D01*
X471840Y-638555D01*
X472027Y-638638D01*
X472213Y-638596D01*
X472373Y-638471D01*
X472480Y-638305D01*
G01X473827Y-638638D02*
Y-636971D01*
G01Y-637305D02*
X473960Y-637138D01*
X474093Y-637013D01*
X474280Y-636971D01*
X474413Y-637013D01*
X474573Y-637138D01*
G01X476880Y-636138D02*
Y-638638D01*
G01Y-638263D02*
X476773Y-638471D01*
X476613Y-638596D01*
X476427Y-638638D01*
X476213Y-638555D01*
X476053Y-638346D01*
X475947Y-638096D01*
X475920Y-637805D01*
X475947Y-637513D01*
X476053Y-637263D01*
X476213Y-637055D01*
X476427Y-636971D01*
X476613Y-637013D01*
X476747Y-637096D01*
X476880Y-637263D01*
G01X480267Y-638638D02*
Y-636138D01*
X480933D01*
X481147Y-636263D01*
X481280Y-636430D01*
X481333Y-636763D01*
X481280Y-637096D01*
X481120Y-637305D01*
X480933Y-637430D01*
X480267D01*
G01X480933D02*
X481333Y-638638D01*
G01X482600Y-637513D02*
X483453D01*
X483373Y-637221D01*
X483240Y-637055D01*
X483053Y-636971D01*
X482867Y-637013D01*
X482707Y-637138D01*
X482600Y-637430D01*
X482547Y-637680D01*
Y-637930D01*
X482600Y-638180D01*
X482733Y-638430D01*
X482893Y-638596D01*
X483080Y-638638D01*
X483267Y-638555D01*
X483453Y-638305D01*
G01X484720Y-636971D02*
X485200Y-638638D01*
X485680Y-636971D01*
G01X487400Y-638721D02*
X487347Y-638680D01*
Y-638596D01*
X487400Y-638555D01*
X487453Y-638596D01*
Y-638680D01*
X487400Y-638721D01*
G01X489147Y-638346D02*
X489333Y-638555D01*
X489547Y-638638D01*
X489760Y-638555D01*
X489947Y-638305D01*
X490080Y-637930D01*
X490133Y-637555D01*
Y-637096D01*
X490080Y-636721D01*
X489947Y-636388D01*
X489787Y-636221D01*
X489600Y-636138D01*
X489387Y-636221D01*
X489227Y-636388D01*
X489120Y-636638D01*
X489067Y-636971D01*
X489120Y-637263D01*
X489253Y-637555D01*
X489413Y-637721D01*
X489600Y-637763D01*
X489813Y-637680D01*
X489973Y-637471D01*
X490133Y-637096D01*
G01X492013Y-637305D02*
X492120Y-637180D01*
X492200Y-636971D01*
X492253Y-636680D01*
X492200Y-636430D01*
X492093Y-636263D01*
X491907Y-636138D01*
X491187D01*
Y-638638D01*
X492067D01*
X492253Y-638471D01*
X492360Y-638221D01*
X492413Y-637930D01*
X492360Y-637638D01*
X492200Y-637388D01*
X492013Y-637305D01*
X491187D01*
G01X457900Y-612638D02*
Y-617638D01*
G01X456443Y-612638D02*
X459357D01*
G01X463000Y-617638D02*
X462620Y-617555D01*
X462240Y-617221D01*
X461987Y-616638D01*
X461860Y-615971D01*
X461987Y-615305D01*
X462240Y-614721D01*
X462620Y-614388D01*
X463000Y-614305D01*
X463380Y-614388D01*
X463760Y-614721D01*
X464013Y-615305D01*
X464077Y-615971D01*
X464013Y-616638D01*
X463760Y-617221D01*
X463380Y-617555D01*
X463000Y-617638D01*
G01X468100D02*
X467720Y-617555D01*
X467340Y-617221D01*
X467087Y-616638D01*
X466960Y-615971D01*
X467087Y-615305D01*
X467340Y-614721D01*
X467720Y-614388D01*
X468100Y-614305D01*
X468480Y-614388D01*
X468860Y-614721D01*
X469113Y-615305D01*
X469177Y-615971D01*
X469113Y-616638D01*
X468860Y-617221D01*
X468480Y-617555D01*
X468100Y-617638D01*
G01X473200D02*
Y-612638D01*
G01X478300Y-617805D02*
X478173Y-617721D01*
Y-617555D01*
X478300Y-617471D01*
X478427Y-617555D01*
Y-617721D01*
X478300Y-617805D01*
G01Y-615555D02*
X478173Y-615471D01*
Y-615305D01*
X478300Y-615221D01*
X478427Y-615305D01*
Y-615471D01*
X478300Y-615555D01*
G01X456633Y-592638D02*
Y-587638D01*
X458217D01*
X458723Y-587888D01*
X459040Y-588221D01*
X459167Y-588888D01*
X459040Y-589555D01*
X458660Y-589971D01*
X458217Y-590221D01*
X456633D01*
G01X458217D02*
X459167Y-592638D01*
G01X464267D02*
X461733D01*
Y-587638D01*
X464267D01*
G01X463253Y-590055D02*
X461733D01*
G01X466517Y-587638D02*
X468100Y-592638D01*
X469683Y-587638D01*
G01X473200Y-592805D02*
X473073Y-592721D01*
Y-592555D01*
X473200Y-592471D01*
X473327Y-592555D01*
Y-592721D01*
X473200Y-592805D01*
G01Y-590555D02*
X473073Y-590471D01*
Y-590305D01*
X473200Y-590221D01*
X473327Y-590305D01*
Y-590471D01*
X473200Y-590555D01*
G01X-476840Y-884638D02*
Y2768362D01*
X5911000D01*
Y-884638D01*
X-476840D01*
G01X8820Y-607488D02*
X10387D01*
Y-609378D01*
X9917Y-610008D01*
X9368Y-610428D01*
X8585Y-610638D01*
X7802Y-610428D01*
X7253Y-610008D01*
X6783Y-609378D01*
X6470Y-608643D01*
X6313Y-607803D01*
Y-607068D01*
X6470Y-606438D01*
X6783Y-605703D01*
X7253Y-605073D01*
X7723Y-604653D01*
X8350Y-604338D01*
X8898D01*
X9525Y-604548D01*
X9995Y-604968D01*
G01X12927Y-604338D02*
Y-608853D01*
X13240Y-609798D01*
X13867Y-610428D01*
X14650Y-610638D01*
X15433Y-610428D01*
X16060Y-609798D01*
X16373Y-608853D01*
Y-604338D01*
G01X20010D02*
X21890D01*
G01X20950D02*
Y-610638D01*
G01X20010D02*
X21890D01*
G01X25605Y-609798D02*
X26232Y-610323D01*
X26937Y-610638D01*
X27563D01*
X28190Y-610323D01*
X28660Y-609798D01*
X28895Y-609063D01*
X28738Y-608328D01*
X28347Y-607698D01*
X27642Y-607278D01*
X26702Y-607068D01*
X26153Y-606648D01*
X25918Y-605913D01*
X26075Y-605178D01*
X26467Y-604653D01*
X27015Y-604338D01*
X27563D01*
X28112Y-604548D01*
X28582Y-605073D01*
G01X31905Y-610638D02*
Y-604338D01*
G01X35195D02*
Y-610638D01*
G01Y-607488D02*
X31905D01*
G01X37892Y-610638D02*
X39850Y-604338D01*
X41808Y-610638D01*
G01X41103Y-608433D02*
X38597D01*
G01X44348Y-610638D02*
Y-604338D01*
X47952Y-610638D01*
Y-604338D01*
G01X57027Y-610638D02*
Y-604338D01*
X58593D01*
X59220Y-604653D01*
X59690Y-605073D01*
X60082Y-605703D01*
X60395Y-606438D01*
X60473Y-607488D01*
X60395Y-608538D01*
X60082Y-609273D01*
X59690Y-609903D01*
X59220Y-610323D01*
X58593Y-610638D01*
X57027D01*
G01X64110Y-604338D02*
X65990D01*
G01X65050D02*
Y-610638D01*
G01X64110D02*
X65990D01*
G01X69705Y-609798D02*
X70332Y-610323D01*
X71037Y-610638D01*
X71663D01*
X72290Y-610323D01*
X72760Y-609798D01*
X72995Y-609063D01*
X72838Y-608328D01*
X72447Y-607698D01*
X71742Y-607278D01*
X70802Y-607068D01*
X70253Y-606648D01*
X70018Y-605913D01*
X70175Y-605178D01*
X70567Y-604653D01*
X71115Y-604338D01*
X71663D01*
X72212Y-604548D01*
X72682Y-605073D01*
G01X77650Y-604338D02*
Y-610638D01*
G01X75848Y-604338D02*
X79452D01*
G01X83950Y-610848D02*
X83793Y-610743D01*
Y-610533D01*
X83950Y-610428D01*
X84107Y-610533D01*
Y-610743D01*
X83950Y-610848D01*
G01X90093Y-611793D02*
X90407Y-610428D01*
G01X96550Y-604338D02*
Y-610638D01*
G01X94748Y-604338D02*
X98352D01*
G01X100892Y-610638D02*
X102850Y-604338D01*
X104808Y-610638D01*
G01X104103Y-608433D02*
X101597D01*
G01X109150Y-610638D02*
X108523Y-610533D01*
X107975Y-610113D01*
X107505Y-609483D01*
X107192Y-608748D01*
X107035Y-607908D01*
Y-607068D01*
X107192Y-606228D01*
X107505Y-605493D01*
X107975Y-604863D01*
X108523Y-604443D01*
X109150Y-604338D01*
X109777Y-604443D01*
X110325Y-604863D01*
X110795Y-605493D01*
X111108Y-606228D01*
X111265Y-607068D01*
Y-607908D01*
X111108Y-608748D01*
X110795Y-609483D01*
X110325Y-610113D01*
X109777Y-610533D01*
X109150Y-610638D01*
G01X115450D02*
Y-607803D01*
X113883Y-604338D01*
G01X117017D02*
X115450Y-607803D01*
G01X120027Y-604338D02*
Y-608853D01*
X120340Y-609798D01*
X120967Y-610428D01*
X121750Y-610638D01*
X122533Y-610428D01*
X123160Y-609798D01*
X123473Y-608853D01*
Y-604338D01*
G01X126092Y-610638D02*
X128050Y-604338D01*
X130008Y-610638D01*
G01X129303Y-608433D02*
X126797D01*
G01X132548Y-610638D02*
Y-604338D01*
X136152Y-610638D01*
Y-604338D01*
G01X10073Y-614863D02*
X9603Y-614548D01*
X9055Y-614338D01*
X8428D01*
X7723Y-614653D01*
X7175Y-615178D01*
X6783Y-615808D01*
X6470Y-616858D01*
X6392Y-617803D01*
X6548Y-618748D01*
X6783Y-619378D01*
X7253Y-620008D01*
X7802Y-620428D01*
X8350Y-620638D01*
X8898D01*
X9447Y-620428D01*
X9917Y-620113D01*
X10308Y-619693D01*
G01X13710Y-614338D02*
X15590D01*
G01X14650D02*
Y-620638D01*
G01X13710D02*
X15590D01*
G01X20950Y-614338D02*
Y-620638D01*
G01X19148Y-614338D02*
X22752D01*
G01X27250Y-620638D02*
Y-617803D01*
X25683Y-614338D01*
G01X28817D02*
X27250Y-617803D01*
G01X38127Y-619378D02*
X38597Y-620113D01*
X39223Y-620533D01*
X39928Y-620638D01*
X40555Y-620533D01*
X41182Y-620008D01*
X41573Y-619378D01*
X41652Y-618748D01*
X41495Y-618013D01*
X40947Y-617488D01*
X40398Y-617278D01*
X39693D01*
G01X40398D02*
X40868Y-616963D01*
X41260Y-616438D01*
X41417Y-615808D01*
X41260Y-615178D01*
X40868Y-614653D01*
X40163Y-614338D01*
X39458Y-614443D01*
X38753Y-614863D01*
G01X44427Y-619378D02*
X44897Y-620113D01*
X45523Y-620533D01*
X46228Y-620638D01*
X46855Y-620533D01*
X47482Y-620008D01*
X47873Y-619378D01*
X47952Y-618748D01*
X47795Y-618013D01*
X47247Y-617488D01*
X46698Y-617278D01*
X45993D01*
G01X46698D02*
X47168Y-616963D01*
X47560Y-616438D01*
X47717Y-615808D01*
X47560Y-615178D01*
X47168Y-614653D01*
X46463Y-614338D01*
X45758Y-614443D01*
X45053Y-614863D01*
G01X50727Y-619378D02*
X51197Y-620113D01*
X51823Y-620533D01*
X52528Y-620638D01*
X53155Y-620533D01*
X53782Y-620008D01*
X54173Y-619378D01*
X54252Y-618748D01*
X54095Y-618013D01*
X53547Y-617488D01*
X52998Y-617278D01*
X52293D01*
G01X52998D02*
X53468Y-616963D01*
X53860Y-616438D01*
X54017Y-615808D01*
X53860Y-615178D01*
X53468Y-614653D01*
X52763Y-614338D01*
X52058Y-614443D01*
X51353Y-614863D01*
G01X58593Y-620638D02*
X58750Y-619273D01*
X58985Y-618118D01*
X59298Y-617068D01*
X59690Y-615913D01*
X60317Y-614338D01*
X57183D01*
G01X64893Y-620638D02*
X65050Y-619273D01*
X65285Y-618118D01*
X65598Y-617068D01*
X65990Y-615913D01*
X66617Y-614338D01*
X63483D01*
G01X71193Y-621793D02*
X71507Y-620428D01*
G01X77650Y-614338D02*
Y-620638D01*
G01X75848Y-614338D02*
X79452D01*
G01X81992Y-620638D02*
X83950Y-614338D01*
X85908Y-620638D01*
G01X85203Y-618433D02*
X82697D01*
G01X89310Y-614338D02*
X91190D01*
G01X90250D02*
Y-620638D01*
G01X89310D02*
X91190D01*
G01X94200Y-614338D02*
X95297Y-620638D01*
X96550Y-614338D01*
X97803Y-620638D01*
X98900Y-614338D01*
G01X100892Y-620638D02*
X102850Y-614338D01*
X104808Y-620638D01*
G01X104103Y-618433D02*
X101597D01*
G01X107348Y-620638D02*
Y-614338D01*
X110952Y-620638D01*
Y-614338D01*
G01X121358Y-622738D02*
X120575Y-621688D01*
X120183Y-620638D01*
Y-616438D01*
X120575Y-615388D01*
X121358Y-614338D01*
G01X132783Y-620638D02*
Y-614338D01*
X134742D01*
X135368Y-614653D01*
X135760Y-615073D01*
X135917Y-615913D01*
X135760Y-616753D01*
X135290Y-617278D01*
X134742Y-617593D01*
X132783D01*
G01X134742D02*
X135917Y-620638D01*
G01X140650Y-620848D02*
X140493Y-620743D01*
Y-620533D01*
X140650Y-620428D01*
X140807Y-620533D01*
Y-620743D01*
X140650Y-620848D01*
G01X146950Y-620638D02*
X146323Y-620533D01*
X145775Y-620113D01*
X145305Y-619483D01*
X144992Y-618748D01*
X144835Y-617908D01*
Y-617068D01*
X144992Y-616228D01*
X145305Y-615493D01*
X145775Y-614863D01*
X146323Y-614443D01*
X146950Y-614338D01*
X147577Y-614443D01*
X148125Y-614863D01*
X148595Y-615493D01*
X148908Y-616228D01*
X149065Y-617068D01*
Y-617908D01*
X148908Y-618748D01*
X148595Y-619483D01*
X148125Y-620113D01*
X147577Y-620533D01*
X146950Y-620638D01*
G01X153250Y-620848D02*
X153093Y-620743D01*
Y-620533D01*
X153250Y-620428D01*
X153407Y-620533D01*
Y-620743D01*
X153250Y-620848D01*
G01X161273Y-614863D02*
X160803Y-614548D01*
X160255Y-614338D01*
X159628D01*
X158923Y-614653D01*
X158375Y-615178D01*
X157983Y-615808D01*
X157670Y-616858D01*
X157592Y-617803D01*
X157748Y-618748D01*
X157983Y-619378D01*
X158453Y-620008D01*
X159002Y-620428D01*
X159550Y-620638D01*
X160098D01*
X160647Y-620428D01*
X161117Y-620113D01*
X161508Y-619693D01*
G01X165850Y-620848D02*
X165693Y-620743D01*
Y-620533D01*
X165850Y-620428D01*
X166007Y-620533D01*
Y-620743D01*
X165850Y-620848D01*
G01X172542Y-622738D02*
X173325Y-621688D01*
X173717Y-620638D01*
Y-616438D01*
X173325Y-615388D01*
X172542Y-614338D01*
G01X6548Y-600638D02*
Y-594338D01*
X10152Y-600638D01*
Y-594338D01*
G01X14650Y-600638D02*
X14023Y-600533D01*
X13475Y-600113D01*
X13005Y-599483D01*
X12692Y-598748D01*
X12535Y-597908D01*
Y-597068D01*
X12692Y-596228D01*
X13005Y-595493D01*
X13475Y-594863D01*
X14023Y-594443D01*
X14650Y-594338D01*
X15277Y-594443D01*
X15825Y-594863D01*
X16295Y-595493D01*
X16608Y-596228D01*
X16765Y-597068D01*
Y-597908D01*
X16608Y-598748D01*
X16295Y-599483D01*
X15825Y-600113D01*
X15277Y-600533D01*
X14650Y-600638D01*
G01X20950Y-600848D02*
X20793Y-600743D01*
Y-600533D01*
X20950Y-600428D01*
X21107Y-600533D01*
Y-600743D01*
X20950Y-600848D01*
G01X25762Y-595388D02*
X26232Y-594758D01*
X26780Y-594443D01*
X27407Y-594338D01*
X28190Y-594548D01*
X28738Y-595073D01*
X28895Y-595703D01*
X28817Y-596333D01*
X28503Y-596858D01*
X26937Y-597908D01*
X26232Y-598643D01*
X25762Y-599693D01*
X25605Y-600638D01*
X28895D01*
G01X33550D02*
Y-594338D01*
X32610Y-595598D01*
G01Y-600638D02*
X34490D01*
G01X39850D02*
Y-594338D01*
X38910Y-595598D01*
G01Y-600638D02*
X40790D01*
G01X45993Y-601793D02*
X46307Y-600428D01*
G01X50100Y-594338D02*
X51197Y-600638D01*
X52450Y-594338D01*
X53703Y-600638D01*
X54800Y-594338D01*
G01X60317Y-600638D02*
X57183D01*
Y-594338D01*
X60317D01*
G01X59063Y-597383D02*
X57183D01*
G01X63248Y-600638D02*
Y-594338D01*
X66852Y-600638D01*
Y-594338D01*
G01X69705Y-600638D02*
Y-594338D01*
G01X72995D02*
Y-600638D01*
G01Y-597488D02*
X69705D01*
G01X75927Y-594338D02*
Y-598853D01*
X76240Y-599798D01*
X76867Y-600428D01*
X77650Y-600638D01*
X78433Y-600428D01*
X79060Y-599798D01*
X79373Y-598853D01*
Y-594338D01*
G01X81992Y-600638D02*
X83950Y-594338D01*
X85908Y-600638D01*
G01X85203Y-598433D02*
X82697D01*
G01X95062Y-595388D02*
X95532Y-594758D01*
X96080Y-594443D01*
X96707Y-594338D01*
X97490Y-594548D01*
X98038Y-595073D01*
X98195Y-595703D01*
X98117Y-596333D01*
X97803Y-596858D01*
X96237Y-597908D01*
X95532Y-598643D01*
X95062Y-599693D01*
X94905Y-600638D01*
X98195D01*
G01X101048D02*
Y-594338D01*
X104652Y-600638D01*
Y-594338D01*
G01X107427Y-600638D02*
Y-594338D01*
X108993D01*
X109620Y-594653D01*
X110090Y-595073D01*
X110482Y-595703D01*
X110795Y-596438D01*
X110873Y-597488D01*
X110795Y-598538D01*
X110482Y-599273D01*
X110090Y-599903D01*
X109620Y-600323D01*
X108993Y-600638D01*
X107427D01*
G01X120183D02*
Y-594338D01*
X122142D01*
X122768Y-594653D01*
X123160Y-595073D01*
X123317Y-595913D01*
X123160Y-596753D01*
X122690Y-597278D01*
X122142Y-597593D01*
X120183D01*
G01X122142D02*
X123317Y-600638D01*
G01X126327D02*
Y-594338D01*
X127893D01*
X128520Y-594653D01*
X128990Y-595073D01*
X129382Y-595703D01*
X129695Y-596438D01*
X129773Y-597488D01*
X129695Y-598538D01*
X129382Y-599273D01*
X128990Y-599903D01*
X128520Y-600323D01*
X127893Y-600638D01*
X126327D01*
G01X134350Y-600848D02*
X134193Y-600743D01*
Y-600533D01*
X134350Y-600428D01*
X134507Y-600533D01*
Y-600743D01*
X134350Y-600848D01*
G01X30650Y-589938D02*
X28130Y-589521D01*
X25925Y-587855D01*
X24035Y-585355D01*
X22775Y-582438D01*
X22145Y-579105D01*
Y-575771D01*
X22775Y-572438D01*
X24035Y-569521D01*
X25925Y-567022D01*
X28130Y-565355D01*
X30650Y-564938D01*
X33170Y-565355D01*
X35375Y-567022D01*
X37265Y-569521D01*
X38525Y-572438D01*
X39155Y-575771D01*
Y-579105D01*
X38525Y-582438D01*
X37265Y-585355D01*
X35375Y-587855D01*
X33170Y-589521D01*
X30650Y-589938D01*
G01X33170Y-583271D02*
X36950Y-589938D01*
G01X50495Y-573272D02*
Y-584938D01*
X51755Y-587855D01*
X53645Y-589521D01*
X55850Y-589938D01*
X58055Y-589521D01*
X59945Y-587855D01*
X61205Y-584938D01*
G01Y-589938D02*
Y-573272D01*
G01X86720Y-589938D02*
Y-573272D01*
G01Y-576188D02*
X85460Y-574522D01*
X83570Y-573688D01*
X81365Y-573272D01*
X79160Y-574105D01*
X77270Y-575771D01*
X76010Y-578272D01*
X75380Y-581605D01*
X76010Y-584938D01*
X77270Y-587439D01*
X79160Y-589105D01*
X81365Y-589938D01*
X83570Y-589521D01*
X85460Y-588272D01*
X86720Y-586605D01*
G01X100895Y-589938D02*
Y-573272D01*
G01Y-577438D02*
X102155Y-575355D01*
X104045Y-573688D01*
X106565Y-573272D01*
X108770Y-573688D01*
X110660Y-575355D01*
X111605Y-578272D01*
Y-589938D01*
G01X131450Y-564938D02*
Y-589938D01*
G01X127040Y-573272D02*
X135860D01*
G01X162320Y-589938D02*
Y-573272D01*
G01Y-576188D02*
X161060Y-574522D01*
X159170Y-573688D01*
X156965Y-573272D01*
X154760Y-574105D01*
X152870Y-575771D01*
X151610Y-578272D01*
X150980Y-581605D01*
X151610Y-584938D01*
X152870Y-587439D01*
X154760Y-589105D01*
X156965Y-589938D01*
X159170Y-589521D01*
X161060Y-588272D01*
X162320Y-586605D01*
G01X202000Y-569638D02*
Y-577638D01*
X206000D01*
G01X213800D02*
Y-572305D01*
G01Y-573238D02*
X213400Y-572705D01*
X212800Y-572438D01*
X212100Y-572305D01*
X211400Y-572571D01*
X210800Y-573105D01*
X210400Y-573905D01*
X210200Y-574971D01*
X210400Y-576038D01*
X210800Y-576838D01*
X211400Y-577371D01*
X212100Y-577638D01*
X212800Y-577505D01*
X213400Y-577105D01*
X213800Y-576572D01*
G01X217900Y-580038D02*
X218500Y-580305D01*
X219300Y-580038D01*
X219800Y-579505D01*
X220200Y-578838D01*
X220800Y-576705D01*
X222100Y-572305D01*
G01X218900D02*
X220800Y-576705D01*
G01X226500Y-574038D02*
X229700D01*
X229400Y-573105D01*
X228900Y-572571D01*
X228200Y-572305D01*
X227500Y-572438D01*
X226900Y-572838D01*
X226500Y-573771D01*
X226300Y-574572D01*
Y-575371D01*
X226500Y-576171D01*
X227000Y-576971D01*
X227600Y-577505D01*
X228300Y-577638D01*
X229000Y-577371D01*
X229700Y-576572D01*
G01X234600Y-577638D02*
Y-572305D01*
G01Y-573371D02*
X235100Y-572838D01*
X235600Y-572438D01*
X236300Y-572305D01*
X236800Y-572438D01*
X237400Y-572838D01*
G01X226000Y-626038D02*
X226500Y-626838D01*
X227100Y-627371D01*
X227800Y-627638D01*
X228600Y-627371D01*
X229200Y-626838D01*
X229800Y-626038D01*
X230000Y-624971D01*
Y-619638D01*
G01X237800Y-627638D02*
Y-622305D01*
G01Y-623238D02*
X237400Y-622705D01*
X236800Y-622438D01*
X236100Y-622305D01*
X235400Y-622571D01*
X234800Y-623105D01*
X234400Y-623905D01*
X234200Y-624971D01*
X234400Y-626038D01*
X234800Y-626838D01*
X235400Y-627371D01*
X236100Y-627638D01*
X236800Y-627505D01*
X237400Y-627105D01*
X237800Y-626572D01*
G01X245600Y-622971D02*
X244900Y-622438D01*
X244300Y-622305D01*
X243500Y-622571D01*
X242900Y-623105D01*
X242500Y-624038D01*
X242400Y-624971D01*
X242500Y-625905D01*
X242900Y-626705D01*
X243500Y-627371D01*
X244300Y-627638D01*
X245000Y-627371D01*
X245600Y-626838D01*
G01X250300Y-627638D02*
Y-619638D01*
G01X253500Y-622305D02*
X250300Y-625371D01*
G01X251600Y-624171D02*
X253700Y-627638D01*
G01X229800Y-598038D02*
X231800D01*
Y-600438D01*
X231200Y-601238D01*
X230500Y-601771D01*
X229500Y-602038D01*
X228500Y-601771D01*
X227800Y-601238D01*
X227200Y-600438D01*
X226800Y-599505D01*
X226600Y-598438D01*
Y-597505D01*
X226800Y-596705D01*
X227200Y-595771D01*
X227800Y-594971D01*
X228400Y-594438D01*
X229200Y-594038D01*
X229900D01*
X230700Y-594305D01*
X231300Y-594838D01*
G01X234900Y-602038D02*
Y-594038D01*
X239500Y-602038D01*
Y-594038D01*
G01X243000Y-602038D02*
Y-594038D01*
X245000D01*
X245800Y-594438D01*
X246400Y-594971D01*
X246900Y-595771D01*
X247300Y-596705D01*
X247400Y-598038D01*
X247300Y-599371D01*
X246900Y-600305D01*
X246400Y-601105D01*
X245800Y-601638D01*
X245000Y-602038D01*
X243000D01*
G01X251000Y-600838D02*
X251600Y-601505D01*
X252300Y-601905D01*
X253200Y-602038D01*
X254100Y-601771D01*
X254800Y-601238D01*
X255300Y-600305D01*
X255400Y-599238D01*
X255200Y-598171D01*
X254700Y-597505D01*
X254000Y-596971D01*
X253300Y-596838D01*
X252600Y-596971D01*
X251700Y-597505D01*
X252000Y-594038D01*
X254700D01*
G01X264000Y-578338D02*
Y-570338D01*
X262800Y-571938D01*
G01Y-578338D02*
X265200D01*
G01X269800Y-576738D02*
X270400Y-577671D01*
X271200Y-578205D01*
X272100Y-578338D01*
X272900Y-578205D01*
X273700Y-577538D01*
X274200Y-576738D01*
X274300Y-575938D01*
X274100Y-575005D01*
X273400Y-574338D01*
X272700Y-574071D01*
X271800D01*
G01X272700D02*
X273300Y-573671D01*
X273800Y-573005D01*
X274000Y-572205D01*
X273800Y-571405D01*
X273300Y-570738D01*
X272400Y-570338D01*
X271500Y-570471D01*
X270600Y-571005D01*
G01X328600Y-620971D02*
X329200Y-620171D01*
X329900Y-619771D01*
X330700Y-619638D01*
X331700Y-619905D01*
X332400Y-620571D01*
X332600Y-621371D01*
X332500Y-622172D01*
X332100Y-622838D01*
X330100Y-624171D01*
X329200Y-625105D01*
X328600Y-626438D01*
X328400Y-627638D01*
X332600D01*
G01X338500Y-619638D02*
X337700Y-619905D01*
X337100Y-620571D01*
X336700Y-621371D01*
X336400Y-622438D01*
X336300Y-623638D01*
X336400Y-624838D01*
X336700Y-625905D01*
X337100Y-626705D01*
X337700Y-627371D01*
X338500Y-627638D01*
X339300Y-627371D01*
X339900Y-626705D01*
X340300Y-625905D01*
X340600Y-624838D01*
X340700Y-623638D01*
X340600Y-622438D01*
X340300Y-621371D01*
X339900Y-620571D01*
X339300Y-619905D01*
X338500Y-619638D01*
G01X344600Y-620971D02*
X345200Y-620171D01*
X345900Y-619771D01*
X346700Y-619638D01*
X347700Y-619905D01*
X348400Y-620571D01*
X348600Y-621371D01*
X348500Y-622172D01*
X348100Y-622838D01*
X346100Y-624171D01*
X345200Y-625105D01*
X344600Y-626438D01*
X344400Y-627638D01*
X348600D01*
G01X352300Y-626038D02*
X352900Y-626971D01*
X353700Y-627505D01*
X354600Y-627638D01*
X355400Y-627505D01*
X356200Y-626838D01*
X356700Y-626038D01*
X356800Y-625238D01*
X356600Y-624305D01*
X355900Y-623638D01*
X355200Y-623371D01*
X354300D01*
G01X355200D02*
X355800Y-622971D01*
X356300Y-622305D01*
X356500Y-621505D01*
X356300Y-620705D01*
X355800Y-620038D01*
X354900Y-619638D01*
X354000Y-619771D01*
X353100Y-620305D01*
G01X360700Y-627905D02*
X364300Y-619638D01*
G01X370500D02*
X369700Y-619905D01*
X369100Y-620571D01*
X368700Y-621371D01*
X368400Y-622438D01*
X368300Y-623638D01*
X368400Y-624838D01*
X368700Y-625905D01*
X369100Y-626705D01*
X369700Y-627371D01*
X370500Y-627638D01*
X371300Y-627371D01*
X371900Y-626705D01*
X372300Y-625905D01*
X372600Y-624838D01*
X372700Y-623638D01*
X372600Y-622438D01*
X372300Y-621371D01*
X371900Y-620571D01*
X371300Y-619905D01*
X370500Y-619638D01*
G01X379700Y-627638D02*
Y-619638D01*
X376000Y-625371D01*
X381000D01*
G01X384700Y-627905D02*
X388300Y-619638D01*
G01X394500Y-627638D02*
Y-619638D01*
X393300Y-621238D01*
G01Y-627638D02*
X395700D01*
G01X402300D02*
X402500Y-625905D01*
X402800Y-624438D01*
X403200Y-623105D01*
X403700Y-621638D01*
X404500Y-619638D01*
X400500D01*
G01X328300Y-602638D02*
Y-594638D01*
X330300D01*
X331100Y-595038D01*
X331700Y-595571D01*
X332200Y-596371D01*
X332600Y-597305D01*
X332700Y-598638D01*
X332600Y-599971D01*
X332200Y-600905D01*
X331700Y-601705D01*
X331100Y-602238D01*
X330300Y-602638D01*
X328300D01*
G01X336000D02*
X338500Y-594638D01*
X341000Y-602638D01*
G01X340100Y-599838D02*
X336900D01*
G01X344600Y-602638D02*
Y-594638D01*
X348400D01*
G01X347000Y-598505D02*
X344600D01*
G01X354500Y-594638D02*
X353700Y-594905D01*
X353100Y-595571D01*
X352700Y-596371D01*
X352400Y-597438D01*
X352300Y-598638D01*
X352400Y-599838D01*
X352700Y-600905D01*
X353100Y-601705D01*
X353700Y-602371D01*
X354500Y-602638D01*
X355300Y-602371D01*
X355900Y-601705D01*
X356300Y-600905D01*
X356600Y-599838D01*
X356700Y-598638D01*
X356600Y-597438D01*
X356300Y-596371D01*
X355900Y-595571D01*
X355300Y-594905D01*
X354500Y-594638D01*
G01X362500D02*
Y-602638D01*
G01X360200Y-594638D02*
X364800D01*
G01X367900Y-602638D02*
Y-594638D01*
X370500Y-601305D01*
X373100Y-594638D01*
Y-602638D01*
G01X379300Y-598371D02*
X379700Y-597971D01*
X380000Y-597305D01*
X380200Y-596371D01*
X380000Y-595571D01*
X379600Y-595038D01*
X378900Y-594638D01*
X376200D01*
Y-602638D01*
X379500D01*
X380200Y-602105D01*
X380600Y-601305D01*
X380800Y-600371D01*
X380600Y-599438D01*
X380000Y-598638D01*
X379300Y-598371D01*
X376200D01*
G01X384300Y-601038D02*
X384900Y-601971D01*
X385700Y-602505D01*
X386600Y-602638D01*
X387400Y-602505D01*
X388200Y-601838D01*
X388700Y-601038D01*
X388800Y-600238D01*
X388600Y-599305D01*
X387900Y-598638D01*
X387200Y-598371D01*
X386300D01*
G01X387200D02*
X387800Y-597971D01*
X388300Y-597305D01*
X388500Y-596505D01*
X388300Y-595705D01*
X387800Y-595038D01*
X386900Y-594638D01*
X386000Y-594771D01*
X385100Y-595305D01*
G01X393300Y-594638D02*
X395700D01*
G01X394500D02*
Y-602638D01*
G01X393300D02*
X395700D01*
G01X404700Y-595305D02*
X404100Y-594905D01*
X403400Y-594638D01*
X402600D01*
X401700Y-595038D01*
X401000Y-595705D01*
X400500Y-596505D01*
X400100Y-597838D01*
X400000Y-599038D01*
X400200Y-600238D01*
X400500Y-601038D01*
X401100Y-601838D01*
X401800Y-602371D01*
X402500Y-602638D01*
X403200D01*
X403900Y-602371D01*
X404500Y-601971D01*
X405000Y-601438D01*
G01X410500Y-594638D02*
X409700Y-594905D01*
X409100Y-595571D01*
X408700Y-596371D01*
X408400Y-597438D01*
X408300Y-598638D01*
X408400Y-599838D01*
X408700Y-600905D01*
X409100Y-601705D01*
X409700Y-602371D01*
X410500Y-602638D01*
X411300Y-602371D01*
X411900Y-601705D01*
X412300Y-600905D01*
X412600Y-599838D01*
X412700Y-598638D01*
X412600Y-597438D01*
X412300Y-596371D01*
X411900Y-595571D01*
X411300Y-594905D01*
X410500Y-594638D01*
G01X346100Y-577638D02*
Y-569638D01*
X349900D01*
G01X348500Y-573505D02*
X346100D01*
G01X356000Y-569638D02*
X355200Y-569905D01*
X354600Y-570571D01*
X354200Y-571371D01*
X353900Y-572438D01*
X353800Y-573638D01*
X353900Y-574838D01*
X354200Y-575905D01*
X354600Y-576705D01*
X355200Y-577371D01*
X356000Y-577638D01*
X356800Y-577371D01*
X357400Y-576705D01*
X357800Y-575905D01*
X358100Y-574838D01*
X358200Y-573638D01*
X358100Y-572438D01*
X357800Y-571371D01*
X357400Y-570571D01*
X356800Y-569905D01*
X356000Y-569638D01*
G01X364000D02*
Y-577638D01*
G01X361700Y-569638D02*
X366300D01*
G01X372600Y-573638D02*
X374600D01*
Y-576038D01*
X374000Y-576838D01*
X373300Y-577371D01*
X372300Y-577638D01*
X371300Y-577371D01*
X370600Y-576838D01*
X370000Y-576038D01*
X369600Y-575105D01*
X369400Y-574038D01*
Y-573105D01*
X369600Y-572305D01*
X370000Y-571371D01*
X370600Y-570571D01*
X371200Y-570038D01*
X372000Y-569638D01*
X372700D01*
X373500Y-569905D01*
X374100Y-570438D01*
G01X377000Y-580305D02*
X383000D01*
G01X385400Y-577638D02*
Y-569638D01*
X388000Y-576305D01*
X390600Y-569638D01*
Y-577638D01*
G01X396800Y-573371D02*
X397200Y-572971D01*
X397500Y-572305D01*
X397700Y-571371D01*
X397500Y-570571D01*
X397100Y-570038D01*
X396400Y-569638D01*
X393700D01*
Y-577638D01*
X397000D01*
X397700Y-577105D01*
X398100Y-576305D01*
X398300Y-575371D01*
X398100Y-574438D01*
X397500Y-573638D01*
X396800Y-573371D01*
X393700D01*
G01X417000Y-630638D02*
Y-622638D01*
X415800Y-624238D01*
G01Y-630638D02*
X418200D01*
G01X423100Y-627305D02*
X423800Y-626371D01*
X424400Y-625838D01*
X425200Y-625571D01*
X425900Y-625838D01*
X426400Y-626371D01*
X426800Y-627171D01*
X426900Y-628105D01*
X426800Y-628905D01*
X426400Y-629705D01*
X425800Y-630371D01*
X425100Y-630638D01*
X424300Y-630371D01*
X423600Y-629572D01*
X423200Y-628371D01*
X423100Y-627038D01*
X423300Y-625305D01*
X423600Y-624371D01*
X424100Y-623438D01*
X424800Y-622771D01*
X425500Y-622638D01*
X426200Y-622905D01*
X426700Y-623571D01*
G01X433000Y-630905D02*
X432800Y-630771D01*
Y-630505D01*
X433000Y-630371D01*
X433200Y-630505D01*
Y-630771D01*
X433000Y-630905D01*
G01X439100Y-627305D02*
X439800Y-626371D01*
X440400Y-625838D01*
X441200Y-625571D01*
X441900Y-625838D01*
X442400Y-626371D01*
X442800Y-627171D01*
X442900Y-628105D01*
X442800Y-628905D01*
X442400Y-629705D01*
X441800Y-630371D01*
X441100Y-630638D01*
X440300Y-630371D01*
X439600Y-629572D01*
X439200Y-628371D01*
X439100Y-627038D01*
X439300Y-625305D01*
X439600Y-624371D01*
X440100Y-623438D01*
X440800Y-622771D01*
X441500Y-622638D01*
X442200Y-622905D01*
X442700Y-623571D01*
G01X462000Y-630638D02*
Y-622638D01*
X460800Y-624238D01*
G01Y-630638D02*
X463200D01*
G01X469800D02*
X470000Y-628905D01*
X470300Y-627438D01*
X470700Y-626105D01*
X471200Y-624638D01*
X472000Y-622638D01*
X468000D01*
G01X478000Y-630905D02*
X477800Y-630771D01*
Y-630505D01*
X478000Y-630371D01*
X478200Y-630505D01*
Y-630771D01*
X478000Y-630905D01*
G01X484100Y-623971D02*
X484700Y-623171D01*
X485400Y-622771D01*
X486200Y-622638D01*
X487200Y-622905D01*
X487900Y-623571D01*
X488100Y-624371D01*
X488000Y-625172D01*
X487600Y-625838D01*
X485600Y-627171D01*
X484700Y-628105D01*
X484100Y-629438D01*
X483900Y-630638D01*
X488100D01*
G01X486200Y-598305D02*
X485600Y-597905D01*
X484900Y-597638D01*
X484100D01*
X483200Y-598038D01*
X482500Y-598705D01*
X482000Y-599505D01*
X481600Y-600838D01*
X481500Y-602038D01*
X481700Y-603238D01*
X482000Y-604038D01*
X482600Y-604838D01*
X483300Y-605371D01*
X484000Y-605638D01*
X484700D01*
X485400Y-605371D01*
X486000Y-604971D01*
X486500Y-604438D01*
M02*
